G04 ================== begin FILE IDENTIFICATION RECORD ==================*
G04 Layout Name:  13948-1b.brd*
G04 Film Name:    L8*
G04 File Format:  Gerber RS274X*
G04 File Origin:  Cadence Allegro 16.5-S045*
G04 Origin Date:  Thu Nov 13 15:46:20 2014*
G04 *
G04 Layer:  VIA CLASS/BOTTOM*
G04 Layer:  PIN/BOTTOM*
G04 Layer:  ETCH/BOTTOM*
G04 Layer:  DRAWING FORMAT/LAYER_PCB_STORY*
G04 Layer:  DRAWING FORMAT/LAYER_L8*
G04 *
G04 Offset:    (0.00 0.00)*
G04 Mirror:    No*
G04 Mode:      Positive*
G04 Rotation:  0*
G04 FullContactRelief:  No*
G04 UndefLineWidth:     6.00*
G04 ================== end FILE IDENTIFICATION RECORD ====================*
%FSLAX35Y35*MOIN*%
%IR0*IPPOS*OFA0.00000B0.00000*MIA0B0*SFA1.00000B1.00000*%
%AMMACRO20*
4,1,40,.011,.007,
.011,-.007,
.010939,-.007695,
.010759,-.008368,
.010464,-.009,
.010064,-.009571,
.009571,-.010064,
.009,-.010464,
.008368,-.010759,
.007695,-.010939,
.007,-.011,
-.007,-.011,
-.007695,-.010939,
-.008368,-.010759,
-.009,-.010464,
-.009571,-.010064,
-.010064,-.009571,
-.010464,-.009,
-.010759,-.008368,
-.010939,-.007695,
-.011,-.007,
-.011,.007,
-.010939,.007695,
-.010759,.008368,
-.010464,.009,
-.010064,.009571,
-.009571,.010064,
-.009,.010464,
-.008368,.010759,
-.007695,.010939,
-.007,.011,
.007,.011,
.007695,.010939,
.008368,.010759,
.009,.010464,
.009571,.010064,
.010064,.009571,
.010464,.009,
.010759,.008368,
.010939,.007695,
.011,.007,
0.0*
%
%ADD20MACRO20*%
%AMMACRO72*
4,1,22,.011,-.0145,
.011,.0105,
.010939,.011195,
.010759,.011868,
.010464,.0125,
.010064,.013071,
.009571,.013564,
.009,.013964,
.008368,.014259,
.007695,.014439,
.007,.0145,
-.007,.0145,
-.007695,.014439,
-.008368,.014259,
-.009,.013964,
-.009571,.013564,
-.010064,.013071,
-.010464,.0125,
-.010759,.011868,
-.010939,.011195,
-.011,.0105,
-.011,-.0145,
.011,-.0145,
0.0*
%
%ADD72MACRO72*%
%AMMACRO66*
4,1,40,.013,-.017,
-.013,-.017,
-.013695,-.016939,
-.014368,-.016759,
-.015,-.016464,
-.015571,-.016064,
-.016064,-.015571,
-.016464,-.015,
-.016759,-.014368,
-.016939,-.013695,
-.017,-.013,
-.017,.013,
-.016939,.013695,
-.016759,.014368,
-.016464,.015,
-.016064,.015571,
-.015571,.016064,
-.015,.016464,
-.014368,.016759,
-.013695,.016939,
-.013,.017,
.013,.017,
.013695,.016939,
.014368,.016759,
.015,.016464,
.015571,.016064,
.016064,.015571,
.016464,.015,
.016759,.014368,
.016939,.013695,
.017,.013,
.017,-.013,
.016939,-.013695,
.016759,-.014368,
.016464,-.015,
.016064,-.015571,
.015571,-.016064,
.015,-.016464,
.014368,-.016759,
.013695,-.016939,
.013,-.017,
0.0*
%
%ADD66MACRO66*%
%AMMACRO35*
4,1,40,-.017,-.013,
-.017,.013,
-.016939,.013695,
-.016759,.014368,
-.016464,.015,
-.016064,.015571,
-.015571,.016064,
-.015,.016464,
-.014368,.016759,
-.013695,.016939,
-.013,.017,
.013,.017,
.013695,.016939,
.014368,.016759,
.015,.016464,
.015571,.016064,
.016064,.015571,
.016464,.015,
.016759,.014368,
.016939,.013695,
.017,.013,
.017,-.013,
.016939,-.013695,
.016759,-.014368,
.016464,-.015,
.016064,-.015571,
.015571,-.016064,
.015,-.016464,
.014368,-.016759,
.013695,-.016939,
.013,-.017,
-.013,-.017,
-.013695,-.016939,
-.014368,-.016759,
-.015,-.016464,
-.015571,-.016064,
-.016064,-.015571,
-.016464,-.015,
-.016759,-.014368,
-.016939,-.013695,
-.017,-.013,
0.0*
%
%ADD35MACRO35*%
%ADD12C,.01*%
%ADD16C,.02*%
%ADD56R,.301X.085*%
%ADD21C,.04*%
%ADD13C,.022*%
%ADD30C,.032*%
%ADD27C,.05*%
%AMMACRO47*
4,1,40,-.007,-.004,
-.007,.004,
-.00697,.004347,
-.006879,.004684,
-.006732,.005,
-.006532,.005286,
-.006286,.005532,
-.006,.005732,
-.005684,.005879,
-.005347,.00597,
-.005,.006,
.005,.006,
.005347,.00597,
.005684,.005879,
.006,.005732,
.006286,.005532,
.006532,.005286,
.006732,.005,
.006879,.004684,
.00697,.004347,
.007,.004,
.007,-.004,
.00697,-.004347,
.006879,-.004684,
.006732,-.005,
.006532,-.005286,
.006286,-.005532,
.006,-.005732,
.005684,-.005879,
.005347,-.00597,
.005,-.006,
-.005,-.006,
-.005347,-.00597,
-.005684,-.005879,
-.006,-.005732,
-.006286,-.005532,
-.006532,-.005286,
-.006732,-.005,
-.006879,-.004684,
-.00697,-.004347,
-.007,-.004,
0.0*
%
%ADD47MACRO47*%
%ADD32R,.028X.126*%
%ADD61C,.052*%
%ADD58C,.043*%
%AMMACRO50*
4,1,40,-.004,.007,
.004,.007,
.004347,.00697,
.004684,.006879,
.005,.006732,
.005286,.006532,
.005532,.006286,
.005732,.006,
.005879,.005684,
.00597,.005347,
.006,.005,
.006,-.005,
.00597,-.005347,
.005879,-.005684,
.005732,-.006,
.005532,-.006286,
.005286,-.006532,
.005,-.006732,
.004684,-.006879,
.004347,-.00697,
.004,-.007,
-.004,-.007,
-.004347,-.00697,
-.004684,-.006879,
-.005,-.006732,
-.005286,-.006532,
-.005532,-.006286,
-.005732,-.006,
-.005879,-.005684,
-.00597,-.005347,
-.006,-.005,
-.006,.005,
-.00597,.005347,
-.005879,.005684,
-.005732,.006,
-.005532,.006286,
-.005286,.006532,
-.005,.006732,
-.004684,.006879,
-.004347,.00697,
-.004,.007,
0.0*
%
%ADD50MACRO50*%
%ADD29C,.061*%
%ADD69C,.054*%
%ADD52C,.045*%
%ADD26R,.028X.165*%
%ADD28C,.046*%
%ADD10C,.028*%
%ADD31C,.056*%
%ADD59C,.066*%
%ADD70C,.058*%
%ADD60C,.078*%
%AMMACRO36*
4,1,40,.0225,.007,
.022378,.008389,
.022018,.009736,
.021428,.011,
.020628,.012142,
.019642,.013128,
.0185,.013928,
.017236,.014518,
.015889,.014878,
.0145,.015,
-.0145,.015,
-.015889,.014878,
-.017236,.014518,
-.0185,.013928,
-.019642,.013128,
-.020628,.012142,
-.021428,.011,
-.022018,.009736,
-.022378,.008389,
-.0225,.007,
-.0225,-.007,
-.022378,-.008389,
-.022018,-.009736,
-.021428,-.011,
-.020628,-.012142,
-.019642,-.013128,
-.0185,-.013928,
-.017236,-.014518,
-.015889,-.014878,
-.0145,-.015,
.0145,-.015,
.015889,-.014878,
.017236,-.014518,
.0185,-.013928,
.019642,-.013128,
.020628,-.012142,
.021428,-.011,
.022018,-.009736,
.022378,-.008389,
.0225,-.007,
.0225,.007,
0.0*
%
%ADD36MACRO36*%
%AMMACRO62*
4,1,40,.007,-.0225,
.008389,-.022378,
.009736,-.022018,
.011,-.021428,
.012142,-.020628,
.013128,-.019642,
.013928,-.0185,
.014518,-.017236,
.014878,-.015889,
.015,-.0145,
.015,.0145,
.014878,.015889,
.014518,.017236,
.013928,.0185,
.013128,.019642,
.012142,.020628,
.011,.021428,
.009736,.022018,
.008389,.022378,
.007,.0225,
-.007,.0225,
-.008389,.022378,
-.009736,.022018,
-.011,.021428,
-.012142,.020628,
-.013128,.019642,
-.013928,.0185,
-.014518,.017236,
-.014878,.015889,
-.015,.0145,
-.015,-.0145,
-.014878,-.015889,
-.014518,-.017236,
-.013928,-.0185,
-.013128,-.019642,
-.012142,-.020628,
-.011,-.021428,
-.009736,-.022018,
-.008389,-.022378,
-.007,-.0225,
.007,-.0225,
0.0*
%
%ADD62MACRO62*%
%AMMACRO42*
4,1,40,-.011,-.007,
-.011,.007,
-.010939,.007695,
-.010759,.008368,
-.010464,.009,
-.010064,.009571,
-.009571,.010064,
-.009,.010464,
-.008368,.010759,
-.007695,.010939,
-.007,.011,
.007,.011,
.007695,.010939,
.008368,.010759,
.009,.010464,
.009571,.010064,
.010064,.009571,
.010464,.009,
.010759,.008368,
.010939,.007695,
.011,.007,
.011,-.007,
.010939,-.007695,
.010759,-.008368,
.010464,-.009,
.010064,-.009571,
.009571,-.010064,
.009,-.010464,
.008368,-.010759,
.007695,-.010939,
.007,-.011,
-.007,-.011,
-.007695,-.010939,
-.008368,-.010759,
-.009,-.010464,
-.009571,-.010064,
-.010064,-.009571,
-.010464,-.009,
-.010759,-.008368,
-.010939,-.007695,
-.011,-.007,
0.0*
%
%ADD42MACRO42*%
%AMMACRO34*
4,1,40,.007,-.011,
-.007,-.011,
-.007695,-.010939,
-.008368,-.010759,
-.009,-.010464,
-.009571,-.010064,
-.010064,-.009571,
-.010464,-.009,
-.010759,-.008368,
-.010939,-.007695,
-.011,-.007,
-.011,.007,
-.010939,.007695,
-.010759,.008368,
-.010464,.009,
-.010064,.009571,
-.009571,.010064,
-.009,.010464,
-.008368,.010759,
-.007695,.010939,
-.007,.011,
.007,.011,
.007695,.010939,
.008368,.010759,
.009,.010464,
.009571,.010064,
.010064,.009571,
.010464,.009,
.010759,.008368,
.010939,.007695,
.011,.007,
.011,-.007,
.010939,-.007695,
.010759,-.008368,
.010464,-.009,
.010064,-.009571,
.009571,-.010064,
.009,-.010464,
.008368,-.010759,
.007695,-.010939,
.007,-.011,
0.0*
%
%ADD34MACRO34*%
%AMMACRO73*
4,1,22,-.007,.0145,
-.007695,.014439,
-.008368,.014259,
-.009,.013964,
-.009571,.013564,
-.010064,.013071,
-.010464,.0125,
-.010759,.011868,
-.010939,.011195,
-.011,.0105,
-.011,-.0145,
.011,-.0145,
.011,.0105,
.010939,.011195,
.010759,.011868,
.010464,.0125,
.010064,.013071,
.009571,.013564,
.009,.013964,
.008368,.014259,
.007695,.014439,
.007,.0145,
-.007,.0145,
0.0*
%
%ADD73MACRO73*%
%AMMACRO23*
4,1,40,-.012,-.008,
-.012,.008,
-.011939,.008695,
-.011759,.009368,
-.011464,.01,
-.011064,.010571,
-.010571,.011064,
-.01,.011464,
-.009368,.011759,
-.008695,.011939,
-.008,.012,
.008,.012,
.008695,.011939,
.009368,.011759,
.01,.011464,
.010571,.011064,
.011064,.010571,
.011464,.01,
.011759,.009368,
.011939,.008695,
.012,.008,
.012,-.008,
.011939,-.008695,
.011759,-.009368,
.011464,-.01,
.011064,-.010571,
.010571,-.011064,
.01,-.011464,
.009368,-.011759,
.008695,-.011939,
.008,-.012,
-.008,-.012,
-.008695,-.011939,
-.009368,-.011759,
-.01,-.011464,
-.010571,-.011064,
-.011064,-.010571,
-.011464,-.01,
-.011759,-.009368,
-.011939,-.008695,
-.012,-.008,
0.0*
%
%ADD23MACRO23*%
%AMMACRO15*
4,1,40,-.008,.012,
.008,.012,
.008695,.011939,
.009368,.011759,
.01,.011464,
.010571,.011064,
.011064,.010571,
.011464,.01,
.011759,.009368,
.011939,.008695,
.012,.008,
.012,-.008,
.011939,-.008695,
.011759,-.009368,
.011464,-.01,
.011064,-.010571,
.010571,-.011064,
.01,-.011464,
.009368,-.011759,
.008695,-.011939,
.008,-.012,
-.008,-.012,
-.008695,-.011939,
-.009368,-.011759,
-.01,-.011464,
-.010571,-.011064,
-.011064,-.010571,
-.011464,-.01,
-.011759,-.009368,
-.011939,-.008695,
-.012,-.008,
-.012,.008,
-.011939,.008695,
-.011759,.009368,
-.011464,.01,
-.011064,.010571,
-.010571,.011064,
-.01,.011464,
-.009368,.011759,
-.008695,.011939,
-.008,.012,
0.0*
%
%ADD15MACRO15*%
%AMMACRO63*
4,1,40,-.013,.017,
.013,.017,
.013695,.016939,
.014368,.016759,
.015,.016464,
.015571,.016064,
.016064,.015571,
.016464,.015,
.016759,.014368,
.016939,.013695,
.017,.013,
.017,-.013,
.016939,-.013695,
.016759,-.014368,
.016464,-.015,
.016064,-.015571,
.015571,-.016064,
.015,-.016464,
.014368,-.016759,
.013695,-.016939,
.013,-.017,
-.013,-.017,
-.013695,-.016939,
-.014368,-.016759,
-.015,-.016464,
-.015571,-.016064,
-.016064,-.015571,
-.016464,-.015,
-.016759,-.014368,
-.016939,-.013695,
-.017,-.013,
-.017,.013,
-.016939,.013695,
-.016759,.014368,
-.016464,.015,
-.016064,.015571,
-.015571,.016064,
-.015,.016464,
-.014368,.016759,
-.013695,.016939,
-.013,.017,
0.0*
%
%ADD63MACRO63*%
%AMMACRO76*
4,1,6,.025,-.0135,
.005,.0065,
.005,.0135,
-.005,.0135,
-.005,.0065,
-.025,-.0135,
.025,-.0135,
0.0*
%
%ADD76MACRO76*%
%AMMACRO48*
4,1,40,.017,.013,
.017,-.013,
.016939,-.013695,
.016759,-.014368,
.016464,-.015,
.016064,-.015571,
.015571,-.016064,
.015,-.016464,
.014368,-.016759,
.013695,-.016939,
.013,-.017,
-.013,-.017,
-.013695,-.016939,
-.014368,-.016759,
-.015,-.016464,
-.015571,-.016064,
-.016064,-.015571,
-.016464,-.015,
-.016759,-.014368,
-.016939,-.013695,
-.017,-.013,
-.017,.013,
-.016939,.013695,
-.016759,.014368,
-.016464,.015,
-.016064,.015571,
-.015571,.016064,
-.015,.016464,
-.014368,.016759,
-.013695,.016939,
-.013,.017,
.013,.017,
.013695,.016939,
.014368,.016759,
.015,.016464,
.015571,.016064,
.016064,.015571,
.016464,.015,
.016759,.014368,
.016939,.013695,
.017,.013,
0.0*
%
%ADD48MACRO48*%
%AMMACRO43*
4,1,40,-.011,-.007,
-.011,.007,
-.010939,.007695,
-.010759,.008368,
-.010464,.009,
-.010064,.009571,
-.009571,.010064,
-.009,.010464,
-.008368,.010759,
-.007695,.010939,
-.007,.011,
.007,.011,
.007695,.010939,
.008368,.010759,
.009,.010464,
.009571,.010064,
.010064,.009571,
.010464,.009,
.010759,.008368,
.010939,.007695,
.011,.007,
.011,-.007,
.010939,-.007695,
.010759,-.008368,
.010464,-.009,
.010064,-.009571,
.009571,-.010064,
.009,-.010464,
.008368,-.010759,
.007695,-.010939,
.007,-.011,
-.007,-.011,
-.007695,-.010939,
-.008368,-.010759,
-.009,-.010464,
-.009571,-.010064,
-.010064,-.009571,
-.010464,-.009,
-.010759,-.008368,
-.010939,-.007695,
-.011,-.007,
0.0*
%
%ADD43MACRO43*%
%AMMACRO38*
4,1,40,.007,-.011,
-.007,-.011,
-.007695,-.010939,
-.008368,-.010759,
-.009,-.010464,
-.009571,-.010064,
-.010064,-.009571,
-.010464,-.009,
-.010759,-.008368,
-.010939,-.007695,
-.011,-.007,
-.011,.007,
-.010939,.007695,
-.010759,.008368,
-.010464,.009,
-.010064,.009571,
-.009571,.010064,
-.009,.010464,
-.008368,.010759,
-.007695,.010939,
-.007,.011,
.007,.011,
.007695,.010939,
.008368,.010759,
.009,.010464,
.009571,.010064,
.010064,.009571,
.010464,.009,
.010759,.008368,
.010939,.007695,
.011,.007,
.011,-.007,
.010939,-.007695,
.010759,-.008368,
.010464,-.009,
.010064,-.009571,
.009571,-.010064,
.009,-.010464,
.008368,-.010759,
.007695,-.010939,
.007,-.011,
0.0*
%
%ADD38MACRO38*%
%AMMACRO74*
4,1,22,-.011,.0145,
-.011,-.0105,
-.010939,-.011195,
-.010759,-.011868,
-.010464,-.0125,
-.010064,-.013071,
-.009571,-.013564,
-.009,-.013964,
-.008368,-.014259,
-.007695,-.014439,
-.007,-.0145,
.007,-.0145,
.007695,-.014439,
.008368,-.014259,
.009,-.013964,
.009571,-.013564,
.010064,-.013071,
.010464,-.0125,
.010759,-.011868,
.010939,-.011195,
.011,-.0105,
.011,.0145,
-.011,.0145,
0.0*
%
%ADD74MACRO74*%
%AMMACRO22*
4,1,40,-.012,-.008,
-.012,.008,
-.011939,.008695,
-.011759,.009368,
-.011464,.01,
-.011064,.010571,
-.010571,.011064,
-.01,.011464,
-.009368,.011759,
-.008695,.011939,
-.008,.012,
.008,.012,
.008695,.011939,
.009368,.011759,
.01,.011464,
.010571,.011064,
.011064,.010571,
.011464,.01,
.011759,.009368,
.011939,.008695,
.012,.008,
.012,-.008,
.011939,-.008695,
.011759,-.009368,
.011464,-.01,
.011064,-.010571,
.010571,-.011064,
.01,-.011464,
.009368,-.011759,
.008695,-.011939,
.008,-.012,
-.008,-.012,
-.008695,-.011939,
-.009368,-.011759,
-.01,-.011464,
-.010571,-.011064,
-.011064,-.010571,
-.011464,-.01,
-.011759,-.009368,
-.011939,-.008695,
-.012,-.008,
0.0*
%
%ADD22MACRO22*%
%AMMACRO14*
4,1,40,-.008,.012,
.008,.012,
.008695,.011939,
.009368,.011759,
.01,.011464,
.010571,.011064,
.011064,.010571,
.011464,.01,
.011759,.009368,
.011939,.008695,
.012,.008,
.012,-.008,
.011939,-.008695,
.011759,-.009368,
.011464,-.01,
.011064,-.010571,
.010571,-.011064,
.01,-.011464,
.009368,-.011759,
.008695,-.011939,
.008,-.012,
-.008,-.012,
-.008695,-.011939,
-.009368,-.011759,
-.01,-.011464,
-.010571,-.011064,
-.011064,-.010571,
-.011464,-.01,
-.011759,-.009368,
-.011939,-.008695,
-.012,-.008,
-.012,.008,
-.011939,.008695,
-.011759,.009368,
-.011464,.01,
-.011064,.010571,
-.010571,.011064,
-.01,.011464,
-.009368,.011759,
-.008695,.011939,
-.008,.012,
0.0*
%
%ADD14MACRO14*%
%AMMACRO64*
4,1,40,-.013,.017,
.013,.017,
.013695,.016939,
.014368,.016759,
.015,.016464,
.015571,.016064,
.016064,.015571,
.016464,.015,
.016759,.014368,
.016939,.013695,
.017,.013,
.017,-.013,
.016939,-.013695,
.016759,-.014368,
.016464,-.015,
.016064,-.015571,
.015571,-.016064,
.015,-.016464,
.014368,-.016759,
.013695,-.016939,
.013,-.017,
-.013,-.017,
-.013695,-.016939,
-.014368,-.016759,
-.015,-.016464,
-.015571,-.016064,
-.016064,-.015571,
-.016464,-.015,
-.016759,-.014368,
-.016939,-.013695,
-.017,-.013,
-.017,.013,
-.016939,.013695,
-.016759,.014368,
-.016464,.015,
-.016064,.015571,
-.015571,.016064,
-.015,.016464,
-.014368,.016759,
-.013695,.016939,
-.013,.017,
0.0*
%
%ADD64MACRO64*%
%AMMACRO49*
4,1,40,.017,.013,
.017,-.013,
.016939,-.013695,
.016759,-.014368,
.016464,-.015,
.016064,-.015571,
.015571,-.016064,
.015,-.016464,
.014368,-.016759,
.013695,-.016939,
.013,-.017,
-.013,-.017,
-.013695,-.016939,
-.014368,-.016759,
-.015,-.016464,
-.015571,-.016064,
-.016064,-.015571,
-.016464,-.015,
-.016759,-.014368,
-.016939,-.013695,
-.017,-.013,
-.017,.013,
-.016939,.013695,
-.016759,.014368,
-.016464,.015,
-.016064,.015571,
-.015571,.016064,
-.015,.016464,
-.014368,.016759,
-.013695,.016939,
-.013,.017,
.013,.017,
.013695,.016939,
.014368,.016759,
.015,.016464,
.015571,.016064,
.016064,.015571,
.016464,.015,
.016759,.014368,
.016939,.013695,
.017,.013,
0.0*
%
%ADD49MACRO49*%
%ADD67R,.02X.06*%
%ADD55R,.012X.038*%
%ADD54R,.038X.012*%
%AMMACRO51*
4,1,40,.004,-.007,
-.004,-.007,
-.004347,-.00697,
-.004684,-.006879,
-.005,-.006732,
-.005286,-.006532,
-.005532,-.006286,
-.005732,-.006,
-.005879,-.005684,
-.00597,-.005347,
-.006,-.005,
-.006,.005,
-.00597,.005347,
-.005879,.005684,
-.005732,.006,
-.005532,.006286,
-.005286,.006532,
-.005,.006732,
-.004684,.006879,
-.004347,.00697,
-.004,.007,
.004,.007,
.004347,.00697,
.004684,.006879,
.005,.006732,
.005286,.006532,
.005532,.006286,
.005732,.006,
.005879,.005684,
.00597,.005347,
.006,.005,
.006,-.005,
.00597,-.005347,
.005879,-.005684,
.005732,-.006,
.005532,-.006286,
.005286,-.006532,
.005,-.006732,
.004684,-.006879,
.004347,-.00697,
.004,-.007,
0.0*
%
%ADD51MACRO51*%
%AMMACRO39*
4,1,40,.007,.004,
.007,-.004,
.00697,-.004347,
.006879,-.004684,
.006732,-.005,
.006532,-.005286,
.006286,-.005532,
.006,-.005732,
.005684,-.005879,
.005347,-.00597,
.005,-.006,
-.005,-.006,
-.005347,-.00597,
-.005684,-.005879,
-.006,-.005732,
-.006286,-.005532,
-.006532,-.005286,
-.006732,-.005,
-.006879,-.004684,
-.00697,-.004347,
-.007,-.004,
-.007,.004,
-.00697,.004347,
-.006879,.004684,
-.006732,.005,
-.006532,.005286,
-.006286,.005532,
-.006,.005732,
-.005684,.005879,
-.005347,.00597,
-.005,.006,
.005,.006,
.005347,.00597,
.005684,.005879,
.006,.005732,
.006286,.005532,
.006532,.005286,
.006732,.005,
.006879,.004684,
.00697,.004347,
.007,.004,
0.0*
%
%ADD39MACRO39*%
%ADD68C,.107*%
%ADD40R,.045X.055*%
%ADD44R,.016X.048*%
%ADD41R,.055X.045*%
%ADD11C,.158*%
%AMMACRO57*
4,1,40,-.007,.0225,
-.008389,.022378,
-.009736,.022018,
-.011,.021428,
-.012142,.020628,
-.013128,.019642,
-.013928,.0185,
-.014518,.017236,
-.014878,.015889,
-.015,.0145,
-.015,-.0145,
-.014878,-.015889,
-.014518,-.017236,
-.013928,-.0185,
-.013128,-.019642,
-.012142,-.020628,
-.011,-.021428,
-.009736,-.022018,
-.008389,-.022378,
-.007,-.0225,
.007,-.0225,
.008389,-.022378,
.009736,-.022018,
.011,-.021428,
.012142,-.020628,
.013128,-.019642,
.013928,-.0185,
.014518,-.017236,
.014878,-.015889,
.015,-.0145,
.015,.0145,
.014878,.015889,
.014518,.017236,
.013928,.0185,
.013128,.019642,
.012142,.020628,
.011,.021428,
.009736,.022018,
.008389,.022378,
.007,.0225,
-.007,.0225,
0.0*
%
%ADD57MACRO57*%
%AMMACRO53*
4,1,40,.024,-.012,
.024,.012,
.023878,.013389,
.023518,.014736,
.022928,.016,
.022128,.017142,
.021142,.018128,
.02,.018928,
.018736,.019518,
.017389,.019878,
.016,.02,
-.016,.02,
-.017389,.019878,
-.018736,.019518,
-.02,.018928,
-.021142,.018128,
-.022128,.017142,
-.022928,.016,
-.023518,.014736,
-.023878,.013389,
-.024,.012,
-.024,-.012,
-.023878,-.013389,
-.023518,-.014736,
-.022928,-.016,
-.022128,-.017142,
-.021142,-.018128,
-.02,-.018928,
-.018736,-.019518,
-.017389,-.019878,
-.016,-.02,
.016,-.02,
.017389,-.019878,
.018736,-.019518,
.02,-.018928,
.021142,-.018128,
.022128,-.017142,
.022928,-.016,
.023518,-.014736,
.023878,-.013389,
.024,-.012,
0.0*
%
%ADD53MACRO53*%
%AMMACRO46*
4,1,40,.008,-.012,
-.008,-.012,
-.008695,-.011939,
-.009368,-.011759,
-.01,-.011464,
-.010571,-.011064,
-.011064,-.010571,
-.011464,-.01,
-.011759,-.009368,
-.011939,-.008695,
-.012,-.008,
-.012,.008,
-.011939,.008695,
-.011759,.009368,
-.011464,.01,
-.011064,.010571,
-.010571,.011064,
-.01,.011464,
-.009368,.011759,
-.008695,.011939,
-.008,.012,
.008,.012,
.008695,.011939,
.009368,.011759,
.01,.011464,
.010571,.011064,
.011064,.010571,
.011464,.01,
.011759,.009368,
.011939,.008695,
.012,.008,
.012,-.008,
.011939,-.008695,
.011759,-.009368,
.011464,-.01,
.011064,-.010571,
.010571,-.011064,
.01,-.011464,
.009368,-.011759,
.008695,-.011939,
.008,-.012,
0.0*
%
%ADD46MACRO46*%
%AMMACRO24*
4,1,40,.012,.008,
.012,-.008,
.011939,-.008695,
.011759,-.009368,
.011464,-.01,
.011064,-.010571,
.010571,-.011064,
.01,-.011464,
.009368,-.011759,
.008695,-.011939,
.008,-.012,
-.008,-.012,
-.008695,-.011939,
-.009368,-.011759,
-.01,-.011464,
-.010571,-.011064,
-.011064,-.010571,
-.011464,-.01,
-.011759,-.009368,
-.011939,-.008695,
-.012,-.008,
-.012,.008,
-.011939,.008695,
-.011759,.009368,
-.011464,.01,
-.011064,.010571,
-.010571,.011064,
-.01,.011464,
-.009368,.011759,
-.008695,.011939,
-.008,.012,
.008,.012,
.008695,.011939,
.009368,.011759,
.01,.011464,
.010571,.011064,
.011064,.010571,
.011464,.01,
.011759,.009368,
.011939,.008695,
.012,.008,
0.0*
%
%ADD24MACRO24*%
%AMMACRO17*
4,1,40,-.007,.011,
.007,.011,
.007695,.010939,
.008368,.010759,
.009,.010464,
.009571,.010064,
.010064,.009571,
.010464,.009,
.010759,.008368,
.010939,.007695,
.011,.007,
.011,-.007,
.010939,-.007695,
.010759,-.008368,
.010464,-.009,
.010064,-.009571,
.009571,-.010064,
.009,-.010464,
.008368,-.010759,
.007695,-.010939,
.007,-.011,
-.007,-.011,
-.007695,-.010939,
-.008368,-.010759,
-.009,-.010464,
-.009571,-.010064,
-.010064,-.009571,
-.010464,-.009,
-.010759,-.008368,
-.010939,-.007695,
-.011,-.007,
-.011,.007,
-.010939,.007695,
-.010759,.008368,
-.010464,.009,
-.010064,.009571,
-.009571,.010064,
-.009,.010464,
-.008368,.010759,
-.007695,.010939,
-.007,.011,
0.0*
%
%ADD17MACRO17*%
%AMMACRO19*
4,1,40,.011,.007,
.011,-.007,
.010939,-.007695,
.010759,-.008368,
.010464,-.009,
.010064,-.009571,
.009571,-.010064,
.009,-.010464,
.008368,-.010759,
.007695,-.010939,
.007,-.011,
-.007,-.011,
-.007695,-.010939,
-.008368,-.010759,
-.009,-.010464,
-.009571,-.010064,
-.010064,-.009571,
-.010464,-.009,
-.010759,-.008368,
-.010939,-.007695,
-.011,-.007,
-.011,.007,
-.010939,.007695,
-.010759,.008368,
-.010464,.009,
-.010064,.009571,
-.009571,.010064,
-.009,.010464,
-.008368,.010759,
-.007695,.010939,
-.007,.011,
.007,.011,
.007695,.010939,
.008368,.010759,
.009,.010464,
.009571,.010064,
.010064,.009571,
.010464,.009,
.010759,.008368,
.010939,.007695,
.011,.007,
0.0*
%
%ADD19MACRO19*%
%AMMACRO71*
4,1,22,.007,-.0145,
.007695,-.014439,
.008368,-.014259,
.009,-.013964,
.009571,-.013564,
.010064,-.013071,
.010464,-.0125,
.010759,-.011868,
.010939,-.011195,
.011,-.0105,
.011,.0145,
-.011,.0145,
-.011,-.0105,
-.010939,-.011195,
-.010759,-.011868,
-.010464,-.0125,
-.010064,-.013071,
-.009571,-.013564,
-.009,-.013964,
-.008368,-.014259,
-.007695,-.014439,
-.007,-.0145,
.007,-.0145,
0.0*
%
%ADD71MACRO71*%
%AMMACRO65*
4,1,40,.013,-.017,
-.013,-.017,
-.013695,-.016939,
-.014368,-.016759,
-.015,-.016464,
-.015571,-.016064,
-.016064,-.015571,
-.016464,-.015,
-.016759,-.014368,
-.016939,-.013695,
-.017,-.013,
-.017,.013,
-.016939,.013695,
-.016759,.014368,
-.016464,.015,
-.016064,.015571,
-.015571,.016064,
-.015,.016464,
-.014368,.016759,
-.013695,.016939,
-.013,.017,
.013,.017,
.013695,.016939,
.014368,.016759,
.015,.016464,
.015571,.016064,
.016064,.015571,
.016464,.015,
.016759,.014368,
.016939,.013695,
.017,.013,
.017,-.013,
.016939,-.013695,
.016759,-.014368,
.016464,-.015,
.016064,-.015571,
.015571,-.016064,
.015,-.016464,
.014368,-.016759,
.013695,-.016939,
.013,-.017,
0.0*
%
%ADD65MACRO65*%
%AMMACRO37*
4,1,40,-.017,-.013,
-.017,.013,
-.016939,.013695,
-.016759,.014368,
-.016464,.015,
-.016064,.015571,
-.015571,.016064,
-.015,.016464,
-.014368,.016759,
-.013695,.016939,
-.013,.017,
.013,.017,
.013695,.016939,
.014368,.016759,
.015,.016464,
.015571,.016064,
.016064,.015571,
.016464,.015,
.016759,.014368,
.016939,.013695,
.017,.013,
.017,-.013,
.016939,-.013695,
.016759,-.014368,
.016464,-.015,
.016064,-.015571,
.015571,-.016064,
.015,-.016464,
.014368,-.016759,
.013695,-.016939,
.013,-.017,
-.013,-.017,
-.013695,-.016939,
-.014368,-.016759,
-.015,-.016464,
-.015571,-.016064,
-.016064,-.015571,
-.016464,-.015,
-.016759,-.014368,
-.016939,-.013695,
-.017,-.013,
0.0*
%
%ADD37MACRO37*%
%AMMACRO75*
4,1,6,.005,-.0135,
.005,-.0065,
.025,.0135,
-.025,.0135,
-.005,-.0065,
-.005,-.0135,
.005,-.0135,
0.0*
%
%ADD75MACRO75*%
%AMMACRO45*
4,1,40,.008,-.012,
-.008,-.012,
-.008695,-.011939,
-.009368,-.011759,
-.01,-.011464,
-.010571,-.011064,
-.011064,-.010571,
-.011464,-.01,
-.011759,-.009368,
-.011939,-.008695,
-.012,-.008,
-.012,.008,
-.011939,.008695,
-.011759,.009368,
-.011464,.01,
-.011064,.010571,
-.010571,.011064,
-.01,.011464,
-.009368,.011759,
-.008695,.011939,
-.008,.012,
.008,.012,
.008695,.011939,
.009368,.011759,
.01,.011464,
.010571,.011064,
.011064,.010571,
.011464,.01,
.011759,.009368,
.011939,.008695,
.012,.008,
.012,-.008,
.011939,-.008695,
.011759,-.009368,
.011464,-.01,
.011064,-.010571,
.010571,-.011064,
.01,-.011464,
.009368,-.011759,
.008695,-.011939,
.008,-.012,
0.0*
%
%ADD45MACRO45*%
%AMMACRO25*
4,1,40,.012,.008,
.012,-.008,
.011939,-.008695,
.011759,-.009368,
.011464,-.01,
.011064,-.010571,
.010571,-.011064,
.01,-.011464,
.009368,-.011759,
.008695,-.011939,
.008,-.012,
-.008,-.012,
-.008695,-.011939,
-.009368,-.011759,
-.01,-.011464,
-.010571,-.011064,
-.011064,-.010571,
-.011464,-.01,
-.011759,-.009368,
-.011939,-.008695,
-.012,-.008,
-.012,.008,
-.011939,.008695,
-.011759,.009368,
-.011464,.01,
-.011064,.010571,
-.010571,.011064,
-.01,.011464,
-.009368,.011759,
-.008695,.011939,
-.008,.012,
.008,.012,
.008695,.011939,
.009368,.011759,
.01,.011464,
.010571,.011064,
.011064,.010571,
.011464,.01,
.011759,.009368,
.011939,.008695,
.012,.008,
0.0*
%
%ADD25MACRO25*%
%AMMACRO18*
4,1,40,-.007,.011,
.007,.011,
.007695,.010939,
.008368,.010759,
.009,.010464,
.009571,.010064,
.010064,.009571,
.010464,.009,
.010759,.008368,
.010939,.007695,
.011,.007,
.011,-.007,
.010939,-.007695,
.010759,-.008368,
.010464,-.009,
.010064,-.009571,
.009571,-.010064,
.009,-.010464,
.008368,-.010759,
.007695,-.010939,
.007,-.011,
-.007,-.011,
-.007695,-.010939,
-.008368,-.010759,
-.009,-.010464,
-.009571,-.010064,
-.010064,-.009571,
-.010464,-.009,
-.010759,-.008368,
-.010939,-.007695,
-.011,-.007,
-.011,.007,
-.010939,.007695,
-.010759,.008368,
-.010464,.009,
-.010064,.009571,
-.009571,.010064,
-.009,.010464,
-.008368,.010759,
-.007695,.010939,
-.007,.011,
0.0*
%
%ADD18MACRO18*%
%ADD77C,.012*%
%ADD78C,.014*%
%ADD79C,.024*%
%ADD80C,.015*%
%ADD81C,.025*%
%ADD82C,.018*%
%ADD83C,.004*%
%ADD84C,.005*%
%ADD85C,.006*%
%ADD86C,.007*%
%ADD87C,.008*%
%ADD88C,.0035*%
%ADD89C,.0045*%
%ADD90C,.0055*%
%ADD110C,.03004*%
%ADD112R,.008X.018*%
%ADD100C,.07004*%
%ADD98C,.05204*%
%ADD113C,.06204*%
%ADD99C,.04404*%
%ADD101C,.09004*%
%ADD116C,.08204*%
%ADD92C,.04604*%
%ADD114C,.05604*%
%ADD97C,.07404*%
%ADD117C,.05804*%
%ADD115C,.06704*%
%ADD95C,.08504*%
%ADD94C,.08604*%
%ADD102C,.07804*%
%ADD93R,.01X.01*%
%ADD109R,.02X.01*%
%ADD107R,.01X.02*%
%ADD105R,.01X.021*%
%ADD104R,.021X.01*%
%ADD108R,.01X.024*%
%ADD111R,.025X.01*%
%ADD91C,.10204*%
%ADD103C,.13104*%
%ADD106R,.008X.008*%
%ADD96C,.18204*%
G75*
%LPD*%
G75*
G36*
G01X327000Y15500D02*
X329000Y13500D01*
X346949D01*
G03X348200Y12898I1251J999D01*
G01X349800D01*
G03X351051Y13500I0J1601D01*
G01X351549D01*
G03X352800Y12898I1251J999D01*
G01X354200D01*
G03X355451Y13500I0J1601D01*
G01X355949D01*
G03X357200Y12898I1251J999D01*
G01X358800D01*
G03X359750Y13211I-1J1602D01*
G03X360700Y12898I951J1289D01*
G01X362300D01*
G03X363551Y13500I0J1601D01*
G01X374138D01*
X374170Y13489D01*
G03X374700Y13398I532J1511D01*
G01X377300D01*
G03X377830Y13489I-2J1602D01*
G01X377862Y13500D01*
X379138D01*
X379170Y13489D01*
G03X379700Y13398I532J1511D01*
G01X382300D01*
G03X382491Y13410I-5J1602D01*
G02X382713Y13234I23J-198D01*
G03X387295Y13316I2287J265D01*
G01X387309Y13500D01*
X387691D01*
X387705Y13316D01*
G03X392295I2295J184D01*
G01X392309Y13500D01*
X403500D01*
X406000Y16000D01*
X519500D01*
X567500Y64000D01*
X581500D01*
X583500Y62000D01*
Y57500D01*
X589000Y52000D01*
X598047D01*
G02X598191Y51227I0J-400D01*
G03X603659I2734J-7093D01*
G02X603803Y52000I144J373D01*
G01X636039D01*
G02X636183Y51227I0J-400D01*
G03X641651I2734J-7093D01*
G02X641795Y52000I144J373D01*
G01X668500D01*
X673614Y57114D01*
G02X674296Y56831I282J-283D01*
G01Y52000D01*
G03X679200I2452J0D01*
G01Y58733D01*
X683030Y62563D01*
G02X683710Y62239I282J-283D01*
G03X683886Y61088I2290J-239D01*
G02X683718Y60582I-367J-159D01*
G03X683463Y56756I1143J-1998D01*
G02X683560Y56228I-243J-318D01*
G03X686917Y56847I1959J-1209D01*
G02X686820Y57375I243J318D01*
G03X686975Y59496I-1959J1209D01*
G02X687143Y60002I367J159D01*
G03X685761Y64290I-1143J1998D01*
G02X685437Y64970I-41J398D01*
G01X686452Y65985D01*
Y69952D01*
X711000Y94500D01*
Y119000D01*
X709168Y120832D01*
Y121306D01*
X709184Y121344D01*
G03X709318Y121984I-1468J641D01*
G01Y123584D01*
G03X709184Y124224I-1602J-1D01*
G01X709168Y124262D01*
Y124806D01*
X709184Y124844D01*
G03X709318Y125484I-1468J641D01*
G01Y127084D01*
G03X709005Y128034I-1602J-1D01*
G03X709318Y128984I-1289J951D01*
G01Y129296D01*
X709321Y129315D01*
G03X709368Y129784I-2355J473D01*
G01Y133284D01*
G03X709321Y133753I-2402J-4D01*
G01X709318Y133772D01*
Y134084D01*
G03X709238Y134583I-1602J-1D01*
G01X709200Y134700D01*
X711000Y136500D01*
X723500D01*
X726500Y133500D01*
X728459D01*
G03X729416Y133182I958J1284D01*
G01X731016D01*
G03X731966Y133495I-1J1602D01*
G03X732916Y133182I951J1289D01*
G01X734516D01*
G03X735060Y133278I-2J1602D01*
G01X735179Y133321D01*
X736500Y132000D01*
X744500D01*
X786000Y173500D01*
Y205500D01*
X807500Y227000D01*
X820000D01*
X830548Y216452D01*
Y139287D01*
G03X833452I1452J-1787D01*
G01Y212583D01*
G02X834134Y212866I400J0D01*
G01X835000Y212000D01*
X958442D01*
X958481Y211850D01*
G03X963519I2519J650D01*
G01X963558Y212000D01*
X963855D01*
G02X964141Y211320I0J-400D01*
G03X967859I1859J-1820D01*
G02X968145Y212000I286J280D01*
G01X997000D01*
X1005017Y203983D01*
X1002242Y201208D01*
X981072D01*
X981050Y201214D01*
G03X978757Y197094I-560J-2387D01*
G01X979545Y196306D01*
X1004272D01*
X1008483Y200517D01*
X1012500Y196500D01*
Y102000D01*
X998500Y88000D01*
Y81000D01*
X1003500Y76000D01*
X1005138D01*
X1005170Y75989D01*
G03X1005700Y75898I532J1511D01*
G01X1007102D01*
X1008000Y75000D01*
Y71862D01*
X1007989Y71830D01*
G03X1007898Y71300I1511J-532D01*
G01Y69700D01*
G03X1007989Y69170I1602J2D01*
G01X1008000Y69138D01*
Y67762D01*
X1007989Y67730D01*
G03X1007898Y67200I1511J-532D01*
G01Y65898D01*
X1003697Y61697D01*
X1003586Y61726D01*
G03X1000774Y58914I-586J-2226D01*
G01X1000803Y58803D01*
X998500Y56500D01*
Y44500D01*
X1006000Y37000D01*
X1039315D01*
G02X1039643Y36370I1J-400D01*
G03X1050357I5357J-3772D01*
G02X1050685Y37000I327J230D01*
G01X1060500D01*
X1064087Y40587D01*
X1064228Y40451D01*
G03X1069284Y40156I2701J2816D01*
G01X1072448D01*
G03Y46378I2355J3111D01*
G01X1069284D01*
G03X1064635Y46424I-2356J-3111D01*
G02X1064000Y46747I-235J323D01*
G01Y50000D01*
X1067500Y53500D01*
Y72000D01*
X1072500Y77000D01*
Y126500D01*
X1093500Y147500D01*
Y208500D01*
X1097000Y212000D01*
X1105500D01*
X1109000Y208500D01*
Y6000D01*
X1106500Y3500D01*
X332000D01*
X331501Y3001D01*
X297499D01*
X296500Y4000D01*
Y66000D01*
X292500Y70000D01*
X249000D01*
X247500Y71500D01*
Y227000D01*
X243000Y231500D01*
X226435D01*
G02X226187Y232214I0J400D01*
G03X221843I-2172J2747D01*
G02X221595Y231500I-248J-314D01*
G01X116500D01*
X111500Y236500D01*
Y304000D01*
X105000Y310500D01*
X11500D01*
X3500Y318500D01*
Y970000D01*
X18500Y985000D01*
X106500D01*
X111000Y989500D01*
Y991000D01*
X111500Y991500D01*
X113500D01*
X114198Y990802D01*
Y988216D01*
X109574Y983591D01*
Y983180D01*
X109509Y983120D01*
G03X109095Y982605I1490J-1622D01*
G01X109082Y982582D01*
X98500Y972000D01*
X42500D01*
X42052Y971552D01*
X41784D01*
X9202Y938971D01*
Y860334D01*
G02X8713Y859944I-400J0D01*
G03X6670Y855980I-513J-2244D01*
G02X6641Y855358I-265J-299D01*
G03X8684Y851302I1359J-1858D01*
G02X9202Y850920I118J-382D01*
G01Y793918D01*
X9500Y793621D01*
Y791000D01*
X35000Y765500D01*
X37500D01*
X54186Y748814D01*
G02X54111Y748189I-282J-283D01*
G03X57273Y745027I1193J-1969D01*
G02X57898Y745102I342J-207D01*
G01X61132Y741868D01*
G02X61124Y741294I-283J-283D01*
G03X64378Y738040I1580J-1674D01*
G02X64952Y738048I291J-275D01*
G01X66000Y737000D01*
Y736391D01*
X65968Y736341D01*
G03X66000Y733450I2179J-1422D01*
G01Y723342D01*
X65988Y723309D01*
G03Y721713I2159J-798D01*
G01X66000Y721680D01*
Y712422D01*
X59477D01*
X59450Y712430D01*
G03X56594Y709574I-646J-2210D01*
G01X56602Y709547D01*
Y699720D01*
G03X57247Y698163I2202J0D01*
G01X58384Y697026D01*
Y695162D01*
G03X58134Y694303I1351J-859D01*
G01Y692703D01*
G03X58357Y691889I1602J1D01*
G01X58384Y691842D01*
Y691664D01*
X58357Y691617D01*
G03X58134Y690803I1379J-815D01*
G01Y689203D01*
G03X59734Y687602I1601J0D01*
G01X61336D01*
G03X62938Y689203I0J1602D01*
G01Y690803D01*
G03X62804Y691443I-1602J-1D01*
G01X62788Y691481D01*
Y692025D01*
X62804Y692063D01*
G03X62938Y692703I-1468J641D01*
G01Y694303D01*
G03X62804Y694943I-1602J-1D01*
G01X62788Y694981D01*
Y698850D01*
X61006Y700632D01*
Y708018D01*
X66982D01*
X67500Y707500D01*
X75000D01*
X92634Y689866D01*
Y689703D01*
G03X92884Y688844I1601J0D01*
G01Y685526D01*
X93271Y685139D01*
X93285Y685114D01*
G03X95950Y684010I2019J1106D01*
G01X95977Y684018D01*
X98482D01*
X109000Y673500D01*
X118000D01*
X127500Y664000D01*
X152500D01*
X160000Y656500D01*
Y629000D01*
X121161Y590161D01*
X121109Y590148D01*
G03X119456Y588495I576J-2229D01*
G01X119443Y588443D01*
X117500Y586500D01*
Y583000D01*
X121000Y579500D01*
X134427D01*
G03X134783Y578966I2075J997D01*
G02Y578434I-298J-266D01*
G03Y575366I1717J-1534D01*
G02Y574834I-298J-266D01*
G03Y571766I1717J-1534D01*
G02Y571234I-298J-266D01*
G03X134638Y568347I1717J-1533D01*
G02X134564Y567799I-324J-235D01*
G03X138302Y565986I1436J-1799D01*
G02X138968Y566282I400J-3D01*
G03X139331Y569983I1532J1718D01*
G02X138739Y570235I-203J345D01*
G03X138217Y571234I-2239J-534D01*
G02Y571766I298J266D01*
G03Y574834I-1717J1534D01*
G02Y575366I298J266D01*
G03Y578434I-1717J1534D01*
G02Y578966I298J266D01*
G03X138573Y579500I-1719J1531D01*
G01X155000D01*
X164000Y570500D01*
Y557435D01*
G02X163556Y557038I-400J1D01*
G03Y552462I-251J-2288D01*
G02X164000Y552065I44J-398D01*
G01Y542528D01*
X163438Y541965D01*
Y527035D01*
X164000Y526472D01*
Y506590D01*
G03Y506410I2200J-90D01*
G01Y459400D01*
X149700Y445100D01*
X50200D01*
X22500Y417400D01*
Y405921D01*
G02X21981Y405540I-400J1D01*
G03Y388160I-2709J-8690D01*
G02X22500Y387779I119J-382D01*
G01Y387500D01*
X24000Y386000D01*
X147500D01*
X186500Y347000D01*
Y328500D01*
X184500Y326500D01*
X181592D01*
G02X181301Y327174I0J400D01*
G03X177943Y330324I-1679J1575D01*
G01X177884Y330260D01*
X177514D01*
X177455Y330324D01*
G03X174097Y327174I-1679J-1575D01*
G02X173806Y326500I-291J-274D01*
G01X172235D01*
X172203Y326512D01*
G03X170294Y326991I-3475J-9804D01*
G02X170005Y327581I61J396D01*
G03X166314Y330274I-2012J1118D01*
G01X166255Y330210D01*
X165885D01*
X165826Y330274D01*
G03X162080Y327686I-1679J-1575D01*
G02X161721Y327110I-359J-176D01*
G01X158177D01*
X158153Y327282D01*
G03X153573Y326908I-2279J-326D01*
G02X153173Y326500I-400J-8D01*
G01X152000D01*
X146500Y321000D01*
Y298801D01*
G02X146305Y298601I-200J0D01*
G03Y293399I59J-2601D01*
G02X146500Y293199I-5J-200D01*
G01Y287613D01*
X144419Y285532D01*
G03X147128Y281872I1081J-2032D01*
G01X153000Y276000D01*
X249999D01*
X262998Y263000D01*
Y211500D01*
G02X262585Y211101I-400J0D01*
G03X262038Y211061I-85J-2601D01*
G02X261572Y211394I-71J394D01*
G03X257560Y208833I-2572J-394D01*
G02Y208167I-222J-333D01*
G03X261572Y205606I1440J-2167D01*
G02X262038Y205939I395J-61D01*
G03X264821Y207324I462J2561D01*
G02X265461Y207426I357J-181D01*
G01X281227Y191660D01*
G02X281058Y190994I-283J-283D01*
G03X280237Y186420I742J-2494D01*
G02Y185780I-240J-320D01*
G03X280544Y181421I1563J-2080D01*
G02X280557Y180729I-194J-350D01*
G03X284458Y178025I1343J-2229D01*
G02X284978Y178331I393J-73D01*
G03X286932Y183143I823J2469D01*
G02X286905Y183849I174J360D01*
G03X287689Y184549I-1305J2251D01*
G02X288293Y184593I321J-238D01*
G01X289000Y183887D01*
Y100164D01*
G03Y96836I2000J-1664D01*
G01Y89500D01*
X293000Y85500D01*
X297425D01*
G03X298300Y85298I876J1800D01*
G01X301200D01*
G03X302075Y85500I-1J2002D01*
G01X304500D01*
X305000Y86000D01*
X309000D01*
X310000Y85000D01*
Y83246D01*
G03X309368Y82368I1500J-1746D01*
G01X307500Y80500D01*
Y79641D01*
X307476Y79596D01*
G03X307290Y77854I2024J-1097D01*
G01X307298Y77827D01*
Y76387D01*
G03X307270Y73659I2202J-1387D01*
G01X307298Y73612D01*
Y73588D01*
X307345Y73541D01*
X307356Y73526D01*
G03X307500Y73336I2143J1475D01*
G01Y71000D01*
X311000Y67500D01*
X320500D01*
X322048Y65952D01*
Y64248D01*
X323752D01*
X324000Y64000D01*
X338500D01*
X343000Y68500D01*
X350298D01*
Y67552D01*
X350251Y67496D01*
G03X353749I1749J-1496D01*
G01X353702Y67552D01*
Y68500D01*
X372000D01*
X378000Y62500D01*
Y44000D01*
X376000Y42000D01*
X328000D01*
X327000Y41000D01*
Y25501D01*
G02X326254Y25301I-400J0D01*
G03X322277Y22050I-2253J-1301D01*
G02Y21450I-264J-300D01*
G03Y17550I1723J-1950D01*
G02Y16950I-264J-300D01*
G03X321572Y14063I1723J-1950D01*
G02X321106Y13530I-373J-144D01*
G03X318550Y12723I-607J-2530D01*
G02X317950I-300J264D01*
G03Y9277I-1950J-1723D01*
G02X318550I300J-264D01*
G03X322928Y11937I1950J1723D01*
G02X323394Y12470I373J144D01*
G03X325723Y16950I606J2530D01*
G02Y17550I264J300D01*
G03X326254Y18199I-1722J1951D01*
G02X327000Y17999I346J-200D01*
G01Y15500D01*
G37*
G36*
G01X185500Y742000D02*
X165500Y762000D01*
Y782500D01*
X177000Y794000D01*
X259500D01*
X275500Y778000D01*
Y726500D01*
X274000Y725000D01*
X272477D01*
G02X272275Y725745I1J400D01*
G03X267961I-2157J3664D01*
G02X267759Y725000I-203J-345D01*
G01X262477D01*
G02X262275Y725745I1J400D01*
G03X257961I-2157J3664D01*
G02X257759Y725000I-203J-345D01*
G01X255000D01*
X254000Y726000D01*
Y727674D01*
X254017Y727712D01*
G03Y731106I-3899J1697D01*
G01X254000Y731144D01*
Y731500D01*
X253452Y732048D01*
X253445Y732057D01*
G03X252766Y732736I-3327J-2648D01*
G01X252757Y732743D01*
X252500Y733000D01*
X252396D01*
X252347Y733030D01*
G03X247841Y733000I-2229J-3621D01*
G01X242395D01*
G03X237841I-2277J-3591D01*
G01X232395D01*
G03X227841I-2277J-3591D01*
G01X222395D01*
G03X217841I-2277J-3591D01*
G01X212395D01*
G03X207841I-2277J-3591D01*
G01X202395D01*
G03X197841I-2277J-3591D01*
G01X192395D01*
G03X188069Y733135I-2277J-3591D01*
G01X187938Y733062D01*
X185500Y735500D01*
Y737448D01*
G02X186263Y737616I400J-1D01*
G03Y741202I3855J1793D01*
G02X185500Y741370I-363J169D01*
G01Y742000D01*
G37*
G36*
G01X260424Y977922D02*
G03X262732Y978542I1754J-1922D01*
G02X262661Y978902I43J195D01*
G03X262793Y979000I-1484J2137D01*
G01X265000D01*
X267678Y981678D01*
Y989588D01*
G03X268159Y992126I-6457J2538D01*
G01Y997481D01*
X269178Y998500D01*
X278102D01*
Y992587D01*
X278178Y992511D01*
Y990500D01*
X281000Y987678D01*
Y964000D01*
X280000Y963000D01*
X277500D01*
X276000Y964500D01*
X275040D01*
X275008Y964511D01*
G03X274478Y964602I-532J-1511D01*
G01X272878D01*
G03X272348Y964511I2J-1602D01*
G01X272316Y964500D01*
X271040D01*
X271008Y964511D01*
G03X270478Y964602I-532J-1511D01*
G01X268878D01*
G03X268348Y964511I2J-1602D01*
G01X268316Y964500D01*
X266500D01*
X264500Y962500D01*
Y939000D01*
X262000Y936500D01*
X156000D01*
X152500Y940000D01*
Y964000D01*
X167500Y979000D01*
X259563D01*
G03X260291Y978594I1615J2040D01*
G02X260424Y977922I-136J-376D01*
G37*
G36*
G01X183000Y511500D02*
X179500Y515000D01*
Y532366D01*
G03Y534620I-2007J1127D01*
G01Y556000D01*
X187000Y563500D01*
Y580000D01*
X189000Y582000D01*
X213055D01*
X218055Y577000D01*
Y518443D01*
G02X217484Y518081I-400J0D01*
G03X215958Y513763I-985J-2081D01*
G02X216146Y513091I-95J-389D01*
G01X214555Y511500D01*
X183000D01*
G37*
G36*
G01X236091Y863735D02*
G02X236306Y863062I-71J-394D01*
G03X238362Y863718I1646J-1609D01*
G02X238147Y864391I71J394D01*
G03X235137Y867855I-1646J1609D01*
G02X234500Y868177I-237J322D01*
G01Y884000D01*
X236500Y886000D01*
X266000D01*
X268000Y884000D01*
Y871140D01*
G03Y868860I2000J-1140D01*
G01Y866640D01*
G03Y864360I2000J-1140D01*
G01Y859000D01*
X319500Y807500D01*
Y689140D01*
G03Y686860I2000J-1140D01*
G01Y669000D01*
X361100Y627400D01*
X373300D01*
X380000Y620700D01*
Y605000D01*
X377500Y602500D01*
X328108D01*
X277000Y653608D01*
Y787500D01*
X234500Y830000D01*
Y863823D01*
G02X235137Y864145I400J0D01*
G03X236091Y863735I1362J1855D01*
G37*
G36*
G01X307397Y102554D02*
X305645Y100802D01*
X305100D01*
G03X304165Y100500I1J-1602D01*
G01X302835D01*
G03X301900Y100802I-936J-1300D01*
G01X300500D01*
G03X299613Y100533I1J-1602D01*
G01X299563Y100500D01*
X299437D01*
X299387Y100533D01*
G03X298500Y100802I-888J-1333D01*
G01X297100D01*
G03X296213Y100533I1J-1602D01*
G01X296163Y100500D01*
X295641D01*
X295596Y100524D01*
G03X294775Y100786I-1098J-2023D01*
G01X294706Y100794D01*
X293500Y102000D01*
Y114000D01*
X294500Y115000D01*
X307000D01*
X308000Y114000D01*
Y104164D01*
G03X307401Y102631I2000J-1665D01*
G01X307397Y102554D01*
G37*
G36*
G01X310929Y218500D02*
X310429Y218000D01*
X305429D01*
X300929Y222500D01*
Y237000D01*
X303429Y239500D01*
X309429D01*
X310929Y238000D01*
Y218500D01*
G37*
G36*
G01X313929Y218000D02*
X312730Y219198D01*
Y219900D01*
G03X312467Y220719I-1402J2D01*
G01X312429Y220771D01*
Y221229D01*
X312467Y221281D01*
G03X312730Y222100I-1139J817D01*
G01Y222900D01*
G03X312429Y223768I-1402J0D01*
G01Y239500D01*
X311429Y240500D01*
X310128D01*
X309927Y240702D01*
X304728D01*
X304429Y241000D01*
Y245500D01*
X304929Y246000D01*
X317929D01*
X318929Y245000D01*
Y218500D01*
X318429Y218000D01*
X313929D01*
G37*
G36*
G01X391926Y262199D02*
G03X387800Y263685I-1826J1401D01*
G02X387415Y263300I-400J15D01*
G03X386074Y259193I85J-2300D01*
G01Y252409D01*
X387951Y250532D01*
X387934Y250430D01*
G03X388079Y249047I2566J-430D01*
G02X387707Y248500I-372J-147D01*
G01X318929D01*
X317929Y247500D01*
X303929D01*
X301929Y249500D01*
Y267000D01*
X302000D01*
Y286500D01*
X306000Y290500D01*
X310738D01*
X310770Y290489D01*
G03X311300Y290398I532J1511D01*
G01X312700D01*
G03X312962Y290420I-3J1602D01*
G01X313063Y290437D01*
X315500Y288000D01*
X319000D01*
X320000Y287000D01*
Y273500D01*
X324500Y269000D01*
X363500D01*
X379000Y284500D01*
X387706D01*
X387932Y284274D01*
X407209D01*
X417909Y273574D01*
X419426D01*
X420448Y272552D01*
X420393Y272427D01*
G03X423548Y269452I2107J-926D01*
G01X425880Y267120D01*
X425856Y267012D01*
G03X430395Y266316I2244J-512D01*
G01X430409Y266500D01*
X435000D01*
X435074Y266426D01*
Y262390D01*
X432184Y259500D01*
X421500D01*
X417601Y255601D01*
X417518Y255602D01*
G03X414898Y252982I-18J-2602D01*
G01X414899Y252899D01*
X410926Y248926D01*
X408715D01*
X408289Y248500D01*
X398517D01*
X391926Y255091D01*
Y255321D01*
X392010Y255381D01*
G03X391926Y259676I-1510J2119D01*
G01Y262199D01*
G37*
G36*
G01X330500Y15000D02*
X329000Y16500D01*
Y39000D01*
X330500Y40500D01*
X397500D01*
X402500Y35500D01*
Y27048D01*
X402336Y27018D01*
G03Y20226I617J-3396D01*
G01X402500Y20196D01*
Y16500D01*
X401000Y15000D01*
X391746D01*
G03X388254I-1746J-1500D01*
G01X386746D01*
G03X383254I-1746J-1500D01*
G01X330500D01*
G37*
G36*
G01X320500Y117000D02*
X319500Y118000D01*
Y124500D01*
X320500Y125500D01*
X325251D01*
X325278Y125492D01*
G03X326580I651J2208D01*
G01X326607Y125500D01*
X335500D01*
X336500Y124500D01*
Y118000D01*
X335500Y117000D01*
X320500D01*
G37*
G36*
G01X417630Y213879D02*
Y214630D01*
X418900Y215900D01*
X418912D01*
X419763Y215048D01*
X421400D01*
Y213682D01*
X421235Y213318D01*
X420788Y212872D01*
G03X420463Y212384I1063J-1060D01*
G01X420447Y212347D01*
X420300Y212200D01*
Y210800D01*
X420700Y210400D01*
X421333D01*
X421364Y210389D01*
G03X422912Y210748I486J1421D01*
G01X423743Y211580D01*
X424129Y212429D01*
X424600Y212900D01*
X425700D01*
X426300Y212300D01*
Y204700D01*
X426867Y204133D01*
X426882Y204092D01*
G03X427421Y203553I847J308D01*
G01X427462Y203538D01*
X427500Y203500D01*
X427682D01*
G03X427729Y203498I62J899D01*
G01X429001D01*
X429500Y203000D01*
Y198500D01*
X429000Y198000D01*
X428095D01*
X428040Y198043D01*
G03X424818I-1611J-2043D01*
G01X424763Y198000D01*
X424000D01*
X422180Y199820D01*
Y199952D01*
X422049D01*
X421400Y200600D01*
X414200D01*
X412200Y198600D01*
X405900D01*
X404680Y199820D01*
Y199952D01*
X404549D01*
X404300Y200200D01*
X398700D01*
X398451Y199952D01*
X398178D01*
Y199678D01*
X396700Y198200D01*
X393200D01*
X392500Y198900D01*
Y209900D01*
X392352Y210048D01*
Y210180D01*
X392220D01*
X391500Y210900D01*
X386900D01*
X386300Y210300D01*
Y203900D01*
X386700Y203500D01*
X386800D01*
X388000Y202300D01*
Y195900D01*
X387600Y195500D01*
X385729D01*
X384929Y194700D01*
Y192500D01*
X384429Y192000D01*
X383482D01*
X382931Y192552D01*
X382878D01*
X381929Y193500D01*
X379429D01*
X378929Y193000D01*
Y189000D01*
X378557Y188628D01*
G02X377990Y188630I-283J283D01*
G03X376459Y189382I-1849J-1830D01*
G02X376108Y189776I49J397D01*
G03X375950Y190434I-1502J-13D01*
G01X375929Y190476D01*
Y192199D01*
X375950Y192241D01*
G03Y193583I-1344J671D01*
G01X375929Y193625D01*
Y195055D01*
G03Y199945I-889J2445D01*
G01Y203500D01*
X373429Y206000D01*
Y213000D01*
X372958Y213470D01*
Y213594D01*
X371429Y215123D01*
Y217500D01*
X342429D01*
X332929Y208000D01*
X331429D01*
X329929Y209500D01*
Y212887D01*
X340542Y223500D01*
X367429D01*
X371429Y227500D01*
X380876D01*
G03X383384I1254J2280D01*
G01X390929D01*
X391929Y226500D01*
Y217500D01*
X392200Y217229D01*
Y217100D01*
X392500Y216800D01*
X392766D01*
X392809Y216777D01*
G03X394199I695J1332D01*
G01X394242Y216800D01*
X396200D01*
X396858Y216142D01*
Y215862D01*
X397500Y215219D01*
Y211900D01*
X398800Y210600D01*
X398912D01*
X398963Y210566D01*
G03X400643I840J1244D01*
G01X400694Y210600D01*
X400800D01*
X401800Y211600D01*
Y212700D01*
X402000Y212900D01*
X403313D01*
X404614Y211599D01*
X404625Y211538D01*
G03X406589Y210389I1477J272D01*
G01X406621Y210400D01*
X409000D01*
X410700Y212100D01*
Y214576D01*
X410706Y214600D01*
G03Y215330I-1457J365D01*
G01X410700Y215354D01*
Y215600D01*
X411400Y216300D01*
X412973D01*
X413458Y215816D01*
Y215544D01*
X413800Y215201D01*
Y211200D01*
X414400Y210600D01*
X414660D01*
X414711Y210566D01*
G03X416391I840J1244D01*
G01X416442Y210600D01*
X416700D01*
X417400Y211300D01*
Y213278D01*
G03X417630Y213879I-671J601D01*
G37*
G36*
G01X382526Y177097D02*
X381429Y176000D01*
X379593D01*
G03X376784Y176336I-1664J-2000D01*
G01X376655Y176274D01*
X376429Y176500D01*
Y182000D01*
X378929Y184500D01*
X383929D01*
X384429Y184000D01*
Y179000D01*
X384053Y178624D01*
X383974Y178621D01*
G03X382529Y177176I56J-1501D01*
G01X382526Y177097D01*
G37*
G36*
G01X427200Y154100D02*
X426600Y153500D01*
X423500D01*
X423000Y154000D01*
X421624D01*
G03X418861Y154029I-1405J-2190D01*
G01X418813Y154000D01*
X418429D01*
X414929Y150500D01*
Y150185D01*
G03X414052Y148720I622J-1367D01*
G01X414058Y148629D01*
X413475Y148046D01*
X413373Y148064D01*
G03X410334Y145686I-444J-2564D01*
G01X410320Y145500D01*
X408429D01*
X407929Y146000D01*
Y153000D01*
X406929Y154000D01*
X386429D01*
X385929Y154500D01*
Y158600D01*
X384900Y159629D01*
Y162600D01*
X385200Y162900D01*
X387100D01*
X387800Y162200D01*
Y160500D01*
X388800Y159500D01*
X396929D01*
X397929Y158500D01*
X423300D01*
X424000Y159200D01*
Y162100D01*
X424500Y162600D01*
X426100D01*
X426743Y161957D01*
X426709Y161843D01*
G03X427200Y160252I1440J-427D01*
G01Y154100D01*
G37*
G36*
G01X386400Y188298D02*
X388000D01*
G03X388902Y189200I0J902D01*
G01Y190800D01*
G03X388000Y191702I-902J0D01*
G01X386682D01*
X385557Y192826D01*
Y192910D01*
G03X385445Y193480I-1502J1D01*
G01X385430Y193517D01*
Y194330D01*
X386099Y194998D01*
X387808D01*
X388502Y195692D01*
Y202508D01*
X387008Y204002D01*
X386908D01*
X386802Y204108D01*
Y209502D01*
X387699Y210398D01*
X391292D01*
X391998Y209692D01*
Y198692D01*
X392064Y198627D01*
Y198364D01*
X392929Y197500D01*
X396929D01*
X397270Y197841D01*
X397301Y197856D01*
G03X398008Y198563I-648J1355D01*
G01X398023Y198594D01*
X398929Y199500D01*
X404200D01*
X405700Y198000D01*
X414429D01*
X415929Y199500D01*
X421429D01*
X421929Y199000D01*
Y195000D01*
X421141Y194212D01*
X421119Y194199D01*
G03X420566Y193637I757J-1297D01*
G01X420429Y193500D01*
Y193306D01*
X420423Y193281D01*
G03Y192523I1453J-379D01*
G01X420429Y192498D01*
Y192000D01*
X421429Y191000D01*
Y188500D01*
X420429Y187500D01*
Y187005D01*
X420423Y186980D01*
G03Y186226I1453J-377D01*
G01X420429Y186201D01*
Y185500D01*
X421429Y184500D01*
Y183000D01*
X419929Y181500D01*
Y179500D01*
X421429Y178000D01*
Y176000D01*
X420429Y175000D01*
Y174407D01*
X420423Y174382D01*
G03Y173628I1453J-377D01*
G01X420429Y173603D01*
Y172500D01*
X421429Y171500D01*
Y169145D01*
X421305Y169094D01*
G03X420423Y167328I571J-1389D01*
G01X420429Y167303D01*
Y167000D01*
X421429Y166000D01*
X421458D01*
X421929Y165529D01*
Y164000D01*
X421914Y163986D01*
X423545Y162355D01*
X423498Y162308D01*
Y161479D01*
G03Y161353I1501J-63D01*
G01Y159698D01*
X423300Y159500D01*
X413259D01*
G03X411543I-858J-1233D01*
G01X406960D01*
G03X405244I-858J-1233D01*
G01X398429D01*
X396929Y161000D01*
X389429D01*
X389414Y161014D01*
X388886D01*
X388400Y161500D01*
Y162900D01*
X387700Y163600D01*
X384800D01*
X384200Y164200D01*
Y165700D01*
X384800Y166300D01*
X386700D01*
X386731Y166290D01*
G03X387679I474J1425D01*
G01X387710Y166300D01*
X388029D01*
X388565Y166836D01*
G02X389165Y166798I283J-283D01*
G03X389545Y168980I1189J917D01*
G02X388929Y169317I-216J337D01*
G01Y177000D01*
X388707Y177222D01*
X388700Y177295D01*
G03X387335Y178660I-1496J-131D01*
G01X387262Y178667D01*
X385429Y180500D01*
Y186005D01*
X385444Y186042D01*
G03Y187184I-1389J571D01*
G01X385429Y187221D01*
Y188031D01*
G02X386004Y188390I400J-1D01*
G03X386400Y188298I397J810D01*
G37*
G36*
G01X392555Y433500D02*
X391055Y435000D01*
Y443500D01*
X391555Y444000D01*
X396555D01*
X397283Y443272D01*
X397295Y443215D01*
G03X399883Y442000I1760J385D01*
G01X403055D01*
X405055Y440000D01*
Y434000D01*
X404555Y433500D01*
X395817D01*
X395785Y433511D01*
G03X395255Y433602I-532J-1511D01*
G01X393855D01*
G03X393325Y433511I2J-1602D01*
G01X393293Y433500D01*
X392555D01*
G37*
G36*
G01X386000Y938500D02*
X385794Y938706D01*
X385786Y938775D01*
G03X385000Y940246I-2286J-276D01*
G01Y947000D01*
X386000Y948000D01*
X390598D01*
G03X391421Y946932I2402J1000D01*
G01X391500Y946872D01*
Y946287D01*
G03X390698Y944900I800J-1388D01*
G01Y943500D01*
G03X392300Y941898I1602J0D01*
G01X393700D01*
G03X394230Y941989I-2J1602D01*
G01X394262Y942000D01*
X395738D01*
X395770Y941989D01*
G03X396300Y941898I532J1511D01*
G01X397700D01*
G03X398230Y941989I-2J1602D01*
G01X398262Y942000D01*
X399738D01*
X399770Y941989D01*
G03X400300Y941898I532J1511D01*
G01X401700D01*
G03X402230Y941989I-2J1602D01*
G01X402262Y942000D01*
X403738D01*
X403770Y941989D01*
G03X404300Y941898I532J1511D01*
G01X405700D01*
G03X406230Y941989I-2J1602D01*
G01X406262Y942000D01*
X407738D01*
X407770Y941989D01*
G03X408300Y941898I532J1511D01*
G01X409700D01*
G03X410230Y941989I-2J1602D01*
G01X410262Y942000D01*
X411738D01*
X411770Y941989D01*
G03X412300Y941898I532J1511D01*
G01X413700D01*
G03X414230Y941989I-2J1602D01*
G01X414262Y942000D01*
X415738D01*
X415770Y941989D01*
G03X416300Y941898I532J1511D01*
G01X417602D01*
X417980Y941520D01*
Y938991D01*
X417490Y938500D01*
X386000D01*
G37*
G36*
G01X423278Y822000D02*
X418778D01*
X416278Y824500D01*
Y865000D01*
X417278Y866000D01*
X423278D01*
X424278Y865000D01*
Y823000D01*
X423278Y822000D01*
G37*
G36*
G01X473961Y156000D02*
G02X473569Y156480I0J400D01*
G03X473602Y156800I-1569J323D01*
G01Y158200D01*
G03X472781Y159598I-1601J0D01*
G02X472681Y160218I195J349D01*
G03X473102Y161300I-1180J1082D01*
G01Y162700D01*
G03X471500Y164302I-1602J0D01*
G01X470100D01*
G03X468673Y163426I1J-1602D01*
G01X467407D01*
G03X465288Y164281I-1807J-1426D01*
G02X465064Y164445I-27J198D01*
G03X464477Y165692I-2564J-445D01*
G01X464429Y165748D01*
Y166453D01*
G02X464983Y166822I400J0D01*
G03X465600Y166698I618J1478D01*
G01X467000D01*
G03X468602Y168300I0J1602D01*
G01Y169700D01*
G03X467000Y171302I-1602J0D01*
G01X465600D01*
G03X464983Y171178I1J-1602D01*
G02X464429Y171547I-154J369D01*
G01Y173453D01*
G02X464983Y173822I400J0D01*
G03X465600Y173698I618J1478D01*
G01X467000D01*
G03X468602Y175300I0J1602D01*
G01Y176700D01*
G03X467000Y178302I-1602J0D01*
G01X465600D01*
G03X464851Y178116I0J-1601D01*
G02X464592Y178181I-93J177D01*
G03X464429Y178396I-1913J-1281D01*
G01Y182500D01*
X465688Y183759D01*
G03X468621Y183957I1322J2241D01*
G01X468676Y184000D01*
X469442D01*
X469481Y183850D01*
G03X472430Y181934I2519J650D01*
G01X472532Y181951D01*
X472992Y181490D01*
X473409D01*
G03X477420Y183582I1807J1426D01*
G02X477642Y184064I383J116D01*
G03X478602Y185531I-641J1467D01*
G01Y186931D01*
G03X478511Y187461I-1602J-2D01*
G01X478500Y187493D01*
Y188952D01*
X478515Y188988D01*
G03X478632Y189591I-1484J601D01*
G01Y190994D01*
G03X478500Y191629I-1601J-2D01*
G01Y191700D01*
X479500Y192700D01*
X483500D01*
X484429Y191771D01*
Y157500D01*
X483605Y156676D01*
X483545Y156664D01*
G03X482407Y156000I383J-1964D01*
G01X473961D01*
G37*
G36*
G01X469756Y309400D02*
G03X468986Y310769I-1602J0D01*
G01X468255Y311500D01*
X463555D01*
X463055Y312000D01*
Y317000D01*
X464005Y317950D01*
X466605D01*
X466755Y318100D01*
X470655D01*
X472328Y319774D01*
X472849D01*
X474302Y321227D01*
Y329124D01*
X474055Y329371D01*
Y331000D01*
X477055D01*
X478055Y330000D01*
Y320700D01*
X476055Y318700D01*
Y311400D01*
X476604Y310852D01*
Y310648D01*
X476806D01*
X478055Y309400D01*
Y300500D01*
X477055Y299500D01*
X470707D01*
G03X469603Y300058I-1552J-1700D01*
G01X469544Y300070D01*
X468555Y301058D01*
Y306443D01*
X468688Y306490D01*
G03X469756Y308000I-533J1510D01*
G01Y309400D01*
G37*
G36*
G01X482990Y319751D02*
G03X484288Y317135I965J-1151D01*
G01X484395Y317160D01*
X487500Y314055D01*
Y311500D01*
X486300Y310300D01*
X478155D01*
X477055Y311400D01*
Y318100D01*
X478555Y319600D01*
Y320491D01*
X478556Y320492D01*
Y322423D01*
X478557Y322427D01*
G03Y322647I-2600J110D01*
G01X478556Y322651D01*
Y324879D01*
X478572Y324916D01*
G03X478624Y325183I-649J265D01*
G01Y325983D01*
G03X478572Y326250I-701J2D01*
G01X478556Y326287D01*
Y327279D01*
X478572Y327316D01*
G03X478624Y327583I-649J265D01*
G01Y328383D01*
G03X478572Y328650I-701J2D01*
G01X478556Y328687D01*
Y330208D01*
X478555Y330209D01*
Y330900D01*
X478955Y331300D01*
X481055D01*
X481455Y330900D01*
Y328100D01*
X481405Y328050D01*
Y321950D01*
X483015Y320340D01*
G02X482990Y319751I-283J-283D01*
G37*
G36*
G01X485045Y352492D02*
X485073Y352500D01*
X486750D01*
G03X488159Y352345I849J1239D01*
G03X489616Y352878I-212J2837D01*
G02X490197Y352753I234J-324D01*
G03X492970Y353809I1303J747D01*
G02X493361Y354292I391J83D01*
G01X496076D01*
G03X497054Y354379I4J5497D01*
G01X497157Y354398D01*
X500055Y351500D01*
Y332900D01*
X499355Y332200D01*
X493555D01*
X493155Y332600D01*
Y334600D01*
X492255Y335500D01*
X491943D01*
X491918Y335507D01*
G03X491154I-382J-1453D01*
G01X491129Y335500D01*
X484069D01*
X484044Y335507D01*
G03X483280I-382J-1453D01*
G01X483255Y335500D01*
X482555D01*
X481274Y336780D01*
Y338565D01*
X480787Y339053D01*
G03X478266Y337637I-1062J-1062D01*
G01X478272Y337614D01*
Y337000D01*
X476555D01*
Y340000D01*
X477555Y341000D01*
Y342137D01*
X477556Y342139D01*
Y343736D01*
X477579Y343779D01*
G03X477656Y344100I-624J320D01*
G01Y344900D01*
G03X477578Y345223I-701J2D01*
G01X477555Y345267D01*
Y352500D01*
X478555Y353500D01*
X481555D01*
X482555Y352500D01*
X482811D01*
X482860Y352469D01*
G03X484225Y352347I801J1270D01*
G03X485045Y352492I-266J3893D01*
G37*
G36*
G01X479055Y374500D02*
X478055Y375500D01*
Y379884D01*
G02X478722Y380182I400J0D01*
G03X479597Y379803I1004J1118D01*
G01X479670Y379797D01*
X479969Y379498D01*
X481791D01*
X481834Y379476D01*
G03X482155Y379398I322J624D01*
G01X482955D01*
G03X483656Y380100I0J701D01*
G01Y381100D01*
G03X482955Y381802I-702J0D01*
G01X482155D01*
G03X481834Y381724I1J-702D01*
G01X481791Y381702D01*
X481179D01*
X481130Y381831D01*
G03X478722Y382418I-1405J-531D01*
G02X478055Y382716I-267J298D01*
G01Y384000D01*
X476055Y386000D01*
X470555D01*
X469555Y387000D01*
Y401068D01*
X471385Y402898D01*
X471955D01*
G03X472656Y403600I0J701D01*
G01Y404400D01*
G03X471955Y405102I-702J0D01*
G01X470473D01*
X470238Y404867D01*
G02X469555Y405149I-283J282D01*
G01Y409000D01*
X469384Y409171D01*
X469371Y409224D01*
G03X469285Y409473I-1457J-364D01*
G03X468348Y411555I-3871J-490D01*
G03X468176Y411741I-2949J-2555D01*
G01X468035Y411882D01*
G02X467943Y411986I776J779D01*
G02X467716Y412654I873J669D01*
G01Y416160D01*
X468055Y416500D01*
X470055D01*
X472055Y418500D01*
X475555D01*
X476055Y419000D01*
Y423000D01*
X476224Y423169D01*
X476268Y423184D01*
G03X477211Y424127I-480J1423D01*
G01X477226Y424171D01*
X477555Y424500D01*
X482155D01*
X482185Y424336D01*
G03X484724Y425669I1477J271D01*
G01X488055Y429000D01*
X500555D01*
X505055Y424500D01*
Y422051D01*
G02X504380Y421760I-400J0D01*
G03X504160Y419407I-1033J-1090D01*
G02X504733Y419251I216J-337D01*
G03X505055Y418816I1430J722D01*
G01Y416718D01*
G03Y414024I867J-1347D01*
G01Y412000D01*
X504055Y411000D01*
Y410735D01*
G02X503590Y410341I-400J1D01*
G03X502285Y407797I-243J-1482D01*
G01X502834Y407248D01*
X504055D01*
Y406799D01*
G02X503590Y406404I-400J0D01*
G03Y403440I-243J-1482D01*
G02X504055Y403045I65J-395D01*
G01Y398925D01*
G02X503590Y398530I-400J0D01*
G03Y395566I-243J-1482D01*
G02X504055Y395171I65J-395D01*
G01Y394102D01*
X500655D01*
G03X499954Y393400I0J-701D01*
G01Y392600D01*
G03X500655Y391898I702J0D01*
G01X504055D01*
Y391051D01*
G02X503590Y390656I-400J0D01*
G03Y387692I-243J-1482D01*
G02X504055Y387297I65J-395D01*
G01Y383177D01*
G02X503590Y382782I-400J0D01*
G03X501850Y381428I-243J-1482D01*
G01X501844Y381355D01*
X501591Y381102D01*
X499155D01*
G03X498454Y380400I0J-701D01*
G01Y379600D01*
G03X499155Y378898I702J0D01*
G01X500720D01*
G02X501003Y378216I0J-400D01*
G01X498491Y375704D01*
X492962D01*
G02X492662Y376369I0J400D01*
G03X490410I-1126J994D01*
G02X490110Y375704I-300J-265D01*
G01X488568D01*
G03X485222Y374500I1J-5253D01*
G01X479055D01*
G37*
G36*
G01X479929Y123500D02*
X478929Y124500D01*
Y128500D01*
X481628Y131198D01*
X482400D01*
G03X482887Y131286I-2J1402D01*
G01X482921Y131298D01*
X484008D01*
X484042Y131286D01*
G03X484529Y131198I489J1314D01*
G01X485329D01*
G03X485816Y131286I-2J1402D01*
G01X485850Y131298D01*
X505630D01*
X505929Y131000D01*
Y125000D01*
X504429Y123500D01*
X479929D01*
G37*
G36*
G01X509328Y135702D02*
Y134298D01*
G03X509418Y133770I1601J1D01*
G01X509429Y133738D01*
Y133000D01*
X508929Y132500D01*
X486197D01*
G03X485329Y132802I-869J-1100D01*
G01X484529D01*
G03X483710Y132538I0J-1402D01*
G01X483658Y132500D01*
X483271D01*
X483219Y132538D01*
G03X482400Y132802I-819J-1138D01*
G01X481628D01*
X479929Y134500D01*
Y138823D01*
X479937Y138850D01*
G03X480002Y139300I-1537J452D01*
G01Y140700D01*
G03X479937Y141150I-1602J-2D01*
G01X479929Y141177D01*
Y141514D01*
X480140D01*
X480150Y141513D01*
G03X482545Y142585I279J2587D01*
G02X482818Y142635I162J-116D01*
G03X483929Y142298I1112J1665D01*
G01X487129D01*
G03X489078Y143845I0J2001D01*
G01X489114Y144000D01*
X498265D01*
G03X501593I1664J2000D01*
G01X508929D01*
X509429Y143500D01*
Y136262D01*
X509418Y136230D01*
G03X509328Y135702I1511J-529D01*
G37*
G36*
G01X483929Y151500D02*
X483429Y152000D01*
Y154801D01*
X484628Y156000D01*
X485929D01*
Y157138D01*
X485940Y157170D01*
G03X486030Y157700I-1511J529D01*
G01Y159300D01*
G03X485940Y159830I-1601J1D01*
G01X485929Y159862D01*
Y164638D01*
X485940Y164670D01*
G03X486030Y165200I-1511J529D01*
G01Y166800D01*
G03X485940Y167330I-1601J1D01*
G01X485929Y167362D01*
Y171138D01*
X485940Y171170D01*
G03X486030Y171700I-1511J529D01*
G01Y173300D01*
G03X485940Y173830I-1601J1D01*
G01X485929Y173862D01*
Y177638D01*
X485940Y177670D01*
G03X486030Y178200I-1511J529D01*
G01Y179800D01*
G03X485940Y180330I-1601J1D01*
G01X485929Y180362D01*
Y182000D01*
X486929Y183000D01*
X500429D01*
X501929Y181500D01*
Y155500D01*
X501570Y155141D01*
G02X501006Y155139I-283J283D01*
G03X497180Y154144I-1616J-1639D01*
G01X497138Y154000D01*
X492929D01*
X490429Y151500D01*
X483929D01*
G37*
G36*
G01X498278Y830000D02*
X491778D01*
X490278Y831500D01*
Y849000D01*
X490778Y849500D01*
X497778D01*
X499778Y847500D01*
Y831500D01*
X498278Y830000D01*
G37*
G36*
G01X504000Y865017D02*
X498983Y860000D01*
X490678D01*
X490178Y860500D01*
Y862500D01*
X490678Y863000D01*
X497500D01*
X500000Y865500D01*
Y867437D01*
G03Y867563I-1500J63D01*
G01Y870500D01*
X498000Y872500D01*
X494678D01*
X494589Y872589D01*
X491911D01*
X491500Y873000D01*
Y887000D01*
X492500Y888000D01*
X503000D01*
X504000Y887000D01*
Y865017D01*
G37*
G36*
G01X513555Y333000D02*
X511555Y331000D01*
X504055D01*
X503055Y332000D01*
Y340500D01*
X501055Y342500D01*
Y356500D01*
X502055Y357500D01*
X512055D01*
X513555Y356000D01*
Y333000D01*
G37*
G36*
G01X603000Y211400D02*
G02X603415Y211800I400J0D01*
G03X604606Y215904I85J2200D01*
G02Y216596I201J346D01*
G03X603225Y220685I-1106J1904D01*
G01X603213Y220683D01*
X603000D01*
Y221000D01*
X602000Y222000D01*
Y229000D01*
X603500Y230500D01*
X612000D01*
X613000Y229500D01*
Y195000D01*
X596000Y178000D01*
X581500D01*
X555000Y151500D01*
X534452D01*
Y152011D01*
X534519Y152071D01*
G03X531481I-1519J1729D01*
G01X531548Y152011D01*
Y151500D01*
X529429D01*
X525159Y147230D01*
X525139Y147218D01*
G03X524270Y146341I1361J-2218D01*
G01X522929Y145000D01*
Y135200D01*
X522758Y135175D01*
G03X520969Y134052I370J-2576D01*
G01X520303D01*
X518751Y132500D01*
X511429D01*
X510929Y133000D01*
Y144756D01*
G03X511582Y145653I-1729J1945D01*
G01X514628Y148698D01*
X515329D01*
G03X516930Y150298I0J1601D01*
G01Y151700D01*
G03X516886Y152075I-1601J2D01*
G01X516880Y152098D01*
Y155880D01*
X527500Y166500D01*
X543000D01*
X560214Y183714D01*
X560307Y183706D01*
G03X562794Y186193I193J2294D01*
G01X562786Y186286D01*
X571500Y195000D01*
X590000D01*
X591821Y196821D01*
X591879Y196833D01*
G03X593667Y198621I-466J2254D01*
G01X593679Y198679D01*
X603000Y208000D01*
Y211400D01*
G37*
G36*
G01X709748Y97000D02*
X687327Y74579D01*
G02X686645Y74839I-283J283D01*
G03X682464Y76436I-2448J-136D01*
G01X681548Y75521D01*
Y69048D01*
X666500Y54000D01*
X590248D01*
X587748Y56500D01*
Y81248D01*
X591500Y85000D01*
X598500D01*
X599500Y84000D01*
Y82847D01*
G02X598796Y82587I-400J0D01*
G03Y77649I-2891J-2469D01*
G02X599500Y77389I304J-260D01*
G01Y77000D01*
X603248Y73252D01*
Y73152D01*
G02X602571Y72863I-400J0D01*
G03Y67373I-2630J-2745D01*
G02X603248Y67084I277J-289D01*
G01Y61252D01*
X607000Y57500D01*
X646000D01*
X671458Y82958D01*
G02X672130Y82585I282J-283D01*
G03X676527Y83820I2536J-583D01*
G02X676813Y84500I286J280D01*
G01X686748D01*
X699248Y97000D01*
Y123000D01*
X695248Y127000D01*
Y128500D01*
X696248Y129500D01*
X697748D01*
X699748Y127500D01*
X700224D01*
X700277Y127461D01*
G03X703430Y127500I1551J2089D01*
G01X705513D01*
X705547Y127487D01*
G03X706116Y127382I570J1497D01*
G01X707798D01*
Y120502D01*
X708248Y120053D01*
Y119500D01*
X709646Y118102D01*
Y115700D01*
G03X709737Y115170I1602J2D01*
G01X709748Y115138D01*
Y97000D01*
G37*
G36*
G01X664769Y970269D02*
X664500Y970000D01*
Y962036D01*
X664496Y962016D01*
G03Y961084I2254J-466D01*
G01X664500Y961064D01*
Y710000D01*
X654500Y700000D01*
X627426D01*
Y705591D01*
X627196Y705821D01*
X627200Y705909D01*
G03X624426Y703874I-2200J91D01*
G01X624574Y703834D01*
Y700000D01*
X592500D01*
X588000Y704500D01*
Y977000D01*
X596000Y985000D01*
X717000D01*
X720500Y988500D01*
Y997000D01*
X722500Y999000D01*
X740500D01*
X742000Y997500D01*
Y982000D01*
X730000Y970000D01*
Y903500D01*
X723000Y896500D01*
X680500D01*
X676000Y901000D01*
Y965233D01*
X676229Y965462D01*
X676321Y965455D01*
G03X676103Y970017I180J2295D01*
G01X676000Y970000D01*
X674500Y971500D01*
X668435D01*
G03X664783Y970320I-1435J-1800D01*
G01X664769Y970269D01*
G37*
G36*
G01X640500Y423000D02*
X667568Y395932D01*
X667529Y395815D01*
G03X670815Y392529I2471J-815D01*
G01X670932Y392568D01*
X695500Y368000D01*
Y330500D01*
X692500Y327500D01*
X601500D01*
X600000Y329000D01*
Y408000D01*
X601798Y409798D01*
X622498D01*
X622699Y410000D01*
X623000D01*
X624000Y411000D01*
Y411301D01*
X624352Y411652D01*
Y412295D01*
X624375Y412339D01*
G03X624542Y413001I-1235J664D01*
G01Y413801D01*
G03X624375Y414463I-1402J-2D01*
G01X624352Y414507D01*
Y416695D01*
X624375Y416739D01*
G03X624542Y417401I-1235J664D01*
G01Y418201D01*
G03X624375Y418863I-1402J-2D01*
G01X624352Y418907D01*
Y421095D01*
X624375Y421139D01*
G03X624542Y421801I-1235J664D01*
G01Y422601D01*
G03X624375Y423263I-1402J-2D01*
G01X624352Y423307D01*
Y425495D01*
X624375Y425539D01*
G03X624542Y426201I-1235J664D01*
G01Y427001D01*
G03X624375Y427663I-1402J-2D01*
G01X624352Y427707D01*
Y429895D01*
X624375Y429939D01*
G03X624542Y430601I-1235J664D01*
G01Y431401D01*
G03X624375Y432063I-1402J-2D01*
G01X624352Y432107D01*
Y434295D01*
X624375Y434339D01*
G03X624542Y435001I-1235J664D01*
G01Y435801D01*
G03X624375Y436463I-1402J-2D01*
G01X624352Y436507D01*
Y440352D01*
X626500Y442500D01*
X636408D01*
G03X636592I92J2300D01*
G01X639000D01*
X640500Y441000D01*
Y433679D01*
G03Y433495I2300J-92D01*
G01Y423000D01*
G37*
G36*
G01X622938Y435001D02*
G03X623150Y434261I1402J1D01*
G01Y432141D01*
G03X622938Y431401I1190J-741D01*
G01Y430601D01*
G03X623150Y429861I1402J1D01*
G01Y427741D01*
G03X622938Y427001I1190J-741D01*
G01Y426201D01*
G03X623150Y425461I1402J1D01*
G01Y423341D01*
G03X622938Y422601I1190J-741D01*
G01Y421801D01*
G03X623150Y421061I1402J1D01*
G01Y418941D01*
G03X622938Y418201I1190J-741D01*
G01Y417401D01*
G03X623150Y416661I1402J1D01*
G01Y414541D01*
G03X622938Y413801I1190J-741D01*
G01Y413001D01*
G03X623150Y412261I1402J1D01*
G01Y412150D01*
X622000Y411000D01*
X602000D01*
X600000Y413000D01*
Y472000D01*
X601000Y473000D01*
X629000D01*
X630000Y472000D01*
Y448000D01*
X623150Y441150D01*
Y436541D01*
G03X622938Y435801I1190J-741D01*
G01Y435001D01*
G37*
G36*
G01X683500Y472000D02*
X663500Y492000D01*
X657794D01*
X657293Y492502D01*
X654973D01*
X654946Y492510D01*
G03X652748Y492000I-645J-2210D01*
G01X649500D01*
X648500Y493000D01*
Y502000D01*
X676500Y530000D01*
X751000D01*
X757500Y523500D01*
Y489000D01*
X756500Y488000D01*
X748553D01*
X747651Y488902D01*
X730091D01*
X723548Y482359D01*
Y482048D01*
X723500Y482000D01*
Y454046D01*
G03Y450554I1500J-1746D01*
G01Y329500D01*
X722500Y328500D01*
X702000D01*
X700500Y330000D01*
Y445500D01*
X695500Y450500D01*
X663000D01*
X661000Y452500D01*
Y460500D01*
X662512Y462012D01*
X667214D01*
Y462500D01*
X680500D01*
X683500Y465500D01*
Y472000D01*
G37*
G36*
G01X682501Y750500D02*
X680002Y753000D01*
Y773016D01*
X680000Y773017D01*
Y797000D01*
X676062Y800938D01*
Y851562D01*
X685000Y860500D01*
Y892500D01*
X687500Y895000D01*
X719500D01*
X724500Y890000D01*
Y818500D01*
X742500Y800500D01*
Y753500D01*
X739750Y750750D01*
X732770D01*
Y755284D01*
G02X733184Y755684I400J0D01*
G03X734144Y760113I84J2300D01*
G01Y767627D01*
X736370Y769853D01*
G03X733440Y770957I-870J2131D01*
G01X731292Y768809D01*
Y760748D01*
X729916Y759373D01*
Y750750D01*
X723750D01*
X723500Y750500D01*
X682501D01*
G37*
G36*
G01X700246Y128702D02*
X698246Y130702D01*
X697546D01*
X695000Y133248D01*
Y139500D01*
X709425Y153925D01*
X709496Y153933D01*
G03X711166Y154797I-280J2587D01*
G02X711766I300J-264D01*
G03X715666I1950J1723D01*
G02X716266I300J-264D01*
G03X720166I1950J1723D01*
G02X720766I300J-264D01*
G03X724666I1950J1723D01*
G02X725266I300J-264D01*
G03Y158243I1950J1723D01*
G02X724666I-300J264D01*
G03X720766I-1950J-1723D01*
G02X720166I-300J264D01*
G03X716266I-1950J-1723D01*
G02X715666I-300J264D01*
G03X713701Y159122I-1950J-1723D01*
G02X713500Y159322I-1J200D01*
G01Y178260D01*
G03Y180540I-2000J1140D01*
G01Y183000D01*
X722500Y192000D01*
X726500D01*
X810500Y276000D01*
X860000D01*
X862500Y273500D01*
Y251500D01*
X860000Y249000D01*
X818000D01*
X784000Y215000D01*
Y175500D01*
X743000Y134500D01*
X735699D01*
X735498Y134702D01*
X727546D01*
X724248Y138000D01*
X710248D01*
X707748Y135500D01*
Y131500D01*
X707798Y131450D01*
Y129050D01*
X707450Y128702D01*
X700246D01*
G37*
G36*
G01X762000Y337500D02*
X761000Y338500D01*
Y385000D01*
X760500Y385500D01*
Y407214D01*
G03X760504Y414024I-16604J3415D01*
G01X760500Y414044D01*
Y425500D01*
X757500Y428500D01*
X747000D01*
X746000Y429500D01*
Y437000D01*
X747000Y438000D01*
X775000D01*
X780500Y432500D01*
Y416286D01*
G03X780370Y413409I2100J-1536D01*
G01X780398Y413362D01*
Y412388D01*
X780370Y412341D01*
G03X780500Y409464I2230J-1341D01*
G01Y357500D01*
X776702Y353702D01*
X776502D01*
X774798Y351998D01*
Y351798D01*
X774500Y351500D01*
Y345000D01*
X776000Y343500D01*
X776301D01*
X776502Y343298D01*
X778045D01*
X778070Y343292D01*
G03X778424Y343246I356J1356D01*
G01X779224D01*
G03X779578Y343292I-2J1402D01*
G01X779603Y343298D01*
X781545D01*
X781570Y343292D01*
G03X781924Y343246I356J1356D01*
G01X782724D01*
G03X783078Y343292I-2J1402D01*
G01X783103Y343298D01*
X783702D01*
X784500Y342500D01*
Y338000D01*
X784000Y337500D01*
X762000D01*
G37*
G36*
G01X862809Y734000D02*
X898000D01*
X904000Y728000D01*
Y674500D01*
X928000Y650500D01*
X1013000D01*
X1014000Y649500D01*
Y624000D01*
X1012000Y622000D01*
X883500D01*
X881000Y619500D01*
X854000D01*
X851786Y621714D01*
X851794Y621807D01*
G03X849307Y624294I-2294J193D01*
G01X849214Y624286D01*
X811500Y662000D01*
X771000D01*
X767500Y665500D01*
Y721500D01*
X780000Y734000D01*
X808254D01*
G03X811746I1746J1500D01*
G01X858191D01*
X858205Y733816D01*
G03X862795I2295J184D01*
G01X862809Y734000D01*
G37*
G36*
G01X1211499Y3001D02*
X1210000Y4500D01*
Y166500D01*
X1211500Y168000D01*
X1232000D01*
X1235500Y164500D01*
Y161800D01*
G02X1234858Y161481I-400J0D01*
G03X1230316Y163012I-4541J-5970D01*
G01X1224016D01*
G03Y148010I0J-7501D01*
G01X1230316D01*
G03X1234858Y149541I1J7501D01*
G02X1235500Y149222I242J-319D01*
G01Y19500D01*
X1240000Y15000D01*
X1358500D01*
X1361508Y18008D01*
X1361607Y17993D01*
G03X1363146Y25220I539J3663D01*
G01X1363000Y25261D01*
Y25921D01*
X1363146Y25962D01*
G03Y33090I-1000J3564D01*
G01X1363000Y33131D01*
Y39888D01*
G02X1363733Y40109I400J0D01*
G03Y44537I3334J2214D01*
G02X1363000Y44758I-333J221D01*
G01Y48500D01*
X1375000Y60500D01*
Y121000D01*
X1394000Y140000D01*
Y153500D01*
X1392000Y155500D01*
Y208700D01*
G03Y224370I-15032J7835D01*
G01Y685000D01*
X1344500Y732500D01*
Y944500D01*
X1341000Y948000D01*
X1188500D01*
X1172000Y964500D01*
X1168406D01*
X1167705Y965202D01*
X1158183D01*
X1157482Y964500D01*
X1157000D01*
X1105000Y912500D01*
Y848500D01*
X1100500Y844000D01*
X1040500D01*
X1017202Y867298D01*
Y869531D01*
G03Y873469I-1702J1969D01*
G01Y884831D01*
X1031750Y899380D01*
X1031870Y899337D01*
G03X1034447Y902947I787J2163D01*
G01X1035500Y904000D01*
Y913000D01*
X1031000Y917500D01*
X1029411D01*
G03X1026021I-1695J-2716D01*
G01X1016000D01*
X1004000Y905500D01*
Y901000D01*
X1007000Y898000D01*
X1013000D01*
X1015500Y895500D01*
Y889000D01*
X1013000Y886500D01*
Y872222D01*
X1012993Y872196D01*
G03Y870804I2507J-696D01*
G01X1013000Y870778D01*
Y857500D01*
X1028000Y842500D01*
Y766000D01*
X1025000Y763000D01*
X873500D01*
X864000Y772500D01*
Y786000D01*
X860000Y790000D01*
X847500D01*
X842500Y785000D01*
Y741500D01*
X836202Y735202D01*
X779798D01*
X770500Y744500D01*
Y759878D01*
X770507Y759904D01*
G03Y761296I-2507J696D01*
G01X770500Y761322D01*
Y824000D01*
X772500Y826000D01*
X856500D01*
X867500Y837000D01*
Y888000D01*
X847500Y908000D01*
X804500D01*
X792500Y920000D01*
Y974683D01*
X793426Y975609D01*
Y983426D01*
X794500Y984500D01*
X902000D01*
X918500Y968000D01*
Y772500D01*
X922500Y768500D01*
X988000D01*
X992000Y772500D01*
Y968500D01*
X1008500Y985000D01*
X1380500D01*
X1397000Y968500D01*
Y98217D01*
G02X1396242Y98039I-400J0D01*
G03Y94481I-3585J-1779D01*
G02X1397000Y94303I358J-178D01*
G01Y80501D01*
G02X1396242Y80323I-400J0D01*
G03Y76765I-3585J-1779D01*
G02X1397000Y76587I358J-178D01*
G01Y61996D01*
G02X1396242Y61818I-400J0D01*
G03Y58260I-3585J-1779D01*
G02X1397000Y58082I358J-178D01*
G01Y44280D01*
G02X1396242Y44102I-400J0D01*
G03Y40544I-3585J-1779D01*
G02X1397000Y40366I358J-178D01*
G01Y5501D01*
X1394500Y3001D01*
X1211499D01*
G37*
G36*
G01X781500Y828500D02*
X765020Y844980D01*
Y856268D01*
G03Y860620I-1427J2176D01*
G01Y888492D01*
X765601Y889074D01*
X772693D01*
G03Y891926I1807J1426D01*
G01X765000D01*
Y935500D01*
X766500Y937000D01*
X770500D01*
X801500Y906000D01*
X846500D01*
X865500Y887000D01*
Y838500D01*
X855500Y828500D01*
X781500D01*
G37*
G36*
G01X761500Y956000D02*
X760500Y957000D01*
Y998700D01*
X761400Y999600D01*
X761500Y999500D01*
X788500D01*
X790500Y997500D01*
Y978000D01*
X789500Y977000D01*
X779000D01*
X778000Y976000D01*
Y974262D01*
X777989Y974230D01*
G03X777898Y973700I1511J-532D01*
G01Y972300D01*
G03X777920Y972038I1602J3D01*
G01X777937Y971937D01*
X777500Y971500D01*
X776000D01*
X774000Y969500D01*
Y957000D01*
X773000Y956000D01*
X761500D01*
G37*
G36*
G01X781924Y344850D02*
G03X780998Y344500I1J-1402D01*
G01X780150D01*
G03X779224Y344850I-927J-1052D01*
G01X778424D01*
G03X777550Y344544I0J-1401D01*
G01X777495Y344500D01*
X777000D01*
X776000Y345500D01*
Y351500D01*
X777000Y352500D01*
X783500D01*
X784500Y351500D01*
Y345500D01*
X783573Y344573D01*
X783440Y344653D01*
G03X782724Y344850I-717J-1205D01*
G01X781924D01*
G37*
G36*
G01X1104803Y762303D02*
X1102000Y759500D01*
X1086500D01*
X1073000Y746000D01*
X1058527D01*
G02X1058205Y746637I0J400D01*
G03X1054495I-1855J1363D01*
G02X1054173Y746000I-322J-237D01*
G01X1042291D01*
G03X1038125I-2083J-980D01*
G01X849000D01*
X845500Y749500D01*
Y784500D01*
X848500Y787500D01*
X860500D01*
X861500Y786500D01*
Y769000D01*
X869000Y761500D01*
X1056500D01*
X1067500Y772500D01*
Y778500D01*
X1065133Y780867D01*
X1065118Y780903D01*
G03X1063903Y782118I-2118J-903D01*
G01X1063867Y782133D01*
X1030500Y815500D01*
Y833000D01*
X1032500Y835000D01*
X1046000D01*
X1090867Y790133D01*
X1090882Y790097D01*
G03X1092097Y788882I2118J903D01*
G01X1092133Y788867D01*
X1095448Y785552D01*
X1095393Y785427D01*
G03X1098427Y782393I2107J-927D01*
G01X1098552Y782448D01*
X1105500Y775500D01*
Y764746D01*
G03X1104774Y762414I1500J-1746D01*
G01X1104803Y762303D01*
G37*
G36*
G01X858555Y285000D02*
X857055Y286500D01*
Y287635D01*
G02X857730Y287925I400J0D01*
G03Y292785I2309J2430D01*
G02X857055Y293075I-275J290D01*
G01Y295013D01*
X857190Y295059D01*
G03Y301401I-1086J3171D01*
G01X857055Y301447D01*
Y304853D01*
X857190Y304899D01*
G03Y311241I-1086J3171D01*
G01X857055Y311287D01*
Y313225D01*
G02X857730Y313515I400J0D01*
G03Y318375I2309J2430D01*
G02X857055Y318665I-275J290D01*
G01Y325000D01*
X859055Y327000D01*
X882798D01*
Y324898D01*
G03X886578Y322772I1702J-1398D01*
G02X887221Y322939I378J-132D01*
G03X890352Y326313I1529J1721D01*
G02X890631Y327000I279J287D01*
G01X1046500D01*
X1048000Y325500D01*
Y286500D01*
X1046500Y285000D01*
X1013722D01*
X1013696Y285007D01*
G03X1012304I-696J-2507D01*
G01X1012278Y285000D01*
X858555D01*
G37*
G36*
G01X880000Y442000D02*
X878500Y443500D01*
Y470500D01*
X881500Y473500D01*
Y618301D01*
X883998Y620798D01*
X896202D01*
X899500Y617500D01*
Y444500D01*
X897000Y442000D01*
X880000D01*
G37*
G36*
G01X1333000Y632447D02*
X1334261Y633709D01*
X1334352Y633703D01*
G03X1336155Y637600I148J2297D01*
G02X1336160Y638160I288J277D01*
G01X1346000Y648000D01*
Y679000D01*
X1348000Y681000D01*
X1377000D01*
X1388000Y670000D01*
Y586671D01*
G02X1387539Y586276I-400J0D01*
G03X1385018Y583800I-339J-2176D01*
G02X1384701Y583354I-396J-54D01*
G03X1383502Y582672I434J-2159D01*
G01X1383443Y582606D01*
X1383107D01*
X1383048Y582672D01*
G03X1382038Y583307I-1633J-1477D01*
G02X1381759Y583769I113J384D01*
G03X1378977Y582088I-2159J431D01*
G02X1379256Y581626I-113J-384D01*
G03X1383048Y579718I2159J-431D01*
G01X1383107Y579784D01*
X1383443D01*
X1383502Y579718D01*
G03X1387317Y581495I1633J1477D01*
G02X1387634Y581941I396J54D01*
G03X1387750Y581968I-441J2157D01*
G01X1387775Y581974D01*
X1388000D01*
Y493500D01*
X1380500Y486000D01*
X1363500D01*
G02X1363101Y486413I1J400D01*
G03X1357899I-2601J87D01*
G02X1357500Y486000I-400J-13D01*
G01X1357086D01*
Y486211D01*
X1357087Y486221D01*
G03X1351899Y486413I-2587J278D01*
G02X1351500Y486000I-400J-13D01*
G01X1349500D01*
X1343000Y479500D01*
X1268500D01*
X1252636Y463636D01*
G02X1252071Y463634I-284J282D01*
G03X1248816Y460379I-1621J-1634D01*
G02X1248814Y459814I-284J-281D01*
G01X1210000Y421000D01*
X1197793D01*
G02X1197421Y421547I0J400D01*
G03X1192579I-2421J953D01*
G02X1192207Y421000I-372J-147D01*
G01X1191700D01*
G02X1191300Y421415I0J400D01*
G03X1190106Y423519I-2300J85D01*
G01X1190081Y423533D01*
X1188912Y424702D01*
X1174173D01*
X1174146Y424710D01*
G03X1171397Y421563I-646J-2210D01*
G02X1171032Y421000I-365J-163D01*
G01X1004500D01*
X1001474Y417974D01*
X1001450Y417961D01*
G03X998574Y415085I3668J-6544D01*
G01X998561Y415061D01*
X967500Y384000D01*
X893500D01*
X890150Y387350D01*
Y399964D01*
X890000Y400113D01*
Y411500D01*
X893000Y414500D01*
X899500D01*
X908030Y423030D01*
X908063Y423045D01*
G03X911513Y425425I-4762J10593D01*
G01X921588Y435500D01*
X935500D01*
X944000Y444000D01*
X1206500D01*
X1214229Y451729D01*
G02X1214880Y451602I283J-283D01*
G03X1217898Y454620I2120J898D01*
G02X1217771Y455271I156J368D01*
G01X1254500Y492000D01*
X1329500D01*
X1329600Y492100D01*
X1333800D01*
X1345700Y504000D01*
X1364500D01*
X1374000Y513500D01*
Y532000D01*
X1368500Y537500D01*
X1357910D01*
G03X1353890I-2010J-900D01*
G01X1344000D01*
X1333000Y548500D01*
Y554532D01*
G02X1333563Y554897I400J0D01*
G03Y559103I937J2103D01*
G02X1333000Y559468I-163J365D01*
G01Y573508D01*
G02X1333684Y573790I400J0D01*
G03Y577034I1633J1622D01*
G02X1333000Y577316I-284J282D01*
G01Y632447D01*
G37*
G36*
G01X923500Y663000D02*
X906500Y680000D01*
Y739000D01*
X910000Y742500D01*
X1055500D01*
X1061000Y737000D01*
Y722321D01*
G02X1060482Y721939I-400J0D01*
G03Y717541I-682J-2199D01*
G02X1061000Y717159I118J-382D01*
G01Y697000D01*
X1027000Y663000D01*
X923500D01*
G37*
G36*
G01X1210700Y370500D02*
G02X1210300Y370915I0J400D01*
G03X1205700I-2300J85D01*
G02X1205300Y370500I-400J-15D01*
G01X1199177D01*
G02X1198855Y371137I0J400D01*
G03X1195145I-1855J1363D01*
G02X1194823Y370500I-322J-237D01*
G01X1177377D01*
X1177335Y370644D01*
G03X1172915I-2210J-644D01*
G01X1172873Y370500D01*
X1158840D01*
G03X1158026Y370779I-1140J-2000D01*
G02X1157685Y371223I56J396D01*
G03X1153155Y370989I-2285J277D01*
G02X1152765Y370500I-390J-89D01*
G01X983500D01*
X978500Y375500D01*
Y393000D01*
X982500Y397000D01*
X1038500D01*
X1043500Y392000D01*
X1160000D01*
X1164000Y388000D01*
X1167513D01*
X1167533Y387996D01*
G03X1168467I467J2254D01*
G01X1168487Y388000D01*
X1177500D01*
X1181500Y392000D01*
X1288000D01*
X1315000Y365000D01*
X1364500D01*
X1366500Y363000D01*
Y346000D01*
X1361500Y341000D01*
X1347000D01*
X1344005Y343995D01*
X1344046Y344114D01*
G03X1341114Y347046I-2173J759D01*
G01X1340995Y347005D01*
X1338500Y349500D01*
X1276754D01*
X1276727Y349668D01*
G03X1268627I-4050J-652D01*
G01X1268600Y349500D01*
X1238000D01*
X1217000Y370500D01*
X1210700D01*
G37*
G36*
G01X1016500Y39500D02*
X1014500Y41500D01*
Y54000D01*
X1015500Y55000D01*
X1024500D01*
X1026500Y57000D01*
Y65500D01*
X1027500Y66500D01*
X1029638D01*
X1029670Y66489D01*
G03X1030200Y66398I532J1511D01*
G01X1032800D01*
G03X1033330Y66489I-2J1602D01*
G01X1033362Y66500D01*
X1034638D01*
X1034670Y66489D01*
G03X1035200Y66398I532J1511D01*
G01X1037800D01*
G03X1038330Y66489I-2J1602D01*
G01X1038362Y66500D01*
X1039638D01*
X1039670Y66489D01*
G03X1040200Y66398I532J1511D01*
G01X1042800D01*
G03X1043330Y66489I-2J1602D01*
G01X1043362Y66500D01*
X1044638D01*
X1044670Y66489D01*
G03X1045200Y66398I532J1511D01*
G01X1047800D01*
G03X1048330Y66489I-2J1602D01*
G01X1048362Y66500D01*
X1049638D01*
X1049670Y66489D01*
G03X1050200Y66398I532J1511D01*
G01X1052800D01*
G03X1053330Y66489I-2J1602D01*
G01X1053362Y66500D01*
X1055000D01*
X1061500Y60000D01*
Y41500D01*
X1059500Y39500D01*
X1058912D01*
Y39816D01*
X1059013Y39874D01*
G03X1054657Y40213I-1927J3393D01*
G02X1054408Y39500I-249J-313D01*
G01X1016500D01*
G37*
G36*
G01X1014900Y56100D02*
X1014000Y57000D01*
Y75483D01*
X1016017Y77500D01*
X1022000D01*
X1022500Y77000D01*
Y57000D01*
X1021702Y56202D01*
X1015002D01*
X1014900Y56100D01*
G37*
G36*
G01X1015074Y80591D02*
X1011549Y77066D01*
X1011448Y77082D01*
G03X1011200Y77102I-252J-1582D01*
G01X1009800D01*
G03X1009270Y77011I2J-1602D01*
G01X1009238Y77000D01*
X1007862D01*
X1007830Y77011D01*
G03X1007685Y77054I-527J-1512D01*
G01X1007631Y77068D01*
X1007498Y77202D01*
X1003998D01*
X1003000Y78199D01*
Y85000D01*
X1004000Y86000D01*
X1014500D01*
X1015074Y85427D01*
Y80591D01*
G37*
G36*
G01X1028000Y68000D02*
X1027000Y69000D01*
Y111500D01*
X1029000Y113500D01*
X1052500D01*
X1054000Y112000D01*
Y81746D01*
G03X1053936Y78311I1500J-1746D01*
G01X1054000Y78252D01*
Y77748D01*
X1053936Y77689D01*
G03X1054000Y74254I1564J-1689D01*
G01Y68500D01*
X1053500Y68000D01*
X1028000D01*
G37*
G36*
G01X1179500Y235500D02*
X1192500Y222500D01*
X1206778D01*
X1206804Y222493D01*
G03X1208196I696J2507D01*
G01X1208222Y222500D01*
X1208500D01*
X1212500Y218500D01*
Y208500D01*
X1209000Y205000D01*
X1206500D01*
X1205500Y204000D01*
X1203000D01*
X1202000Y205000D01*
Y214000D01*
X1198000Y218000D01*
X1108500D01*
X1101500Y225000D01*
X1086112D01*
G03X1082888I-1612J-1500D01*
G01X1067000D01*
X1066927Y224926D01*
X1066909D01*
X1062983Y221000D01*
X1056534D01*
G03X1054579Y221547I-1534J-1716D01*
G01X1054475Y221528D01*
X1051000Y225003D01*
Y233500D01*
X1053000Y235500D01*
X1116500D01*
X1119000Y238000D01*
Y279879D01*
G02X1119578Y280237I400J0D01*
G03Y284363I1022J2063D01*
G02X1119000Y284721I-178J358D01*
G01Y287483D01*
X1121517Y290000D01*
X1138000D01*
X1140000Y288000D01*
Y237500D01*
X1142000Y235500D01*
X1179500D01*
G37*
G36*
G01X1076209Y685531D02*
X1075389Y686352D01*
X1072399D01*
X1072274Y686226D01*
X1072000Y686500D01*
Y736500D01*
X1072368Y736868D01*
G03X1073573Y738000I-868J2132D01*
G01X1079500D01*
X1079937Y737563D01*
X1079920Y737462D01*
G03X1079898Y737200I1580J-265D01*
G01Y735800D01*
G03X1079989Y735270I1602J2D01*
G01X1080000Y735238D01*
Y735000D01*
X1079000Y734000D01*
Y728762D01*
X1078989Y728730D01*
G03X1078898Y728200I1511J-532D01*
G01Y726800D01*
G03X1078989Y726270I1602J2D01*
G01X1079000Y726238D01*
Y724762D01*
X1078989Y724730D01*
G03X1078898Y724200I1511J-532D01*
G01Y722800D01*
G03X1078989Y722270I1602J2D01*
G01X1079000Y722238D01*
Y720762D01*
X1078989Y720730D01*
G03X1078898Y720200I1511J-532D01*
G01Y718800D01*
G03X1078989Y718270I1602J2D01*
G01X1079000Y718238D01*
Y716762D01*
X1078989Y716730D01*
G03X1078898Y716200I1511J-532D01*
G01Y714800D01*
G03X1078989Y714270I1602J2D01*
G01X1079000Y714238D01*
Y712762D01*
X1078989Y712730D01*
G03X1078898Y712200I1511J-532D01*
G01Y710800D01*
G03X1078989Y710270I1602J2D01*
G01X1079000Y710238D01*
Y708762D01*
X1078989Y708730D01*
G03X1078898Y708200I1511J-532D01*
G01Y706800D01*
G03X1078989Y706270I1602J2D01*
G01X1079000Y706238D01*
Y704762D01*
X1078989Y704730D01*
G03X1078898Y704200I1511J-532D01*
G01Y702800D01*
G03X1078989Y702270I1602J2D01*
G01X1079000Y702238D01*
Y700762D01*
X1078989Y700730D01*
G03X1078898Y700200I1511J-532D01*
G01Y698800D01*
G03X1078989Y698270I1602J2D01*
G01X1079000Y698238D01*
Y696762D01*
X1078989Y696730D01*
G03X1078898Y696200I1511J-532D01*
G01Y694800D01*
G03X1078989Y694270I1602J2D01*
G01X1079000Y694238D01*
Y692762D01*
X1078989Y692730D01*
G03X1078898Y692200I1511J-532D01*
G01Y690800D01*
G03X1078989Y690270I1602J2D01*
G01X1079000Y690238D01*
Y688762D01*
X1078989Y688730D01*
G03X1078898Y688200I1511J-532D01*
G01Y686800D01*
G03X1078920Y686538I1602J3D01*
G01X1078937Y686437D01*
X1078302Y685802D01*
X1077100D01*
G03X1076209Y685531I0J-1602D01*
G37*
G36*
G01X1168665Y792457D02*
G03X1167963Y793881I-1388J201D01*
G02X1167974Y794585I195J349D01*
G03X1166644Y794607I-645J1245D01*
G02X1166633Y793903I-195J-349D01*
G03X1165934Y793061I644J-1245D01*
G02X1165694Y792924I-192J57D01*
G03X1163011Y792000I-631J-2524D01*
G01X1161000D01*
X1160918Y792082D01*
X1160904Y792109D01*
G03X1159809Y793204I-2304J-1209D01*
G01X1159782Y793218D01*
X1159000Y794000D01*
X1155213D01*
X1155180Y794011D01*
G03X1155061Y794048I-475J-1319D01*
G02X1155059Y794435I50J194D01*
G03X1155943Y795142I-359J1355D01*
G02X1156646Y795154I355J-185D01*
G03X1156623Y796492I1220J690D01*
G02X1155920Y796480I-355J185D01*
G03X1154560Y797185I-1220J-690D01*
G02X1154345Y797342I-20J199D01*
G03X1151265Y799346I-2545J-542D01*
G02X1150787Y799796I-82J392D01*
G03X1149207Y798611I-1387J204D01*
G02X1149505Y798027I-55J-396D01*
G03X1149200Y796691I2295J-1227D01*
G02X1148702Y796287I-399J-17D01*
G03X1145502Y794235I-641J-2522D01*
G02X1145301Y794072I-197J37D01*
G03X1144854Y794009I-30J-1402D01*
G01X1144825Y794000D01*
X1142523D01*
X1142496Y794008D01*
G03X1142034Y794060I-386J-1348D01*
G01X1141945Y794055D01*
X1140500Y795500D01*
Y801500D01*
X1140280Y801720D01*
G02X1140590Y802402I282J283D01*
G03X1140700Y802398I113J1598D01*
G01X1143300D01*
G03X1144902Y804000I0J1602D01*
G01Y806600D01*
G03X1144212Y807917I-1602J0D01*
G01Y809500D01*
G03X1139808I-2202J0D01*
G01Y807930D01*
G03X1139098Y806600I891J-1330D01*
G01Y804000D01*
G03X1139362Y803120I1602J1D01*
G02X1139028Y802500I-334J-220D01*
G01X1117500D01*
X1110068Y809932D01*
Y813273D01*
X1118738Y821944D01*
G02X1119314Y821933I283J-283D01*
G03X1123210Y822856I1686J1567D01*
G01X1123252Y823000D01*
X1183500D01*
X1185500Y821000D01*
Y800500D01*
X1177000Y792000D01*
X1169060D01*
G02X1168665Y792457I1J400D01*
G37*
G36*
G01X1137983Y825500D02*
G02X1137700Y826183I0J400D01*
G01X1140921Y829404D01*
X1141009Y829400D01*
G03X1138900Y831509I91J2200D01*
G01X1138904Y831421D01*
X1134709Y827226D01*
X1122774D01*
X1113132Y836868D01*
G03X1111868Y838132I-2132J-868D01*
G01X1109500Y840500D01*
Y910500D01*
X1144000Y945000D01*
X1169500D01*
X1174000Y940500D01*
Y830500D01*
X1169000Y825500D01*
X1137983D01*
G37*
G36*
G01X1141497Y679333D02*
X1141482Y679380D01*
G03X1140978Y680291I-2483J-779D01*
G01X1140930Y680347D01*
Y680990D01*
X1141250Y681310D01*
X1142360D01*
X1142550Y681500D01*
Y683083D01*
X1142723Y683107D01*
G03X1143502Y684000I-122J893D01*
G01Y685600D01*
G03X1142723Y686493I-901J0D01*
G01X1142550Y686517D01*
Y692590D01*
X1141570Y693570D01*
Y702446D01*
G02X1142094Y702826I400J0D01*
G03X1145376Y706101I806J2474D01*
G02X1145485Y706345I190J61D01*
G03X1145698Y706460I-605J1375D01*
G01X1148785D01*
X1148820Y706304D01*
G03X1149700Y705598I880J195D01*
G01X1152300D01*
G03X1153180Y706304I0J901D01*
G01X1153215Y706460D01*
X1157597D01*
G03X1157743I73J1500D01*
G01X1161444D01*
G02X1161768Y705826I0J-400D01*
G03X1161598Y705300I732J-527D01*
G01Y703700D01*
G03X1162500Y702798I902J0D01*
G01X1164100D01*
G03X1165002Y703700I0J902D01*
G01Y704128D01*
X1165333Y704459D01*
G02X1165933Y704419I282J-283D01*
G03X1167048Y703578I2067J1581D01*
G01X1167087Y703563D01*
X1168390Y702260D01*
Y683546D01*
X1168098Y683255D01*
Y682200D01*
G03X1169265Y680585I1701J0D01*
G01X1169310Y680570D01*
X1170298Y679582D01*
Y678600D01*
G03X1170365Y678260I896J0D01*
G01X1170380Y678223D01*
Y678040D01*
X1170244Y677994D01*
G03X1168832Y676840I836J-2464D01*
G01X1162246D01*
X1162202Y676981D01*
G03X1162077Y677271I-1434J-446D01*
G01X1162052Y677317D01*
Y677720D01*
G03X1162502Y678500I-451J780D01*
G01Y680100D01*
G03X1161600Y681002I-902J0D01*
G01X1160000D01*
G03X1159098Y680100I0J-902D01*
G01Y678500D01*
G03X1159406Y677822I902J1D01*
G02X1159484Y677314I-264J-301D01*
G03X1159334Y676981I1284J-779D01*
G01X1159290Y676840D01*
X1158702D01*
Y678000D01*
G03X1157800Y678902I-902J0D01*
G01X1156200D01*
G03X1155298Y678000I0J-902D01*
G01Y676840D01*
X1154760D01*
X1153290Y678310D01*
X1152843D01*
X1152799Y678334D01*
G03X1151028Y678072I-709J-1324D01*
G01X1150461Y677504D01*
X1150345Y677542D01*
G03X1150068Y677586I-278J-858D01*
G01X1148468D01*
G03X1147663Y677090I0J-901D01*
G01X1147608Y676980D01*
X1146470D01*
Y678284D01*
G03X1145568Y679186I-902J0D01*
G01X1143968D01*
G03X1143066Y678284I0J-902D01*
G01Y678246D01*
G02X1142725Y678105I-200J0D01*
G01X1141497Y679333D01*
G37*
G36*
G01X1327500Y378000D02*
X1331500Y374000D01*
X1336000D01*
X1337500Y372500D01*
Y368000D01*
X1335702Y366202D01*
X1321298D01*
X1320500Y367000D01*
Y368778D01*
X1320507Y368804D01*
G03Y370196I-2507J696D01*
G01X1320500Y370222D01*
Y374778D01*
X1320507Y374804D01*
G03Y376196I-2507J696D01*
G01X1320500Y376222D01*
Y380778D01*
X1320507Y380804D01*
G03X1317982Y384102I-2507J696D01*
G01X1317899Y384101D01*
X1309000Y393000D01*
X1288699D01*
X1288498Y393202D01*
X1181002D01*
X1180801Y393000D01*
X1175500D01*
X1172000Y389500D01*
X1165500D01*
X1164000Y391000D01*
Y394000D01*
X1164867Y394867D01*
X1164903Y394882D01*
G03X1166000Y398140I-903J2118D01*
G01Y408500D01*
X1173000Y415500D01*
X1203500D01*
X1216750Y402250D01*
X1280408D01*
G03X1280592I92J2300D01*
G01X1288750D01*
X1289500Y401500D01*
Y400500D01*
X1290500Y399500D01*
X1294500D01*
X1295500Y400500D01*
Y402000D01*
X1295750Y402250D01*
X1322250D01*
X1327500Y397000D01*
Y378000D01*
G37*
G36*
G01X1158300Y707000D02*
X1156800Y708500D01*
Y709349D01*
G02X1157292Y709738I400J0D01*
G03X1158467Y712451I344J1462D01*
G02X1158455Y713110I221J334D01*
G03Y715552I-874J1221D01*
G02X1158467Y716211I233J325D01*
G03X1158464Y718717I-830J1252D01*
G02X1158465Y719385I221J334D01*
G03X1158416Y721930I-822J1257D01*
G02X1158344Y722200I102J172D01*
G03X1157950Y725291I-2264J1282D01*
G01Y726482D01*
X1158342Y726874D01*
X1158902D01*
X1163918Y731890D01*
G02X1164600Y731585I283J-283D01*
G03X1165371Y732813I1500J-86D01*
G02X1164776Y733163I-195J350D01*
G01Y733776D01*
X1165000Y734000D01*
Y737559D01*
G03X1166666Y740430I-900J2441D01*
G01X1166649Y740532D01*
X1168728Y742610D01*
Y745294D01*
X1168732Y745298D01*
Y750191D01*
X1168728Y750195D01*
Y759792D01*
X1159493Y769026D01*
X1158351D01*
X1157726Y769651D01*
Y770532D01*
G03X1157696Y770826I-1426J3D01*
G01X1157680Y770902D01*
G03X1157573Y771219I-1396J-295D01*
G01X1157554Y771260D01*
Y771554D01*
X1158000Y772000D01*
X1164722D01*
G03X1165781Y771399I1778J1900D01*
G02X1166036Y770854I-111J-384D01*
G03X1166319Y769308I1284J-564D01*
G02X1166249Y768690I-285J-281D01*
G03X1167900Y766431I753J-1183D01*
G02X1168469Y766374I257J-307D01*
G03X1169274Y770295I2031J1626D01*
G02X1168694Y770569I-188J353D01*
G03X1168062Y771479I-1374J-280D01*
G02X1168049Y771810I106J170D01*
G03X1168278Y772000I-1544J2094D01*
G01X1177500D01*
X1179500Y770000D01*
Y732500D01*
X1171000Y724000D01*
X1163500D01*
X1161500Y722000D01*
Y715789D01*
G03Y713011I2200J-1389D01*
G01Y708000D01*
X1160500Y707000D01*
X1158300D01*
G37*
G36*
G01X1246017Y750500D02*
X1242991Y753526D01*
X1225936D01*
X1225411Y753002D01*
X1200500D01*
X1199484Y751986D01*
X1195514D01*
X1190000Y757500D01*
X1188020D01*
X1187000Y758520D01*
Y759865D01*
G02X1187489Y760255I400J0D01*
G03X1186979Y764563I511J2245D01*
G02X1186402Y764922I-177J358D01*
G01Y765693D01*
G03X1186000Y769561I-1427J1807D01*
G01Y771036D01*
G03X1186288Y771332I-1499J1747D01*
G02X1186880Y771364I310J-252D01*
G03X1186712Y774450I1620J1636D01*
G02X1186120Y774418I-310J252D01*
G03X1186000Y774528I-1615J-1641D01*
G01Y779067D01*
G03Y782933I-1250J1933D01*
G01Y793500D01*
X1192500Y800000D01*
Y869000D01*
X1180000Y881500D01*
Y933500D01*
X1192500Y946000D01*
X1340000D01*
X1342000Y944000D01*
Y772000D01*
X1320500Y750500D01*
X1308192D01*
G03X1308008I-92J-2300D01*
G01X1246017D01*
G37*
G36*
G01X1193500Y237000D02*
X1194500Y238000D01*
X1205374D01*
G03X1209626I2126J1500D01*
G01X1243500D01*
X1246000Y235500D01*
Y217500D01*
X1245000Y216500D01*
X1215000D01*
X1214000Y217500D01*
Y220000D01*
X1210500Y223500D01*
X1209199D01*
X1208998Y223702D01*
X1195298D01*
X1193500Y225500D01*
Y237000D01*
G37*
G36*
G01X1229177Y200000D02*
X1229338Y199838D01*
X1229500Y200000D01*
X1269500D01*
X1335500Y266000D01*
X1372000D01*
X1377500Y260500D01*
Y253000D01*
X1373000Y248500D01*
X1342000D01*
X1278500Y185000D01*
X1244500D01*
X1242500Y187000D01*
X1203000D01*
X1202000Y188000D01*
Y199000D01*
X1203000Y200000D01*
X1207360D01*
G03X1209640I1140J2000D01*
G01X1215638D01*
X1215670Y199989D01*
G03X1216200Y199898I532J1511D01*
G01X1217800D01*
G03X1218330Y199989I-2J1602D01*
G01X1218362Y200000D01*
X1219138D01*
X1219170Y199989D01*
G03X1219700Y199898I532J1511D01*
G01X1221300D01*
G03X1221830Y199989I-2J1602D01*
G01X1221862Y200000D01*
X1229177D01*
G37*
G36*
G01X1209498Y203798D02*
X1213702Y208002D01*
Y208202D01*
X1214000Y208500D01*
X1237903D01*
G03X1239778Y207158I2097J949D01*
G01X1239849Y207151D01*
X1242500Y204500D01*
Y202500D01*
X1241500Y201500D01*
X1231128D01*
Y201652D01*
X1223226D01*
Y201500D01*
X1206500D01*
X1206000Y202000D01*
Y202801D01*
X1206998Y203798D01*
X1209498D01*
G37*
G36*
G01X1286000Y40500D02*
X1237500Y89000D01*
Y153352D01*
G03Y157670I-7184J2159D01*
G01Y184500D01*
X1238798Y185798D01*
X1242002D01*
X1244002Y183798D01*
X1244201D01*
X1244250Y183750D01*
X1252750D01*
X1262706Y173794D01*
X1262714Y173725D01*
G03X1264356Y171790I2286J275D01*
G01X1264500Y171748D01*
Y171252D01*
X1264356Y171210D01*
G03X1262701Y168888I644J-2210D01*
G02X1262109Y168517I-400J-20D01*
G03X1259083Y167775I-1109J-2017D01*
G02X1258417I-333J221D01*
G03Y165225I-1917J-1275D01*
G02X1259083I333J-221D01*
G03X1263299Y166612I1917J1275D01*
G02X1263891Y166983I400J20D01*
G03X1264356Y166790I1110J2017D01*
G01X1264500Y166748D01*
Y103000D01*
X1297500Y70000D01*
X1315900D01*
X1318042Y67858D01*
X1318056Y67806D01*
G03X1321306Y64556I4444J1194D01*
G01X1321358Y64542D01*
X1343500Y42400D01*
Y31832D01*
G03Y27220I2896J-2306D01*
G01Y23962D01*
G03X1343459Y19403I2896J-2306D01*
G01X1343500Y19349D01*
Y18400D01*
X1341600Y16500D01*
X1334500D01*
X1333000Y18000D01*
Y32800D01*
X1325300Y40500D01*
X1307700D01*
G02X1307448Y41211I0J400D01*
G03X1304552I-1448J1789D01*
G02X1304300Y40500I-252J-311D01*
G01X1286000D01*
G37*
G36*
G01X1261813Y651398D02*
X1264546Y648674D01*
X1265908D01*
X1266246Y648335D01*
Y645000D01*
X1260517D01*
X1259937Y645581D01*
X1259986Y645703D01*
G03X1260102Y646300I-1486J598D01*
G01Y647700D01*
G03X1259718Y648740I-1602J-1D01*
G02Y649260I304J260D01*
G03X1260102Y650300I-1218J1041D01*
G01Y651084D01*
X1260416Y651398D01*
X1261813D01*
G37*
G36*
G01X1260102Y661313D02*
X1260118Y661330D01*
Y661370D01*
X1260132Y661384D01*
X1263786D01*
X1264460Y662058D01*
X1265942D01*
X1266500Y661500D01*
Y656202D01*
X1260316D01*
X1260102Y656416D01*
Y657700D01*
G03X1260011Y658230I-1602J-2D01*
G01X1260000Y658262D01*
Y659738D01*
X1260011Y659770D01*
G03X1260102Y660300I-1511J532D01*
G01Y661313D01*
G37*
G36*
G01X1265000Y716017D02*
X1262909Y713926D01*
X1258074D01*
X1258000Y714000D01*
Y714238D01*
X1258011Y714270D01*
G03X1258102Y714800I-1511J532D01*
G01Y716200D01*
G03X1258080Y716462I-1602J-3D01*
G01X1258063Y716563D01*
X1258500Y717000D01*
X1260500D01*
X1260725Y717225D01*
X1260758Y717240D01*
G03X1261560Y718042I-658J1460D01*
G01X1261575Y718075D01*
X1262000Y718500D01*
X1264000D01*
X1265000Y717500D01*
Y716017D01*
G37*
G36*
G01X1272500Y689500D02*
X1272000Y690000D01*
Y699000D01*
X1272398Y699398D01*
X1273700D01*
G03X1274230Y699489I-2J1602D01*
G01X1274262Y699500D01*
X1275638D01*
X1275670Y699489D01*
G03X1276200Y699398I532J1511D01*
G01X1277602D01*
X1278000Y699000D01*
Y696312D01*
G03Y693288I1600J-1512D01*
G01Y690000D01*
X1277602Y689602D01*
X1276300D01*
G03X1275770Y689511I2J-1602D01*
G01X1275738Y689500D01*
X1272500D01*
G37*
G36*
G01X1271500Y716989D02*
X1271930Y717419D01*
X1272025Y717408D01*
G03X1272200Y717398I179J1592D01*
G01X1273800D01*
G03X1274330Y717489I-2J1602D01*
G01X1274362Y717500D01*
X1275738D01*
X1275770Y717489D01*
G03X1276300Y717398I532J1511D01*
G01X1277700D01*
G03X1277962Y717420I-3J1602D01*
G01X1278063Y717437D01*
X1278500Y717000D01*
Y708500D01*
X1278080Y708080D01*
X1277984Y708091D01*
G03X1277800Y708102I-187J-1591D01*
G01X1276200D01*
G03X1275670Y708011I2J-1602D01*
G01X1275638Y708000D01*
X1274262D01*
X1274230Y708011D01*
G03X1273700Y708102I-532J-1511D01*
G01X1272300D01*
G03X1272038Y708080I3J-1602D01*
G01X1271937Y708063D01*
X1271500Y708500D01*
Y716989D01*
G37*
G36*
G01X1333500Y323000D02*
X1336000Y320500D01*
X1378138D01*
X1378170Y320489D01*
G03X1378700Y320398I532J1511D01*
G01X1380300D01*
G03X1380830Y320489I-2J1602D01*
G01X1380862Y320500D01*
X1383238D01*
X1383270Y320489D01*
G03X1383800Y320398I532J1511D01*
G01X1385200D01*
G03X1385730Y320489I-2J1602D01*
G01X1385762Y320500D01*
X1386500D01*
X1387500Y319500D01*
Y283500D01*
X1386764Y282764D01*
G02X1386185Y282777I-283J282D01*
G03X1385000Y283302I-1186J-1077D01*
G01X1383600D01*
G03X1382992Y283182I0J-1602D01*
G01X1382869Y283131D01*
X1382602Y283398D01*
Y285100D01*
G03X1382511Y285630I-1602J-2D01*
G01X1382500Y285662D01*
Y286098D01*
G03X1383211Y290460I-1000J2402D01*
G03X1380360Y294000I-1711J1540D01*
G01X1377140D01*
G03X1373976Y290904I-1140J-2000D01*
G01X1374000Y290859D01*
Y290218D01*
X1373978Y290175D01*
G03X1374000Y287783I2322J-1175D01*
G01Y285165D01*
G03X1373998Y285100I1599J-82D01*
G01Y283998D01*
X1373280Y283280D01*
X1373184Y283291D01*
G03X1373000Y283302I-187J-1591D01*
G01X1371600D01*
G03X1370713Y283033I1J-1602D01*
G01X1370663Y283000D01*
X1370000D01*
X1361500Y291500D01*
X1352500D01*
X1351500Y290500D01*
Y283970D01*
X1347782D01*
Y283000D01*
X1322000D01*
X1306000Y299000D01*
Y321983D01*
X1307017Y323000D01*
X1333500D01*
G37*
G36*
G01X1330000Y18000D02*
X1318000D01*
Y34000D01*
X1330000D01*
Y18000D01*
G37*
%LPC*%
G75*
G36*
G01X708646Y83703D02*
G03X709312Y83696I335J218D01*
G02X709286Y81147I1904J-1294D01*
G03X708620Y81154I-335J-218D01*
G02X708646Y83703I-1904J1294D01*
G37*
G36*
G01X60691Y675422D02*
X87216D01*
X90716Y671922D01*
X92929D01*
G02X93704Y672122I775J-1402D01*
G01X95304D01*
G02X96906Y670520I0J-1602D01*
G01Y668920D01*
G02X95304Y667318I-1602J0D01*
G01X93704D01*
G02X92929Y667518I0J1602D01*
G01X90477D01*
X90450Y667510D01*
G02X87785Y668614I-646J2210D01*
G01X87771Y668639D01*
X85392Y671018D01*
X62515D01*
X61906Y670409D01*
Y668920D01*
G02X60304Y667318I-1602J0D01*
G01X58704D01*
G02X57929Y667518I0J1602D01*
G01X55977D01*
X55950Y667510D01*
G02Y671930I-646J2210D01*
G01X55977Y671922D01*
X57352D01*
Y672083D01*
X60691Y675422D01*
G37*
G36*
G01X51903Y658392D02*
G03X52212Y657792I345J-202D01*
G02X50039Y656706I-212J-2292D01*
G03X49745Y657313I-341J210D01*
G02X51903Y658392I255J2187D01*
G37*
G36*
G01X135179Y546252D02*
X147473D01*
X152592Y551371D01*
X152606Y551396D01*
G02X155731Y548271I2019J-1106D01*
G01X155706Y548257D01*
X149297Y541848D01*
X128000D01*
G02Y546252I0J2202D01*
G01X129821D01*
G03X130217Y546703I0J400D01*
G02X131225Y548917I2283J297D01*
G03Y549583I-221J333D01*
G02Y553417I1275J1917D01*
G03Y554083I-221J333D01*
G02X130783Y557534I1275J1917D01*
G03Y558066I-298J266D01*
G02X134217I1717J1534D01*
G03Y557534I298J-266D01*
G02X133775Y554083I-1717J-1534D01*
G03Y553417I221J-333D01*
G02Y549583I-1275J-1917D01*
G03Y548917I221J-333D01*
G02X134783Y546703I-1275J-1917D01*
G03X135179Y546252I396J-51D01*
G37*
G36*
G01X164909Y353198D02*
X164539D01*
X164480Y353134D01*
G02Y356284I-1679J1575D01*
G01X164539Y356220D01*
X164909D01*
X164968Y356284D01*
G02Y353134I1679J-1575D01*
G01X164909Y353198D01*
G37*
G36*
G01X153409D02*
X153039D01*
X152980Y353134D01*
G02Y356284I-1679J1575D01*
G01X153039Y356220D01*
X153409D01*
X153468Y356284D01*
G02Y353134I1679J-1575D01*
G01X153409Y353198D01*
G37*
G36*
G01X141409D02*
X141039D01*
X140980Y353134D01*
G02Y356284I-1679J1575D01*
G01X141039Y356220D01*
X141409D01*
X141468Y356284D01*
G02Y353134I1679J-1575D01*
G01X141409Y353198D01*
G37*
G36*
G01X129409D02*
X129039D01*
X128980Y353134D01*
G02Y356284I-1679J1575D01*
G01X129039Y356220D01*
X129409D01*
X129468Y356284D01*
G02Y353134I1679J-1575D01*
G01X129409Y353198D01*
G37*
G36*
G01X959907Y189789D02*
G03X959982Y189261I333J-222D01*
G02X956583Y188775I-1482J-1761D01*
G03X956508Y189303I-333J222D01*
G02X959907Y189789I1482J1761D01*
G37*
G36*
G01X253126Y156308D02*
X253167D01*
X253182Y156492D01*
G02Y153742I16896J-1375D01*
G01X253167Y153926D01*
X253126D01*
Y156308D01*
G37*
G36*
G01X1092156Y124988D02*
X1091766D01*
X1091707Y124925D01*
G02Y128075I-1679J1575D01*
G01X1091766Y128012D01*
X1092156D01*
X1092215Y128075D01*
G02Y124925I1679J-1575D01*
G01X1092156Y124988D01*
G37*
G36*
G01X730000Y106750D02*
Y103362D01*
X731323Y102038D01*
X731377Y102025D01*
G02X728223Y98871I-629J-2525D01*
G01X728210Y98925D01*
X724346Y102788D01*
Y103548D01*
X723096D01*
Y111452D01*
X729820D01*
G02X730916Y111886I1096J-1167D01*
G01X732516D01*
G02X733156Y111752I-1J-1602D01*
G01X733194Y111736D01*
X733738D01*
X733776Y111752D01*
G02X734416Y111886I641J-1468D01*
G01X736016D01*
G02X736656Y111752I-1J-1602D01*
G01X736694Y111736D01*
X738613D01*
G02Y107332I1387J-2202D01*
G01X736875D01*
G02X736016Y107082I-859J1351D01*
G01X734416D01*
G02X733602Y107305I1J1602D01*
G01X733555Y107332D01*
X733377D01*
X733330Y107305D01*
G02X732516Y107082I-815J1379D01*
G01X730916D01*
G02X730503Y107137I3J1602D01*
G03X730000Y106750I-103J-386D01*
G37*
G36*
G01X253126Y93316D02*
X253167D01*
X253182Y93500D01*
G02Y90750I16896J-1375D01*
G01X253167Y90934D01*
X253126D01*
Y93316D01*
G37*
G36*
G01X132879Y321367D02*
G02X130792Y321113I-756J-2490D01*
G03X130723Y321833I-204J344D01*
G02X132774Y322083I777J2167D01*
G03X132879Y321367I221J-333D01*
G37*
G36*
G01X797214Y165644D02*
G03X797140Y165024I211J-340D01*
G02X794286Y165364I-1640J-1616D01*
G03X794360Y165984I-211J340D01*
G02X797214Y165644I1640J1616D01*
G37*
G36*
G01X200766Y562593D02*
G02X200068Y564685I-2266J406D01*
G03X200734Y564907I272J293D01*
G02X201432Y562815I2266J-406D01*
G03X200766Y562593I-272J-293D01*
G37*
G36*
G01X313639Y273482D02*
G03X314238Y273415I329J228D01*
G02X313861Y270018I1762J-1915D01*
G03X313262Y270085I-329J-228D01*
G02X313639Y273482I-1762J1915D01*
G37*
G36*
G01X423169Y207970D02*
X424169D01*
Y206970D01*
X424229Y206900D01*
Y205900D01*
X423229D01*
Y206900D01*
X423169Y206970D01*
Y207970D01*
G37*
G36*
G01X407914Y201550D02*
X408914D01*
X409029Y201500D01*
X410029D01*
Y200500D01*
X409029D01*
X408914Y200550D01*
X407914D01*
Y201550D01*
G37*
G36*
G01X383728Y220502D02*
G02X384629Y221402I901J-1D01*
G01X386229D01*
G02X387130Y220500I-1J-902D01*
G01Y218900D01*
G02X386930Y218334I-901J0D01*
G01Y215088D01*
X386770Y214928D01*
Y214598D01*
G02X386648Y214146I-901J1D01*
G01X386620Y214099D01*
Y212252D01*
X385117Y210748D01*
G02X382993Y212872I-1062J1062D01*
G01X383618Y213496D01*
Y213977D01*
G02X383368Y214600I651J623D01*
G01Y216200D01*
G02X383826Y216985I902J0D01*
G01X383928Y217042D01*
Y218334D01*
G02X383728Y218900I701J566D01*
G01Y220502D01*
G37*
G36*
G01X378630Y207998D02*
G02X377729Y207098I-901J1D01*
G01X376129D01*
G02X375228Y208000I1J902D01*
G01Y209600D01*
G02X375428Y210166I901J0D01*
G01Y211605D01*
X375938Y212115D01*
Y213967D01*
G02X375688Y214590I651J623D01*
G01Y216192D01*
G02X376589Y217092I901J-1D01*
G01X378189D01*
G02X379090Y216190I-1J-902D01*
G01Y214588D01*
G02X378968Y214136I-901J1D01*
G01X378940Y214089D01*
Y212733D01*
G02X378818Y210748I-1184J-923D01*
G01X378430Y210361D01*
Y210170D01*
X378467Y210118D01*
G02X378630Y209602I-738J-517D01*
G01Y207998D01*
G37*
G36*
G01X419414Y156350D02*
X420414D01*
X420500Y156300D01*
X421500D01*
Y155300D01*
X420500D01*
X420414Y155350D01*
X419414D01*
Y156350D01*
G37*
G36*
G01X424340Y156600D02*
X425340D01*
Y155600D01*
X424340D01*
X423900Y155300D01*
X422900D01*
Y156300D01*
X423900D01*
X424340Y156600D01*
G37*
G36*
G01X395591Y181376D02*
X395938Y181723D01*
Y181932D01*
X396124Y182118D01*
X396048Y182250D01*
G02X395928Y182699I781J449D01*
G01Y184300D01*
G02X396027Y184713I902J2D01*
G01X396094Y184842D01*
X395940Y184997D01*
Y185205D01*
X395846Y185299D01*
G02X395563Y187705I808J1315D01*
G01X395898Y188040D01*
Y188248D01*
X396136Y188486D01*
Y188623D01*
X396114Y188651D01*
G02X395928Y189199I715J548D01*
G01Y190802D01*
G02X395973Y191082I901J-1D01*
G01X396011Y191199D01*
X395890Y191321D01*
Y191552D01*
X395591Y191850D01*
G02X397715Y193974I1062J1062D01*
G01X398892Y192796D01*
Y192565D01*
X399180Y192277D01*
Y191301D01*
X399208Y191254D01*
G02X399330Y190802I-779J-453D01*
G01Y189198D01*
G02X399222Y188772I-901J2D01*
G01Y187208D01*
X398984Y186970D01*
Y186762D01*
X398807Y186584D01*
X398942Y186449D01*
Y186241D01*
X399180Y186003D01*
Y184801D01*
X399208Y184754D01*
G02X399330Y184302I-779J-453D01*
G01Y182698D01*
G02X399208Y182246I-901J1D01*
G01X399180Y182199D01*
Y180927D01*
X398942Y180688D01*
Y180479D01*
X398776Y180314D01*
X398942Y180149D01*
Y179942D01*
X399180Y179703D01*
Y178301D01*
X399208Y178254D01*
G02X399330Y177802I-779J-453D01*
G01Y176198D01*
G02X399208Y175746I-901J1D01*
G01X399180Y175699D01*
Y174701D01*
X398892Y174412D01*
Y174130D01*
X398776Y174015D01*
X398892Y173900D01*
Y173666D01*
X399180Y173377D01*
Y171801D01*
X399208Y171754D01*
G02X399330Y171302I-779J-453D01*
G01Y169698D01*
G02X399208Y169246I-901J1D01*
G01X399180Y169199D01*
Y169128D01*
X398272Y168220D01*
X398928Y167563D01*
Y167329D01*
X399280Y166977D01*
Y166301D01*
X399308Y166254D01*
G02X399430Y165802I-779J-453D01*
G01Y164198D01*
G02X398529Y163298I-901J1D01*
G01X396929D01*
G02X396028Y164200I1J902D01*
G01Y165800D01*
G02X396031Y165879I901J5D01*
G01X396039Y165971D01*
X395926Y166085D01*
Y166319D01*
X395591Y166653D01*
G02X395152Y167713I1062J1061D01*
G01Y169346D01*
X395928Y170122D01*
Y171302D01*
G02X396132Y171872I901J-1D01*
G01X396178Y171927D01*
Y172133D01*
X395888Y172422D01*
Y172656D01*
X395591Y172953D01*
G02Y175077I1062J1062D01*
G01X395888Y175374D01*
Y175656D01*
X396018Y175786D01*
X395977Y175904D01*
G02X395928Y176200I852J293D01*
G01Y177800D01*
G02X396178Y178423I901J0D01*
G01Y178459D01*
X395938Y178698D01*
Y178905D01*
X395591Y179252D01*
G02Y181376I1062J1062D01*
G37*
G36*
G01X392329Y194400D02*
X391000Y195500D01*
Y196500D01*
X392000D01*
X393329Y195400D01*
Y194400D01*
X392329D01*
G37*
G36*
G01X419414Y161350D02*
Y162350D01*
X420414D01*
X420500Y162300D01*
X421500D01*
Y161300D01*
X420500D01*
X420414Y161350D01*
X419414D01*
G37*
G36*
G01X414528Y169698D02*
Y171302D01*
G02X414650Y171754I901J-1D01*
G01X414678Y171801D01*
Y172765D01*
X414489Y172953D01*
G02Y175077I1062J1062D01*
G01X414678Y175265D01*
Y175699D01*
X414650Y175746D01*
G02X414528Y176198I779J453D01*
G01Y177802D01*
G02X414650Y178254I901J-1D01*
G01X414678Y178301D01*
Y179101D01*
X414525Y179253D01*
G02Y181377I1062J1062D01*
G01X414678Y181529D01*
Y182199D01*
X414650Y182246D01*
G02X414528Y182698I779J453D01*
G01Y184302D01*
G02X414650Y184754I901J-1D01*
G01X414678Y184801D01*
Y185364D01*
X414489Y185552D01*
G02X414050Y186612I1062J1061D01*
G01Y189994D01*
X414528Y190472D01*
Y190802D01*
G02X414650Y191254I901J-1D01*
G01X414678Y191301D01*
Y191662D01*
X414489Y191850D01*
G02X416613Y193974I1062J1062D01*
G01X417680Y192906D01*
Y191423D01*
G02X417930Y190800I-651J-623D01*
G01Y189200D01*
G02X417212Y188317I-902J0D01*
G01X417052Y188284D01*
Y187236D01*
X417680Y186608D01*
Y184923D01*
G02X417930Y184300I-651J-623D01*
G01Y182700D01*
G02X417680Y182077I-901J0D01*
G01Y178423D01*
G02X417930Y177800I-651J-623D01*
G01Y176200D01*
G02X417680Y175577I-901J0D01*
G01Y171923D01*
G02X417930Y171300I-651J-623D01*
G01Y169700D01*
G02X417680Y169077I-901J0D01*
G01Y167721D01*
X417780Y167621D01*
Y166423D01*
G02X418030Y165800I-651J-623D01*
G01Y164198D01*
G02X417129Y163298I-901J1D01*
G01X415529D01*
G02X414628Y164200I1J902D01*
G01Y165800D01*
G02X414778Y166298I902J0D01*
G01Y166377D01*
X414513Y166641D01*
G02Y168765I1062J1062D01*
G01X414678Y168929D01*
Y169199D01*
X414650Y169246D01*
G02X414528Y169698I779J453D01*
G37*
G36*
G01X410530Y165802D02*
Y164198D01*
G02X409629Y163298I-901J1D01*
G01X408029D01*
G02X407128Y164200I1J902D01*
G01Y165802D01*
G02X407250Y166254I901J-1D01*
G01X407278Y166301D01*
Y167565D01*
X407178Y167665D01*
Y169199D01*
X407150Y169246D01*
G02X407028Y169698I779J453D01*
G01Y171302D01*
G02X407150Y171754I901J-1D01*
G01X407178Y171801D01*
Y175699D01*
X407150Y175746D01*
G02X407028Y176198I779J453D01*
G01Y177802D01*
G02X407150Y178254I901J-1D01*
G01X407178Y178301D01*
Y182199D01*
X407150Y182246D01*
G02X407028Y182698I779J453D01*
G01Y184302D01*
G02X407150Y184754I901J-1D01*
G01X407178Y184801D01*
Y188699D01*
X407150Y188746D01*
G02X407028Y189198I779J453D01*
G01Y190802D01*
G02X407150Y191254I901J-1D01*
G01X407178Y191301D01*
Y192962D01*
X408189Y193974D01*
G02X410313Y191850I1062J-1062D01*
G01X410180Y191718D01*
Y191427D01*
X410226Y191372D01*
G02X410430Y190802I-697J-571D01*
G01Y189200D01*
G02X410180Y188577I-901J0D01*
G01Y187807D01*
X410313Y187675D01*
G02Y185551I-1062J-1062D01*
G01X410180Y185419D01*
Y184923D01*
G02X410430Y184300I-651J-623D01*
G01Y182700D01*
G02X410180Y182077I-901J0D01*
G01Y181546D01*
X410350Y181377D01*
G02Y179253I-1062J-1062D01*
G01X410180Y179084D01*
Y178423D01*
G02X410430Y177800I-651J-623D01*
G01Y176200D01*
G02X410180Y175577I-901J0D01*
G01Y175209D01*
X410313Y175077D01*
G02Y172953I-1062J-1062D01*
G01X410180Y172821D01*
Y171923D01*
G02X410430Y171300I-651J-623D01*
G01Y169698D01*
G02X410226Y169128I-901J1D01*
G01X410180Y169073D01*
Y168909D01*
X410313Y168777D01*
G02X410336Y166677I-1062J-1062D01*
G01X410280Y166619D01*
Y166427D01*
X410326Y166372D01*
G02X410530Y165802I-697J-571D01*
G37*
G36*
G01X473348Y412924D02*
X473354Y412851D01*
X473556Y412648D01*
Y410764D01*
X473579Y410721D01*
G02X473656Y410400I-624J-320D01*
G01Y409600D01*
G02X472955Y408898I-701J-1D01*
G01X471955D01*
G02X471254Y409600I1J702D01*
G01Y410400D01*
G02X471331Y410721I701J1D01*
G01X471353Y410764D01*
Y411373D01*
X471235Y411426D01*
G02X473348Y412924I616J1370D01*
G37*
G36*
G01X489319Y411002D02*
X490951D01*
X491591Y410362D01*
X491664Y410356D01*
G02X490052Y408629I-128J-1497D01*
G01X490025Y408798D01*
X489319D01*
X489276Y408776D01*
G02X488955Y408698I-322J624D01*
G01X488155D01*
G02X487454Y409400I1J702D01*
G01Y410400D01*
G02X488155Y411102I701J1D01*
G01X488955D01*
G02X489276Y411024I-1J-702D01*
G01X489319Y411002D01*
G37*
G36*
G01X483790Y407362D02*
X483717Y407356D01*
X483359Y406998D01*
X481819D01*
X481776Y406976D01*
G02X481455Y406898I-322J624D01*
G01X480655D01*
G02X479954Y407600I1J702D01*
G01Y408600D01*
G02X480655Y409302I701J1D01*
G01X481455D01*
G02X481776Y409224I-1J-702D01*
G01X481819Y409202D01*
X482193D01*
X482238Y409338D01*
G02X483790Y407362I1424J-479D01*
G37*
G36*
G01X480217Y394998D02*
X479670Y395545D01*
X479597Y395551D01*
G02X481194Y397360I128J1497D01*
G01X481228Y397202D01*
X482291D01*
X482334Y397224D01*
G02X482655Y397302I322J-624D01*
G01X483455D01*
G02X484156Y396600I-1J-702D01*
G01Y395600D01*
G02X483455Y394898I-701J-1D01*
G01X482655D01*
G02X482334Y394976I1J702D01*
G01X482291Y394998D01*
X480217D01*
G37*
G36*
G01X489819Y395002D02*
X491203D01*
X491591Y394614D01*
X491664Y394608D01*
G02X490104Y392659I-128J-1497D01*
G01X490060Y392798D01*
X489819D01*
X489776Y392776D01*
G02X489455Y392698I-322J624D01*
G01X488655D01*
G02X487954Y393400I1J702D01*
G01Y394400D01*
G02X488655Y395102I701J1D01*
G01X489455D01*
G02X489776Y395024I-1J-702D01*
G01X489819Y395002D01*
G37*
G36*
G01X489319Y387002D02*
X491329D01*
X491591Y386740D01*
X491664Y386734D01*
G02X490144Y384674I-128J-1497D01*
G01X490093Y384798D01*
X489319D01*
X489276Y384776D01*
G02X488955Y384698I-322J624D01*
G01X488155D01*
G02X487454Y385400I1J702D01*
G01Y386400D01*
G02X488155Y387102I701J1D01*
G01X488955D01*
G02X489276Y387024I-1J-702D01*
G01X489319Y387002D01*
G37*
G36*
G01X497655Y404398D02*
X496655D01*
G02X495954Y405100I1J702D01*
G01Y405900D01*
G02X496031Y406221I701J1D01*
G01X496054Y406264D01*
Y406721D01*
X495418Y407356D01*
X495345Y407362D01*
G02X496970Y408987I128J1497D01*
G01X496976Y408914D01*
X497227Y408663D01*
G03X497910Y408927I283J282D01*
G02X498815Y407480I1500J-68D01*
G03X498256Y407113I-159J-367D01*
G01Y406264D01*
X498279Y406221D01*
G02X498356Y405900I-624J-320D01*
G01Y405100D01*
G02X497655Y404398I-701J-1D01*
G37*
G36*
G01X568672Y183096D02*
G03X569098Y183511I26J399D01*
G02X571400Y181300I2300J91D01*
G01X571317D01*
X571049Y181032D01*
X571066Y180930D01*
G02X568672Y183096I-2566J-430D01*
G37*
G36*
G01X605606Y202404D02*
G02X603394I-1106J-1904D01*
G03Y203096I-201J346D01*
G02X605606I1106J1904D01*
G03Y202404I201J-346D01*
G37*
G36*
G01X613702Y878498D02*
Y775002D01*
X611998Y773298D01*
X597502D01*
X595798Y775002D01*
Y879498D01*
X597502Y881202D01*
X610998D01*
X613702Y878498D01*
G37*
G36*
G01X678202Y368498D02*
Y353502D01*
X675498Y350798D01*
X623502D01*
X620798Y353502D01*
Y368998D01*
X623502Y371702D01*
X674998D01*
X678202Y368498D01*
G37*
G36*
G01X714870Y858408D02*
G03X714315Y858334I-240J-320D01*
G02X713880Y861592I-1815J1416D01*
G03X714435Y861666I240J320D01*
G02X714870Y858408I1815J-1416D01*
G37*
G36*
G01X849638Y261225D02*
G03X848972I-333J-221D01*
G02Y263775I-1917J1275D01*
G03X849638I333J221D01*
G02Y261225I1917J-1275D01*
G37*
G36*
G01X869788Y654929D02*
X877426Y647291D01*
Y633507D01*
G02X874574I-1426J-1807D01*
G01Y646109D01*
X867771Y652912D01*
X867679Y652905D01*
G02X869795Y655021I-179J2295D01*
G01X869788Y654929D01*
G37*
G36*
G01X1096143Y904633D02*
G03X1095563Y904478I-222J-333D01*
G02X1094780Y907413I-2063J1022D01*
G03X1095360Y907568I222J333D01*
G02X1096143Y904633I2063J-1022D01*
G37*
G36*
G01X1097691Y867871D02*
G02X1101450Y867723I1932J1252D01*
G02X1097691Y867871I-1950J-1723D01*
G37*
G36*
G01X900062Y314976D02*
G03X900210Y314458I358J-178D01*
G02X896938Y313524I-1210J-1958D01*
G03X896790Y314042I-358J178D01*
G02X900062Y314976I1210J1958D01*
G37*
G36*
G01X1345753Y590714D02*
G02X1343481I-1136J-2002D01*
G03Y591410I-197J348D01*
G02X1346619Y594548I1136J2002D01*
G03X1347315I348J197D01*
G02Y592276I2002J-1136D01*
G03X1346619I-348J-197D01*
G02X1345753Y591410I-2002J1136D01*
G03Y590714I197J-348D01*
G37*
G36*
G01X1360546Y625463D02*
G02X1355468Y625400I-2546J537D01*
G03X1354848Y625634I-389J-93D01*
G02X1351482Y626436I-1331J1878D01*
G03X1350934Y626599I-354J-187D01*
G02X1349255Y626380I-1116J2013D01*
G03X1348781Y626128I-98J-388D01*
G02X1344566Y625867I-2164J784D01*
G03X1343937Y625978I-356J-182D01*
G02X1344418Y628707I-1570J1684D01*
G03X1345047Y628596I356J182D01*
G02X1347179Y629144I1569J-1684D01*
G03X1347653Y629396I98J388D01*
G02X1351852Y629688I2164J-784D01*
G03X1352400Y629525I354J187D01*
G02X1352775Y629691I1116J-2014D01*
G03X1353026Y630194I-129J379D01*
G02X1355007Y633555I2474J806D01*
G03X1355273Y634154I-76J393D01*
G02X1359949Y634620I2227J1346D01*
G03X1360282Y634087I376J-136D01*
G02X1358238Y629585I-282J-2587D01*
G03X1357639Y629518I-270J-295D01*
G02X1357432Y629258I-2135J1487D01*
G03X1357766Y628591I297J-268D01*
G02X1360155Y627459I235J-2591D01*
G03X1360873Y627582I331J224D01*
G02X1361257Y625620I2227J-583D01*
G03X1360546Y625463I-320J-240D01*
G37*
G36*
G01X1211301Y438569D02*
G03X1211819Y438199I400J12D01*
G02X1210199Y435931I681J-2199D01*
G03X1209681Y436301I-400J-12D01*
G02X1211301Y438569I-681J2199D01*
G37*
G36*
G01X1248822Y475246D02*
G03X1248977Y474728I360J-175D01*
G02X1245728Y473754I-1177J-1978D01*
G03X1245573Y474272I-360J175D01*
G02X1248822Y475246I1177J1978D01*
G37*
G36*
G01X1381212Y596132D02*
G03X1380885Y595607I52J-397D01*
G02X1378513Y597083I-2085J-707D01*
G03X1378840Y597608I-52J397D01*
G02X1379448Y599948I2085J707D01*
G01X1379514Y600007D01*
Y600343D01*
X1379448Y600402D01*
G02X1378819Y601393I1477J1633D01*
G03X1378338Y601665I-383J-116D01*
G02X1376290Y605403I-538J2135D01*
G03X1376320Y605953I-274J291D01*
G02X1376353Y608848I1676J1429D01*
G03Y609381I-298J267D01*
G02X1376490Y612453I1643J1466D01*
G03X1376497Y612738I-137J146D01*
G02X1380213Y613712I1585J1528D01*
G03X1380760Y613245I387J-100D01*
G02X1382963Y609467I877J-2020D01*
G03X1382954Y608836I241J-319D01*
G02X1379945Y605640I-1376J-1719D01*
G03X1379394Y605681I-297J-268D01*
G02X1379369Y605660I-1429J1675D01*
G03X1379352Y605362I124J-157D01*
G02X1379906Y604442I-1552J-1562D01*
G03X1380387Y604170I383J116D01*
G02X1382459Y603615I538J-2135D01*
G03X1382993Y603594I279J287D01*
G02X1385990Y600377I1407J-1694D01*
G03Y599823I289J-277D01*
G02X1382923Y596667I-1590J-1523D01*
G03X1382388Y596670I-269J-296D01*
G02X1381212Y596132I-1464J1645D01*
G37*
G36*
G01X1359595Y617525D02*
G03X1360025Y617095I399J-31D01*
G02X1357905Y614975I175J-2295D01*
G03X1357475Y615405I-399J31D01*
G02X1359595Y617525I-175J2295D01*
G37*
G36*
G01X973674Y702882D02*
G02X972705Y700822I1326J-1882D01*
G03X972076Y701118I-399J-31D01*
G02X973045Y703178I-1326J1882D01*
G03X973674Y702882I399J31D01*
G37*
G36*
G01X1054508Y694126D02*
G02X1052196Y695282I-2008J-1126D01*
G03X1052492Y695874I-53J396D01*
G02X1052221Y697327I2008J1126D01*
G03X1051925Y697771I-396J57D01*
G02X1051072Y701805I575J2229D01*
G03X1051098Y702410I-248J314D01*
G02X1051650Y706144I1580J1674D01*
G03X1051624Y706871I-179J358D01*
G02X1050897Y710653I876J2129D01*
G03X1050919Y711204I-278J287D01*
G02X1054251Y711071I1729J1520D01*
G03X1054229Y710520I278J-287D01*
G02X1053528Y706940I-1729J-1520D01*
G03X1053554Y706213I179J-358D01*
G02X1054106Y702279I-876J-2129D01*
G03X1054080Y701674I248J-314D01*
G02X1054779Y699673I-1580J-1674D01*
G03X1055075Y699229I396J-57D01*
G02X1054804Y694718I-575J-2229D01*
G03X1054508Y694126I53J-396D01*
G37*
G36*
G01X1042355Y692683D02*
G02X1040465I-945J-1989D01*
G03Y693405I-172J361D01*
G02X1040261Y697273I945J1989D01*
G03Y697955I-208J341D01*
G02X1040151Y701640I1149J1878D01*
G03X1040142Y702302I-229J328D01*
G02X1039135Y703870I1268J1922D01*
G03X1038705Y704207I-395J-61D01*
G02X1038701Y708793I-205J2293D01*
G03X1039132Y709134I35J399D01*
G02X1042632Y706853I2278J-330D01*
G03Y706175I212J-339D01*
G02X1042678Y702302I-1222J-1951D01*
G03X1042669Y701640I220J-334D01*
G02X1042559Y697955I-1259J-1807D01*
G03Y697273I208J-341D01*
G02X1042355Y693405I-1149J-1879D01*
G03Y692683I172J-361D01*
G37*
G36*
G01X1168130Y231127D02*
G02Y232873I-2130J873D01*
G03X1168870I370J152D01*
G02Y231127I2130J-873D01*
G03X1168130I-370J-152D01*
G37*
G36*
G01X1134040Y807798D02*
G02X1132600Y806898I-1440J702D01*
G01X1130000D01*
G02X1128398Y808500I0J1602D01*
G01Y811100D01*
G02X1130000Y812702I1602J0D01*
G01X1132600D01*
G02X1133763Y812202I0J-1603D01*
G01X1135000D01*
G02Y807798I0J-2202D01*
G01X1134040D01*
G37*
G36*
G01X1122823Y807043D02*
X1122079Y806298D01*
X1121000D01*
G02X1120002Y810462I0J2202D01*
G01X1120030Y810477D01*
X1121755Y812202D01*
X1122337D01*
G02X1123500Y812702I1163J-1103D01*
G01X1126100D01*
G02X1127702Y811100I0J-1602D01*
G01Y808500D01*
G02X1126100Y806898I-1602J0D01*
G01X1123500D01*
G02X1122943Y806998I0J1601D01*
G01X1122823Y807043D01*
G37*
G36*
G01X1156702Y805500D02*
G02X1155100Y803898I-1602J0D01*
G01X1153500D01*
G02X1151898Y805500I0J1602D01*
G01Y807100D01*
G02X1152098Y807875I1602J0D01*
G01Y809610D01*
G02X1156502I2202J0D01*
G01Y807875D01*
G02X1156702Y807100I-1402J-775D01*
G01Y805500D01*
G37*
G36*
G01X1161100Y802398D02*
X1159500D01*
G02X1157898Y804000I0J1602D01*
G01Y805600D01*
G02X1158098Y806375I1602J0D01*
G01Y809610D01*
G02X1162502I2202J0D01*
G01Y806375D01*
G02X1162611Y806130I-1404J-771D01*
G03X1162989I189J66D01*
G02X1163098Y806375I1513J-526D01*
G01Y809610D01*
G02X1167502I2202J0D01*
G01Y806375D01*
G02X1167611Y806130I-1404J-771D01*
G03X1167989I189J66D01*
G02X1168098Y806375I1513J-526D01*
G01Y809610D01*
G02X1172502I2202J0D01*
G01Y806375D01*
G02X1172702Y805600I-1402J-775D01*
G01Y804000D01*
G02X1171100Y802398I-1602J0D01*
G01X1169500D01*
G02X1168140Y803155I1J1602D01*
G03X1167460I-340J-211D01*
G02X1166100Y802398I-1361J845D01*
G01X1164500D01*
G02X1163140Y803155I1J1602D01*
G03X1162460I-340J-211D01*
G02X1161100Y802398I-1361J845D01*
G37*
G36*
G01X1167432Y857685D02*
G02X1166734Y855593I1568J-1686D01*
G03X1166068Y855815I-394J-71D01*
G02X1166766Y857907I-1568J1686D01*
G03X1167432Y857685I394J71D01*
G37*
G36*
G01X1146100Y684100D02*
X1147100D01*
Y683100D01*
X1146468Y681784D01*
X1145468D01*
Y682784D01*
X1146100Y684100D01*
G37*
G36*
G01X1144968Y687584D02*
X1145968D01*
X1147100Y686500D01*
Y685500D01*
X1146100D01*
X1144968Y686584D01*
Y687584D01*
G37*
G36*
G01X1165968Y688584D02*
Y687584D01*
X1166000Y687200D01*
Y686200D01*
X1165000D01*
Y687200D01*
X1164968Y687584D01*
Y688584D01*
X1165968D01*
G37*
G36*
G01X1143600Y699300D02*
Y698300D01*
X1143568Y697984D01*
Y696984D01*
X1142568D01*
Y697984D01*
X1142600Y698300D01*
Y699300D01*
X1143600D01*
G37*
G36*
G01X1147000D02*
Y698300D01*
X1146968Y697984D01*
Y696984D01*
X1145968D01*
Y697984D01*
X1146000Y698300D01*
Y699300D01*
X1147000D01*
G37*
G36*
G01X1168476Y727777D02*
G02X1167326Y728966I-1476J-277D01*
G03X1167806Y729431I87J391D01*
G02X1168956Y728242I1476J277D01*
G03X1168476Y727777I-87J-391D01*
G37*
G36*
G01X1315157Y837130D02*
G03X1314565Y836982I-233J-325D01*
G02X1313843Y839870I-2065J1018D01*
G03X1314435Y840018I233J325D01*
G02X1315157Y837130I2065J-1018D01*
G37*
G36*
G01X1302678Y840025D02*
G03X1303228Y839919I329J227D01*
G02X1302606Y836691I1272J-1919D01*
G03X1302056Y836797I-329J-227D01*
G02X1302678Y840025I-1272J1919D01*
G37*
G36*
G01X1242306Y787392D02*
G03X1241727Y787386I-287J-279D01*
G02X1237766Y789281I-1682J1571D01*
G03X1237470Y789724I-396J56D01*
G02X1240326Y791629I577J2229D01*
G03X1240622Y791186I396J-56D01*
G02X1241692Y790565I-578J-2228D01*
G03X1242271Y790571I287J279D01*
G02X1242306Y787392I1682J-1571D01*
G37*
G36*
G01X1240279Y764177D02*
G03X1240578Y763732I396J-57D01*
G02X1237737Y761823I-562J-2232D01*
G03X1237438Y762268I-396J57D01*
G02X1240279Y764177I562J2232D01*
G37*
G36*
G01X1318998Y848496D02*
G02X1316280Y847764I-885J-2125D01*
G03X1316115Y848375I-319J242D01*
G02X1314870Y849627I885J2125D01*
G03X1314130I-370J-152D01*
G02Y851373I-2130J873D01*
G03X1314870I370J152D01*
G02X1318833Y849107I2130J-873D01*
G03X1318998Y848496I319J-242D01*
G37*
G36*
G01X1192820Y766477D02*
G02X1191772Y765079I1180J-1977D01*
G03X1191180Y765523I-387J101D01*
G02X1192228Y766921I-1180J1977D01*
G03X1192820Y766477I387J-101D01*
G37*
G36*
G01X1274936Y692378D02*
X1275400Y692300D01*
X1276400D01*
Y691300D01*
X1275400D01*
X1274936Y691378D01*
X1273936D01*
Y692378D01*
X1274936D01*
G37*
G54D110*
X390392Y186614D03*
X402952Y167715D03*
X402977Y174003D03*
X402952Y186613D03*
Y180314D03*
Y192912D03*
X487599Y345865D03*
X483662Y349802D03*
X487599D03*
X483662Y345865D03*
X487599Y341928D03*
X483662D03*
X491536D03*
X483662Y337991D03*
X487599D03*
X475788Y400985D03*
Y397048D03*
Y393111D03*
X471851D03*
Y397048D03*
X475788Y389174D03*
X491536Y400985D03*
X479725Y389174D03*
X491536Y416733D03*
X487599D03*
Y404922D03*
X479725Y412796D03*
X491536Y420670D03*
Y424607D03*
X487599D03*
X499410Y416733D03*
Y412796D03*
X495473Y416733D03*
Y412796D03*
X499410Y420670D03*
Y424607D03*
X495473D03*
Y420670D03*
X1171500Y733725D03*
X1175000Y734870D03*
G54D112*
X476623Y326783D03*
X480423D03*
G54D100*
X153937Y238898D03*
Y246772D03*
Y260551D03*
X224015Y246772D03*
Y260551D03*
G54D98*
X123654Y320953D03*
X121000Y545500D03*
X895000Y96000D03*
X899500Y92500D03*
X703053Y133568D03*
X727248Y141500D03*
X1060000Y929500D03*
X1277500Y757500D03*
Y778500D03*
X1312750Y314000D03*
X1322500Y299000D03*
X1324000Y290500D03*
G54D113*
X1272441Y7087D03*
X1299213D03*
G54D99*
X124500Y515500D03*
X862500Y65000D03*
X874000Y56000D03*
X873500Y61500D03*
X945000Y141500D03*
X947500Y153000D03*
X959900Y180700D03*
X974500Y188500D03*
X975007Y194300D03*
X756000Y180000D03*
X1001100Y776500D03*
X1061356Y753354D03*
X1061696Y761294D03*
X1011500Y667500D03*
X1155390Y818000D03*
G54D101*
X590315Y9134D03*
Y19134D03*
X649527Y9134D03*
Y19134D03*
Y29134D03*
G54D116*
X1258504Y368701D03*
G54D92*
X716034Y53966D03*
X716466Y65466D03*
X127654Y293453D03*
X122906Y331953D03*
X147500Y472100D03*
X135500Y511000D03*
X144000Y572500D03*
X160000Y465500D03*
X153050Y486500D03*
X414000Y8000D03*
X438500Y9000D03*
X720216Y82138D03*
X740500Y75000D03*
X754500Y67500D03*
X873000Y68500D03*
X923000Y51500D03*
X189355Y526470D03*
X195725Y540750D03*
X208305Y562640D03*
X253610Y863447D03*
X252500Y851500D03*
X252000Y846500D03*
X261500Y857500D03*
X247500Y829500D03*
X240000Y829250D03*
X346404Y260000D03*
X474755Y308300D03*
X495929Y164500D03*
X572000Y189000D03*
X561429Y174441D03*
X687968Y755284D03*
Y781784D03*
X691300Y807300D03*
X698818Y759350D03*
X703328Y800144D03*
X697250Y876750D03*
X723168Y774984D03*
X722000Y808500D03*
X735000Y780500D03*
X733498Y180750D03*
X733000Y193000D03*
X745500Y145000D03*
X765116Y187659D03*
X789500Y235837D03*
X838055Y262500D03*
X878500Y695500D03*
X884200Y636500D03*
X860718Y683684D03*
X865500Y690500D03*
X870500Y665060D03*
X861250Y649250D03*
X871000Y639500D03*
X859500Y629500D03*
X842500Y719500D03*
X852500Y710500D03*
X854000Y640500D03*
X846250Y642250D03*
X835000Y719000D03*
X794000Y723500D03*
X798000Y706000D03*
X783746Y692754D03*
X785500Y666500D03*
X770646Y685354D03*
X826500Y743000D03*
X1032200Y921500D03*
X1077000Y943075D03*
X1083200Y956500D03*
X1097500Y849000D03*
X1089000Y867284D03*
X1390004Y122600D03*
X782750Y845750D03*
X781000Y877000D03*
X805250Y865750D03*
X794500Y897000D03*
X814000Y849500D03*
X819000Y868500D03*
X839250Y854500D03*
X826060Y863440D03*
X824560Y868560D03*
X852600Y868500D03*
X1098000Y775000D03*
X1070098Y764500D03*
X1077500Y759000D03*
X989000Y757150D03*
X917000Y752500D03*
X903480Y324230D03*
X1367617Y570012D03*
X1369617Y557012D03*
X1353117Y610412D03*
X1364617Y592912D03*
X1356817Y579012D03*
X1360817Y557812D03*
X1355500Y556500D03*
X1347617Y610412D03*
X1342648Y612412D03*
X1257468Y478500D03*
X1242000Y459000D03*
X1216500Y439500D03*
X1195000Y428000D03*
X988900Y434800D03*
X982075Y439500D03*
X944000Y434000D03*
X924465Y388465D03*
X904600Y406600D03*
X1023500Y727000D03*
X1037000Y734000D03*
X1024387Y738230D03*
X1042400Y684500D03*
X1054000Y735000D03*
X1239000Y352800D03*
X1239500Y366000D03*
X1234177Y379500D03*
X1210800Y379700D03*
X1176500Y383500D03*
X1123000Y250500D03*
X1209000Y212500D03*
X1182500Y407000D03*
X1187500Y411000D03*
X1197000Y409500D03*
X1209500Y404500D03*
X1198718Y800782D03*
X1201968Y757500D03*
X1212840Y781000D03*
X1204000Y862000D03*
X1217250Y862250D03*
X1211500Y882500D03*
X1221000Y764750D03*
X1233000Y782500D03*
X1223000Y826500D03*
X1230500Y841000D03*
X1218500Y834500D03*
X1229807Y847000D03*
X1248500Y775500D03*
X1248950Y782450D03*
X1241984Y796000D03*
X1240660Y829000D03*
X1245650Y821850D03*
X1235258Y820758D03*
X1253500Y778465D03*
X1257950Y809250D03*
X1264000Y853000D03*
X1267500Y779000D03*
X1298034Y907034D03*
X1306000Y782500D03*
X1314284D03*
X1303750Y862250D03*
X1307468Y884532D03*
X1318784Y793716D03*
X1325250Y834250D03*
X1321466Y907034D03*
X1208000Y231000D03*
X1239000Y190500D03*
X1309500Y51000D03*
X1322000Y318500D03*
G54D114*
X1379862Y108465D03*
Y119095D03*
G54D97*
X121890Y269528D03*
X131890D03*
X141890D03*
X1377896Y21656D03*
X1370021D03*
X1377896Y29526D03*
X1370021D03*
X1385766Y21656D03*
Y29526D03*
X1338526D03*
Y21656D03*
G54D117*
X1224016Y386221D03*
G54D115*
X871849Y298230D03*
X867914Y290355D03*
X863974Y298230D03*
X871849Y308070D03*
X867914Y315945D03*
X863974Y308070D03*
G54D95*
X35435Y373228D03*
X82675D03*
X220118Y739409D03*
X210118D03*
X200118D03*
X270118D03*
X260118D03*
X240118D03*
X250118D03*
X230118D03*
G54D94*
X21220Y373228D03*
X96890D03*
G54D102*
X1084646Y43267D03*
G54D93*
X714248Y115300D03*
Y118700D03*
X711716Y121584D03*
X374300Y9000D03*
X377700D03*
X379300D03*
X382700D03*
X1005700Y67600D03*
X1005500Y69300D03*
X730516Y114284D03*
X736416D03*
X64304Y668520D03*
X99304D03*
Y670920D03*
X65336Y688803D03*
Y694703D03*
X354600Y10700D03*
X352400D03*
X362700Y10500D03*
X356800D03*
X350200D03*
X347800D03*
X734916Y130784D03*
X729016D03*
X711716Y134484D03*
X1005300Y73500D03*
X1005500Y71700D03*
X268478Y967000D03*
X270878D03*
X272478D03*
X274878D03*
X313100Y288200D03*
X310900D03*
X309200Y287000D03*
X305800D03*
X315553Y249652D03*
X313353D03*
X352400Y16300D03*
X354600D03*
X347800Y16500D03*
X350200D03*
X356800D03*
X362700D03*
X374300Y18000D03*
X377700D03*
X379300D03*
X382700D03*
X386629Y224500D03*
X384229D03*
X358129Y220500D03*
X355729D03*
X366629Y220250D03*
X364229D03*
X345129D03*
X342729D03*
X374489Y216620D03*
X389869Y216600D03*
X382189Y216590D03*
X374489Y214220D03*
X378129Y204000D03*
X418739Y213450D03*
X423729Y204000D03*
X406014Y201050D03*
X411929Y201000D03*
X389869Y214200D03*
X382189Y214190D03*
X385500Y201800D03*
X395229Y200900D03*
X414114Y155850D03*
X410629Y156000D03*
X408229D03*
X404129D03*
X398229D03*
X387729Y155600D03*
X392000Y188800D03*
X414114Y161850D03*
X398229Y162000D03*
X404129D03*
X408229D03*
X410629D03*
X391929Y175200D03*
X392000Y191200D03*
X411929Y195000D03*
X406014Y195050D03*
X391900Y939700D03*
X394100D03*
X395900D03*
X398100D03*
X399900D03*
X402100D03*
X403900D03*
X406100D03*
X407900D03*
X410100D03*
X411900D03*
X414100D03*
X415900D03*
X422178Y862800D03*
X422478Y861100D03*
Y858900D03*
Y856600D03*
Y854400D03*
Y852100D03*
Y849900D03*
Y847600D03*
Y845400D03*
Y843100D03*
Y840900D03*
Y838600D03*
Y836400D03*
Y834100D03*
Y831900D03*
Y829600D03*
Y827400D03*
X422278Y825700D03*
Y823300D03*
X480831Y191391D03*
Y189191D03*
X470800Y177100D03*
Y174900D03*
Y170100D03*
Y167900D03*
X475300Y163100D03*
Y160900D03*
X475800Y158600D03*
X480800Y187331D03*
Y185131D03*
X482429Y180200D03*
Y177800D03*
Y173700D03*
Y171300D03*
Y167200D03*
Y164800D03*
Y159700D03*
X507129Y136100D03*
X488429Y157300D03*
Y159700D03*
Y164800D03*
Y167200D03*
Y171300D03*
Y173700D03*
Y177800D03*
Y180200D03*
X492578Y847400D03*
Y845100D03*
Y842900D03*
Y841100D03*
Y838900D03*
Y837100D03*
Y834900D03*
X492778Y833200D03*
X512729Y133900D03*
Y136100D03*
X520929Y139800D03*
Y142200D03*
X705716Y121584D03*
X705248Y118700D03*
Y115300D03*
X729016Y136784D03*
X734916D03*
X775700Y974100D03*
X1029800Y62000D03*
X1033200D03*
X1034800D03*
X1038200D03*
X1039800D03*
X1043200D03*
X1044800D03*
X1048200D03*
X1049800D03*
X1053200D03*
X1009400Y79300D03*
X1011600D03*
X1005300Y79500D03*
X1007700D03*
X1029800Y71000D03*
X1033200D03*
X1034800D03*
X1038200D03*
X1039800D03*
X1043200D03*
X1044800D03*
X1048200D03*
X1049800D03*
X1076700Y688600D03*
Y690400D03*
Y692600D03*
Y694400D03*
Y696600D03*
Y698400D03*
Y700600D03*
Y702400D03*
Y704600D03*
Y706400D03*
Y708600D03*
Y710400D03*
Y712600D03*
Y714400D03*
Y716600D03*
Y718400D03*
Y720600D03*
Y722400D03*
Y724600D03*
Y726400D03*
Y728600D03*
X1077700Y735400D03*
X1143700Y798000D03*
X1159100Y800000D03*
X1161500D03*
X1164100D03*
X1166500D03*
X1169100D03*
X1171500D03*
X1153100Y801500D03*
X1155500D03*
X1149300Y703900D03*
X1146500Y702200D03*
X1152700Y700500D03*
X1149300D03*
X1165468Y699084D03*
Y696484D03*
Y694084D03*
X1146468D03*
X1143068D03*
X1165468Y690484D03*
X1145468Y689484D03*
X1165500Y684300D03*
X1158200Y682000D03*
X1155800D03*
X1150468Y680684D03*
X1148068D03*
X1165600Y680500D03*
X1167400Y680400D03*
Y678200D03*
X1165600Y678100D03*
X1152700Y703900D03*
X1158500Y703300D03*
X1165468Y701484D03*
X1210800Y196000D03*
X1214200D03*
X1215800Y197500D03*
X1221700D03*
X1215800Y203500D03*
X1221700D03*
X1214200Y205000D03*
X1262300Y648100D03*
Y658100D03*
Y659900D03*
X1275800Y697000D03*
X1274100Y697200D03*
Y710300D03*
X1275800Y710500D03*
X1274200Y715000D03*
X1275900Y715200D03*
X1371200Y285500D03*
X1385400D03*
X1378300Y318000D03*
X1380700D03*
X1383400Y318200D03*
X1385600D03*
G54D109*
X417014Y155850D03*
Y161850D03*
G54D107*
X385500Y198900D03*
G54D105*
X65336Y691753D03*
X711716Y124534D03*
Y128034D03*
Y131534D03*
X391929Y172250D03*
X705716Y124534D03*
G54D104*
X733466Y114284D03*
X359750Y10500D03*
X731966Y130784D03*
X359750Y16500D03*
X401179Y156000D03*
Y162000D03*
X731966Y136784D03*
X1218750Y197500D03*
Y203500D03*
G54D108*
X409529Y151600D03*
G54D111*
X403279Y163800D03*
G54D91*
X585315Y44134D03*
X654527D03*
G54D103*
X1096732Y32598D03*
G54D106*
X313829Y220200D03*
Y221800D03*
Y223200D03*
X313353Y244052D03*
X315553D03*
X393455Y435800D03*
X395655D03*
X398455D03*
X400655D03*
X398355Y440600D03*
X399755D03*
X476623Y328683D03*
Y324883D03*
X480423D03*
Y328683D03*
X479755Y352100D03*
X497455Y350300D03*
Y348700D03*
Y346300D03*
X479455Y345200D03*
X498455Y345100D03*
X479455Y343800D03*
X498455Y343700D03*
X497455Y352700D03*
X481355Y375900D03*
X482755D03*
X481855Y377600D03*
X483255D03*
X496655Y379300D03*
Y380700D03*
X487855Y388900D03*
X489255D03*
X498155Y392300D03*
X482355Y393100D03*
X483755D03*
X498155Y393700D03*
X488355Y396900D03*
X489755D03*
X474455Y403300D03*
Y404700D03*
X494155Y404800D03*
X480355Y405100D03*
X481755D03*
X494155Y406200D03*
X475455Y409300D03*
Y410700D03*
X487855Y412900D03*
X489255D03*
X469755Y415100D03*
X473855Y417100D03*
X475255D03*
X482700Y130100D03*
X484229D03*
X485629D03*
X503455Y352700D03*
X502255Y343700D03*
Y345100D03*
X503455Y346300D03*
Y348700D03*
Y350300D03*
X623800Y346500D03*
X627200D03*
X628800D03*
X632200D03*
X633800D03*
X637200D03*
X638800D03*
X642200D03*
X623800Y349900D03*
X627200D03*
X628800D03*
X632200D03*
X633800D03*
X637200D03*
X638800D03*
X642200D03*
X625640Y412701D03*
Y414101D03*
Y417101D03*
Y418501D03*
Y421501D03*
Y422901D03*
Y425901D03*
Y427301D03*
Y430301D03*
Y431701D03*
Y434701D03*
Y436101D03*
X778124Y342148D03*
X779524D03*
X781624D03*
X783024D03*
Y345948D03*
X781624D03*
X779524D03*
X778124D03*
G54D96*
X19272Y337795D03*
X98838D03*
%LPD*%
G75*
G36*
G01X598000Y774500D02*
X597000Y775500D01*
Y801948D01*
G02X597646Y802264I400J0D01*
G03Y805736I1354J1736D01*
G02X597000Y806052I-246J316D01*
G01Y879000D01*
X598000Y880000D01*
X610500D01*
X612500Y878000D01*
Y775500D01*
X611500Y774500D01*
X598000D01*
G37*
G36*
G01X677000Y354000D02*
X675000Y352000D01*
X624000D01*
X622000Y354000D01*
Y368500D01*
X624000Y370500D01*
X674500D01*
X677000Y368000D01*
Y354000D01*
G37*
%LPC*%
G75*
G54D93*
X642200Y355500D03*
X627200D03*
X628800D03*
X632200D03*
X633800D03*
X637200D03*
X638800D03*
X623800D03*
%LPD*%
G75*
G54D10*
X8590Y318590D03*
X4500Y329297D03*
Y349297D03*
Y369297D03*
Y389297D03*
Y409297D03*
Y429297D03*
Y449297D03*
Y469297D03*
Y489297D03*
Y509297D03*
Y529297D03*
Y549297D03*
Y569297D03*
Y589297D03*
Y609297D03*
Y629297D03*
Y649297D03*
Y669297D03*
Y689297D03*
Y709297D03*
Y729297D03*
Y749297D03*
Y769297D03*
Y789297D03*
Y809297D03*
Y829297D03*
Y849297D03*
Y869297D03*
Y889297D03*
Y909297D03*
Y929297D03*
Y949297D03*
Y969297D03*
X20000Y380000D03*
Y440000D03*
Y460000D03*
Y480000D03*
Y500000D03*
X27004Y783420D03*
X23820Y795182D03*
X30312Y805489D03*
X25000Y980000D03*
X49369Y767582D03*
X46304Y779520D03*
X40204Y788820D03*
X35747Y796605D03*
X43456Y803320D03*
X36904Y813020D03*
X38804Y843320D03*
X38500Y891500D03*
X46500Y879500D03*
X47880Y918798D03*
X45000Y980000D03*
X68147Y734920D03*
X63167Y775783D03*
X52720Y832220D03*
X63879Y839879D03*
X56500Y874000D03*
X57770Y926520D03*
X55270Y920220D03*
X52770Y927420D03*
X62770Y926400D03*
X60270Y918820D03*
X55000Y975000D03*
X65000Y980000D03*
X71846Y726562D03*
X77699Y738515D03*
X77504Y767420D03*
X84221Y831279D03*
X75000Y975000D03*
X94804Y718720D03*
X99804Y727120D03*
X86704Y740720D03*
X87104Y871920D03*
X94904Y869720D03*
X99804Y920520D03*
X93604Y938795D03*
X95000Y975000D03*
X109054Y898620D03*
X103312Y904712D03*
X116554Y909020D03*
X114054Y900220D03*
X107804Y908820D03*
X117202Y926322D03*
X112476Y924744D03*
X107804Y920720D03*
X106803Y927321D03*
X132123Y318877D03*
X123654Y320953D03*
X121000Y545500D03*
X124054Y897920D03*
X122904Y907820D03*
X119054Y901520D03*
X119804Y920320D03*
X131404Y925520D03*
X127804Y920520D03*
X123804Y925720D03*
X146364Y296000D03*
X140000Y720000D03*
Y740000D03*
X135804Y920020D03*
X156500Y939500D03*
X162000D03*
X182500Y547500D03*
X168000Y575000D03*
Y580000D03*
X178000Y590000D03*
X180000Y760000D03*
X167500Y939500D03*
X172500D03*
X177500D03*
X182000D03*
X188000D03*
X193500D03*
X199500D03*
X207100Y703600D03*
X206000Y982000D03*
X229000Y493500D03*
X231200Y509800D03*
X227755Y520900D03*
X222000Y703500D03*
X220000Y760000D03*
X224000Y875000D03*
X225500Y879500D03*
X225000Y920500D03*
X232000Y921000D03*
X227500Y957500D03*
Y963500D03*
X226000Y982000D03*
X242000Y509600D03*
X241200Y501800D03*
X237055Y516500D03*
X249000Y513700D03*
X234155Y530700D03*
X248045Y528970D03*
X241600Y522500D03*
X248700Y548800D03*
X247500Y883000D03*
X243000D03*
X246968Y957784D03*
X233468Y957284D03*
X239968Y957784D03*
X246968Y963784D03*
X239968D03*
X233468D03*
X246000Y982000D03*
X261500Y188900D03*
X256300Y188800D03*
X258800Y184200D03*
X261400Y179800D03*
X255800Y179600D03*
X259000Y211000D03*
Y206000D03*
X262500Y208500D03*
X260000Y260000D03*
X259055Y497200D03*
X264665Y487730D03*
X250200Y501400D03*
X258592Y511993D03*
X255829Y527924D03*
X263400Y527900D03*
X253679Y520037D03*
X264615Y519970D03*
X259000Y537700D03*
X262200Y545000D03*
X263700Y552500D03*
X255500Y552600D03*
X260000Y760000D03*
X252000Y883000D03*
X256500D03*
X261000D03*
X265500D03*
X252000Y957500D03*
X252500Y963500D03*
X262178Y976000D03*
X261178Y981040D03*
X281800Y183700D03*
Y188500D03*
X281900Y178500D03*
X271655Y528210D03*
X280800Y532800D03*
X275055Y517960D03*
X281500Y523500D03*
X271986Y523421D03*
X278000Y543700D03*
X274200Y537200D03*
X271400Y547800D03*
X266635Y537120D03*
X277500Y977000D03*
X278500Y965000D03*
X277500Y969500D03*
X272500D03*
X268000D03*
X296000Y105000D03*
X291000Y98500D03*
X285800Y180800D03*
X285600Y186100D03*
X285500Y330000D03*
X286000Y336000D03*
X293495Y494300D03*
X294692Y503484D03*
X292605Y536560D03*
X285678Y995500D03*
X293178D03*
X299500Y5500D03*
X309500Y75000D03*
X306000Y105000D03*
X301000D03*
X310000Y102500D03*
X301600Y110600D03*
X302329Y223800D03*
X306700Y265500D03*
X310929Y257500D03*
X311500Y272000D03*
X311429Y334500D03*
X307429Y336000D03*
Y331500D03*
X314588Y361696D03*
X303354Y358650D03*
X308474Y373060D03*
X301178Y995500D03*
X309678D03*
X320500Y11000D03*
X316000D03*
X324000Y24000D03*
Y19500D03*
Y15000D03*
X321000Y29000D03*
Y33500D03*
Y38000D03*
X330500Y38500D03*
Y33500D03*
X316000Y50000D03*
X321000Y57000D03*
Y52500D03*
Y48000D03*
Y42500D03*
Y61500D03*
X328000Y93000D03*
X323000D03*
X316598Y91500D03*
X320500Y124000D03*
X316400Y222500D03*
X315929Y253000D03*
X317529Y241600D03*
X316000Y271500D03*
X315929Y257500D03*
X330500Y287000D03*
X322500Y298000D03*
X322429Y349300D03*
X325100Y364000D03*
X324678Y995500D03*
X317178D03*
X344000Y27000D03*
X336000D03*
X337500Y68500D03*
X337000Y73500D03*
X337500Y102000D03*
X342900Y120040D03*
X346129Y188200D03*
X345540Y202000D03*
X347040Y193000D03*
X336200Y366275D03*
X344000Y368315D03*
X335645Y445630D03*
X336855Y458900D03*
X341178Y996000D03*
X332678Y995500D03*
X349000Y38500D03*
Y33500D03*
X362500Y64000D03*
X349000Y78000D03*
X358080Y184300D03*
X354410Y176460D03*
X350040Y184500D03*
X361929Y174000D03*
X350040Y198500D03*
X353040Y202500D03*
X357540Y199500D03*
X358440Y189300D03*
X348800Y221000D03*
X351929Y266000D03*
X352429Y279000D03*
X357929Y277000D03*
X363662Y373838D03*
X357661Y434216D03*
X364055Y428500D03*
X361055Y431500D03*
X359855Y440400D03*
X359455Y448300D03*
X352917Y443700D03*
X362500Y608500D03*
X355500D03*
Y614000D03*
X362500D03*
X356500Y622500D03*
X361000Y925490D03*
X363000Y936000D03*
X361646Y990784D03*
X358268Y995500D03*
X348678Y996000D03*
X370000Y51000D03*
Y55500D03*
Y60000D03*
X370500Y72100D03*
X376140Y186800D03*
X366729Y174000D03*
X377929D03*
X375040Y197500D03*
X373500Y235200D03*
X366000Y277500D03*
X376600Y350310D03*
X379500Y377000D03*
X374600Y413540D03*
X374900Y404300D03*
X367000Y412000D03*
X364430Y424300D03*
X367800Y420300D03*
X375100Y436955D03*
X369900Y446932D03*
X367500Y436355D03*
X366255Y456700D03*
X365940Y464200D03*
X369555Y470800D03*
X376500Y608500D03*
X369500D03*
Y614000D03*
X376500D03*
X378500Y812000D03*
Y824500D03*
X375600Y909600D03*
X371900Y901400D03*
X370500Y941500D03*
X377000Y942000D03*
X366678Y990500D03*
X377953Y995725D03*
X393800Y25100D03*
X389300Y20100D03*
X393800D03*
X384800Y25100D03*
X389300D03*
X384800Y20100D03*
X380500Y34500D03*
X391000Y35500D03*
X395500D03*
X393900Y30400D03*
X389400D03*
X384900D03*
X386000Y53000D03*
X381500D03*
Y58000D03*
X382130Y229780D03*
X396329Y227800D03*
X390500Y250000D03*
Y257500D03*
X385425Y348740D03*
X386500Y362100D03*
X387519Y379375D03*
X392900Y388000D03*
X383000Y401000D03*
X387669Y387355D03*
X386455Y392000D03*
X380555Y407000D03*
X394555Y426000D03*
X383250Y910750D03*
X392575Y924575D03*
X381000Y919500D03*
X393000Y949000D03*
X387500Y944500D03*
X389763Y996085D03*
X398300Y20100D03*
Y25100D03*
X400000Y35500D03*
X398400Y30400D03*
X398000Y39500D03*
X412929Y145500D03*
X408429Y219700D03*
X401929Y225300D03*
X405000Y272000D03*
X410330Y326500D03*
X405555Y379000D03*
X401055Y381500D03*
X404555Y412000D03*
X399555Y426000D03*
X406055Y423700D03*
X403155Y437600D03*
X406500Y713500D03*
X412000Y724000D03*
X409500Y775500D03*
X400200Y893925D03*
X400000Y888500D03*
X399500Y908500D03*
X402500Y927500D03*
X398000Y949500D03*
X411574Y971926D03*
X409000Y992000D03*
X403900Y990500D03*
X421540Y123500D03*
Y118500D03*
X428040Y123500D03*
X426786Y113500D03*
X418040Y132500D03*
X425229Y128700D03*
X422940Y133000D03*
X428040D03*
X423329Y145620D03*
X417729Y145500D03*
X420219Y151810D03*
X426429Y196000D03*
X425126Y221124D03*
X425532Y228137D03*
X416500Y229500D03*
X417500Y253000D03*
X429500Y307500D03*
X422952Y325500D03*
X421055Y321000D03*
X413555Y322000D03*
X424000Y377000D03*
X415755Y408200D03*
X422500Y764500D03*
X418500Y850500D03*
X417000Y969000D03*
X418071Y974956D03*
X414000Y977500D03*
X433040Y119000D03*
X438540D03*
X444540Y122500D03*
X443042Y139065D03*
X433040Y132500D03*
X430040Y128500D03*
X438540Y132500D03*
X435040Y128000D03*
X445059Y127830D03*
X443429Y132400D03*
X429939Y146020D03*
X442429Y171500D03*
X442099Y187600D03*
X440009Y225589D03*
X431321Y232880D03*
X435659Y223364D03*
X445000Y223000D03*
X438000Y245000D03*
X432600Y291400D03*
X445395Y317610D03*
X442555Y324000D03*
X432555Y333500D03*
X434155Y327000D03*
X436055Y342000D03*
X436555Y337000D03*
X432000Y366000D03*
X431000Y713500D03*
Y724000D03*
X432678Y827300D03*
X431298Y832710D03*
X430878Y842800D03*
X436978Y831000D03*
X430978Y837500D03*
X431126Y848348D03*
X431466Y858563D03*
X430936Y853145D03*
X437978Y859000D03*
X430778Y864000D03*
X432723Y970223D03*
X435678Y996000D03*
X443178D03*
X459429Y102700D03*
X452829Y99000D03*
X448229Y133000D03*
X452159Y125370D03*
X452929Y134500D03*
X458349Y137762D03*
X459929Y128500D03*
X454929Y130000D03*
X447349Y149920D03*
X450989Y153950D03*
X458839Y147900D03*
X450255Y140258D03*
X449429Y145500D03*
X454479Y150150D03*
X456929Y143000D03*
X455229Y162460D03*
X456309Y157740D03*
X451669Y159120D03*
X447129Y157000D03*
X447489Y162190D03*
X458129Y167900D03*
X461272Y159293D03*
X455429Y185500D03*
X448876Y195275D03*
X450237Y200375D03*
X460500Y196000D03*
X461000Y216500D03*
X449500Y220925D03*
X452509Y226958D03*
X448055Y311500D03*
X452555Y316500D03*
X447055Y321500D03*
X456055D03*
X452555Y352900D03*
X448555Y338000D03*
X453878Y824900D03*
X456278Y829500D03*
Y866500D03*
X458678Y996000D03*
X450178D03*
X465329Y111900D03*
X467000Y118500D03*
X463429Y139000D03*
X465429Y127000D03*
X468600Y136700D03*
X462539Y144270D03*
X462500Y154000D03*
Y164000D03*
X475900Y173800D03*
X472000Y184500D03*
X467010Y186000D03*
X465807Y197940D03*
X462500Y221500D03*
X464000Y243500D03*
X476700Y303800D03*
X468555Y323000D03*
X463055Y322500D03*
X472055Y334000D03*
X475957Y322537D03*
X467255Y342600D03*
X472055Y341500D03*
X462555Y346000D03*
X477500Y715000D03*
X476978Y830500D03*
X474178Y995500D03*
X466178Y996000D03*
X479000Y116500D03*
X482429Y139000D03*
X480429Y144100D03*
X494829Y140500D03*
X493800Y172000D03*
X485500Y313000D03*
X493455Y345000D03*
X485500Y400500D03*
X491500Y715000D03*
X490500Y800000D03*
X482778Y832000D03*
X479578Y843200D03*
X479078Y836000D03*
X483878Y839300D03*
X479278Y850000D03*
X484178Y846984D03*
X480578Y856000D03*
X482278Y867500D03*
X495000Y883000D03*
X489678Y995500D03*
X482178D03*
X499929Y146000D03*
X509200Y146700D03*
X510500Y237300D03*
X506000Y239500D03*
X511500Y345000D03*
X504500Y715000D03*
X502500Y800000D03*
X497500Y833000D03*
X501000Y876000D03*
X500500Y863500D03*
X499000Y883000D03*
X505678Y995500D03*
X498178D03*
X516000Y134000D03*
X519929Y135500D03*
X523129Y132600D03*
X526500Y145000D03*
X524000Y243500D03*
X521055Y528500D03*
Y533500D03*
X516555Y528500D03*
Y533500D03*
X526055D03*
X526000Y524500D03*
Y529000D03*
X521000Y524000D03*
X521055Y544000D03*
Y548900D03*
X516555Y543500D03*
X516655Y548900D03*
X521055Y538500D03*
X516555Y539000D03*
X526055Y538500D03*
Y544000D03*
Y548900D03*
X516500Y556000D03*
X521178Y995500D03*
X513678D03*
X531500Y124500D03*
X543500Y179000D03*
X538500Y188500D03*
X542500Y215500D03*
X540500Y211000D03*
X544500Y224500D03*
X544178Y956000D03*
Y973500D03*
X536678Y996000D03*
X530083Y995500D03*
X560000Y20000D03*
X556500Y184500D03*
X550500D03*
X560468Y203788D03*
X555500Y190500D03*
X555000Y219500D03*
X550075Y212500D03*
X552435Y232150D03*
X556455Y337700D03*
X550755Y337500D03*
X560678Y996000D03*
X568500Y180500D03*
X566900Y195900D03*
X562441Y199072D03*
X564500Y217000D03*
X564000Y212000D03*
X568000Y239000D03*
X567500Y457500D03*
X563000Y453000D03*
X567500D03*
Y462000D03*
Y466500D03*
X563000Y457500D03*
Y462000D03*
Y466500D03*
X569178Y996000D03*
X576678D03*
X591000Y253500D03*
X584500Y240500D03*
X591000Y262500D03*
X586000Y267000D03*
Y262500D03*
X591000Y258000D03*
X586150Y383000D03*
X586200Y378500D03*
X581950Y383000D03*
X582000Y378500D03*
X590500Y383000D03*
X586150Y396000D03*
X590500D03*
X581950D03*
X586150Y409500D03*
X581950D03*
X590500D03*
X582700Y431500D03*
X590500Y423500D03*
X586150D03*
X587000Y431500D03*
X578500D03*
X581950Y423500D03*
X582200Y439500D03*
X578000D03*
X586500D03*
X593500Y648500D03*
Y659500D03*
Y654000D03*
X584678Y994500D03*
X595500Y253500D03*
Y258000D03*
X610500Y333000D03*
X606000Y341500D03*
X609000Y345500D03*
X610000Y415500D03*
Y434000D03*
Y428500D03*
Y422000D03*
X610100Y439500D03*
X602500Y465900D03*
X608000Y465800D03*
X602500Y470100D03*
X608000Y470300D03*
X601000Y543000D03*
X599500Y648500D03*
Y654000D03*
Y659500D03*
X604500Y714500D03*
X609500Y778500D03*
X603000D03*
Y785000D03*
X609000Y870000D03*
X604000Y877500D03*
X609211Y877611D03*
X606000Y918500D03*
X598178Y983500D03*
X615000Y333000D03*
X620500D03*
X611500Y341500D03*
X613500Y345500D03*
X616500Y341500D03*
X621500D03*
X614200Y415500D03*
X614500Y434000D03*
X614200Y422000D03*
Y428500D03*
X613500Y451500D03*
X614300Y439500D03*
X620000Y465800D03*
X613500D03*
X626500D03*
X613500Y470000D03*
X620000D03*
X626500D03*
Y557350D03*
X626000Y676000D03*
X616500Y714500D03*
X613500Y744500D03*
Y759000D03*
X620500Y848500D03*
X642000Y335000D03*
X639000Y332000D03*
X637500Y367900D03*
X630500Y368500D03*
X642000D03*
X638500Y409000D03*
X634500Y427000D03*
X637000Y431500D03*
X632500D03*
Y440100D03*
X637000Y436500D03*
X632500D03*
X634000Y734500D03*
X633500Y749500D03*
X630500Y912000D03*
X650000Y110000D03*
X650300Y336400D03*
X647500Y368500D03*
X653500D03*
X659500D03*
X651500Y408500D03*
X646500D03*
X654600Y447700D03*
X654000Y455900D03*
X645500Y481000D03*
X649100Y471700D03*
X657500Y827000D03*
X656500Y906000D03*
X674666Y82002D03*
X670454Y94544D03*
X670998Y116010D03*
X660000Y120000D03*
X670522Y130200D03*
X673500Y334000D03*
X668000D03*
X662000D03*
X666500Y359500D03*
X665000Y368500D03*
X670000Y395000D03*
X670500Y414000D03*
X670919Y406750D03*
X659700Y432600D03*
X664900Y441800D03*
X675411Y446000D03*
X668800Y465993D03*
X663360Y483321D03*
X674000Y888900D03*
X669000Y887385D03*
X671500Y899000D03*
X685898Y133380D03*
X682418Y129980D03*
X690966Y142028D03*
X685000Y150500D03*
X690500Y468000D03*
X679900Y470200D03*
X682500Y917500D03*
X701949Y118331D03*
X701828Y129550D03*
X698500Y132500D03*
X701748Y125400D03*
X697248Y128000D03*
X703053Y133568D03*
X704716Y156520D03*
X700216Y156368D03*
X705500Y352500D03*
X707000Y340500D03*
X708500Y365000D03*
X707000Y385000D03*
Y378000D03*
X708500Y371000D03*
X693100Y445800D03*
X694000Y483500D03*
X693500Y472000D03*
X694000Y492000D03*
Y500500D03*
Y507500D03*
Y514000D03*
X705600Y769300D03*
X701400Y883900D03*
X722716Y156520D03*
X718216D03*
X713716D03*
X709216D03*
X719500Y185600D03*
X725000Y189000D03*
X711500Y385000D03*
Y378000D03*
X720000Y849000D03*
X721900Y852750D03*
X720000Y905000D03*
X730748Y99500D03*
X740000Y109534D03*
X739000Y120400D03*
X732248Y140000D03*
X731716Y156500D03*
X736000Y142000D03*
X727248Y141500D03*
X727216Y156520D03*
X740000Y681000D03*
X740500Y755000D03*
X739900Y760000D03*
X733784Y861131D03*
X746716Y130238D03*
X750916Y130272D03*
X742800Y173600D03*
X757000Y435500D03*
X752100Y435600D03*
X751500Y431000D03*
X756500D03*
X757802Y474000D03*
X747775Y710275D03*
X748500Y858700D03*
X760522Y116784D03*
X770000Y123500D03*
X765000Y351500D03*
X773000Y339500D03*
X761600Y435600D03*
X761500Y431000D03*
X766000D03*
X770000Y677000D03*
Y681500D03*
X768000Y760600D03*
X762900Y767800D03*
X767000Y845000D03*
X763593Y858444D03*
X760500Y866283D03*
X773000Y917000D03*
Y921500D03*
Y927000D03*
X767500D03*
X771000Y958500D03*
X766600D03*
X762100Y958600D03*
X771500Y963500D03*
X767100D03*
X762600Y963600D03*
X771400Y968900D03*
X767000D03*
X762500Y969000D03*
X769800Y977300D03*
X777500Y351000D03*
X782500D03*
X777500Y339500D03*
X782400Y339400D03*
X782600Y414750D03*
Y411000D03*
X776468Y447600D03*
X778688Y470790D03*
X800000Y100000D03*
X792000Y356500D03*
X791000Y466603D03*
X801500Y573000D03*
X800500Y977500D03*
X794500D03*
X800500Y982000D03*
X794500D03*
X810000Y120000D03*
X818500Y361600D03*
X813500Y367000D03*
X811600Y477100D03*
X819000Y473000D03*
X820500Y754000D03*
Y765500D03*
X821000Y883700D03*
X828500Y361500D03*
X837000D03*
X829500Y373500D03*
Y380000D03*
Y385500D03*
X825500Y669000D03*
X846500Y362000D03*
X842000Y367000D03*
Y372000D03*
Y377500D03*
X848600Y517100D03*
X843100Y517000D03*
X843200Y512800D03*
X843300Y507900D03*
X848800Y508000D03*
X848700Y512900D03*
X854500Y778000D03*
X850000D03*
X854200Y764700D03*
X854500Y783000D03*
X850000D03*
X870000Y160000D03*
X858500Y656500D03*
X879736Y290000D03*
X875500Y290500D03*
X878500Y294178D03*
X882500Y339500D03*
X884000Y396500D03*
X879500D03*
X883200Y451500D03*
X889000Y617000D03*
X895000Y96000D03*
X899500Y92500D03*
X890000Y140000D03*
X899000Y405500D03*
X894000D03*
X899000Y410500D03*
X894000D03*
X892000Y610500D03*
X895000Y617500D03*
X910000Y160000D03*
X915000Y805000D03*
Y825000D03*
Y845000D03*
Y865000D03*
Y885000D03*
Y905000D03*
Y925000D03*
Y945000D03*
Y965000D03*
X930500Y219000D03*
X936500D03*
X930500Y232000D03*
X936500D03*
Y225500D03*
X930500D03*
Y536500D03*
X945720Y478280D03*
X943500Y488000D03*
X966000Y209500D03*
X961000Y212500D03*
X963500Y488000D03*
X961000Y495000D03*
X963500Y536500D03*
Y654500D03*
X958000D03*
Y659500D03*
X963500D03*
X969000Y655100D03*
Y659500D03*
X965000Y725500D03*
X981000Y386500D03*
X985000Y388000D03*
X980500Y391000D03*
X984500Y392500D03*
X980400Y435300D03*
X974500Y655100D03*
Y659500D03*
X980000Y725500D03*
X1004500Y84000D03*
X994000Y643600D03*
X1000500Y667500D03*
X990000D03*
X1007000Y12000D03*
X1013500Y84000D03*
X1009000D03*
X1016500Y75500D03*
X1013000Y282500D03*
X1012900Y275300D03*
X1011500Y642000D03*
Y648000D03*
X1015500Y871500D03*
X1020500Y882500D03*
Y887000D03*
X1022500Y51500D03*
X1034500D03*
X1028000D03*
X1021000Y75500D03*
X1032000Y82500D03*
Y90000D03*
Y97000D03*
Y103500D03*
Y110000D03*
X1025500Y140500D03*
X1036000Y178000D03*
X1031800Y248800D03*
X1027500Y248500D03*
X1036300Y248800D03*
X1033000Y290000D03*
X1027500D03*
X1027700Y294200D03*
X1033200D03*
X1029500Y653000D03*
X1035500Y825500D03*
Y830000D03*
X1035000Y970000D03*
X1045000Y141500D03*
X1051034Y173534D03*
X1053000Y228000D03*
X1046000Y290000D03*
X1039500D03*
X1039700Y294200D03*
X1046200D03*
X1050500Y680500D03*
X1040000Y825500D03*
X1044500D03*
X1049000D03*
X1053400D03*
X1040000Y830000D03*
X1051000Y883600D03*
Y888500D03*
X1054000Y124500D03*
X1063000Y140500D03*
X1065000Y154000D03*
X1057000Y229500D03*
X1056716Y224500D03*
X1060500Y282500D03*
X1060600Y303150D03*
X1056100Y303200D03*
X1059900Y295200D03*
X1059800Y290600D03*
X1068000Y645329D03*
X1066300Y658800D03*
X1055000Y664500D03*
X1058000Y677500D03*
X1065000Y677000D03*
X1056000Y801500D03*
X1058000Y889500D03*
Y902500D03*
Y896000D03*
X1060000Y929500D03*
X1055000Y970000D03*
X1078500Y140500D03*
X1084988Y154203D03*
X1080500Y153500D03*
X1077500Y150000D03*
X1070000Y145500D03*
X1085150Y158400D03*
X1086000Y187500D03*
Y192500D03*
X1079000Y434000D03*
X1085000D03*
X1079100Y429000D03*
X1085896Y551500D03*
X1071977Y630000D03*
X1085000Y667500D03*
X1075000Y970000D03*
X1100000Y180000D03*
X1101500Y461500D03*
X1088000Y609500D03*
X1098000Y659000D03*
X1088000Y677000D03*
X1102500Y666800D03*
X1093000Y670000D03*
X1095500Y681706D03*
X1087400Y686000D03*
X1094250Y690050D03*
X1087100Y695000D03*
X1094000Y699500D03*
X1086500Y713000D03*
X1092812Y708500D03*
X1086600Y704000D03*
X1086300Y720100D03*
X1093600Y716100D03*
X1087000Y739200D03*
X1093975Y742500D03*
X1102500Y762500D03*
X1097500D03*
X1102500Y767400D03*
X1097500D03*
X1093000Y766500D03*
X1097500Y797500D03*
X1091500Y846500D03*
X1099500Y866000D03*
X1105000Y400500D03*
X1110500Y660076D03*
X1118200Y657400D03*
X1115000Y650000D03*
X1107524Y676124D03*
X1110700Y669200D03*
X1112400Y678500D03*
X1112600Y713100D03*
X1106400Y714400D03*
X1116500Y718300D03*
X1106600Y753000D03*
X1115800Y766400D03*
X1110400Y769500D03*
X1117630Y779565D03*
X1117600Y787000D03*
X1114500Y855500D03*
X1119000D03*
X1105000Y970000D03*
X1134000Y229000D03*
X1128500D03*
X1129000Y502500D03*
X1123500D03*
Y507500D03*
X1129000D03*
X1135500D03*
Y502500D03*
X1133200Y633500D03*
X1127610Y663660D03*
X1133000Y657000D03*
X1127800Y656204D03*
X1121760Y665640D03*
X1119400Y706210D03*
X1127554Y724482D03*
X1128000Y718000D03*
X1132902Y746400D03*
X1134000Y757350D03*
X1119295Y774903D03*
X1123852Y776918D03*
X1123233Y772157D03*
X1128378Y774146D03*
X1123500Y796000D03*
X1125000Y970000D03*
X1141000Y507500D03*
Y502500D03*
X1146500Y539000D03*
X1136200Y574100D03*
X1145800Y576200D03*
X1143500Y655500D03*
Y660500D03*
X1151000Y656500D03*
X1137386Y660414D03*
X1138760Y671560D03*
X1141790Y667130D03*
X1139000Y678600D03*
X1145400Y673100D03*
X1135724Y692464D03*
X1142900Y705300D03*
X1140586Y725300D03*
X1137286Y731000D03*
X1142811Y731100D03*
X1144075Y739375D03*
X1138900Y761600D03*
X1143862Y770957D03*
X1135900Y792500D03*
X1148061Y793765D03*
X1148760Y789016D03*
X1151800Y796800D03*
X1145800Y816000D03*
X1137000Y890000D03*
X1144500D03*
X1152000D03*
X1145000Y970000D03*
X1161500Y222000D03*
X1166500D03*
X1160500Y242000D03*
Y246500D03*
X1165000Y242000D03*
Y246500D03*
X1159000Y396500D03*
X1157700Y528200D03*
X1154100Y539600D03*
X1156179Y615121D03*
X1159500Y624000D03*
X1152600Y634600D03*
X1164000Y655000D03*
Y660000D03*
X1159000Y652176D03*
X1156500Y657500D03*
X1154000Y652500D03*
X1167280Y672050D03*
X1158780Y670430D03*
X1168000Y706000D03*
X1163700Y714400D03*
X1154610Y711340D03*
X1152709Y720064D03*
X1156080Y723482D03*
X1160000Y734480D03*
X1164100Y740000D03*
X1157500Y739200D03*
X1151900Y740500D03*
X1156700Y744100D03*
X1161324Y749550D03*
X1161128Y759674D03*
X1164178Y755967D03*
X1163600Y777900D03*
X1158801Y778038D03*
X1166500Y773900D03*
X1158600Y790900D03*
X1157841Y784725D03*
X1165063Y790400D03*
X1158000Y890000D03*
X1164500D03*
X1171000Y222000D03*
X1176000D03*
X1169000Y398000D03*
X1171000Y394000D03*
X1170500Y461000D03*
X1173100Y499200D03*
X1181400Y592100D03*
X1181884Y614211D03*
X1182500Y623500D03*
X1171775Y630000D03*
X1169075Y617500D03*
X1175500Y660000D03*
X1183000Y656000D03*
X1182500Y664500D03*
X1171080Y675530D03*
X1173500Y683000D03*
X1170000Y710790D03*
X1173600Y704500D03*
X1184500Y730500D03*
X1180210Y718150D03*
X1174500Y753000D03*
X1168465Y779808D03*
X1173263Y779656D03*
X1170500Y768000D03*
X1174100Y774900D03*
X1173902Y784414D03*
X1170300Y787985D03*
X1182000Y816000D03*
X1181500Y820500D03*
X1177000D03*
X1175000Y970000D03*
X1199100Y226600D03*
X1194900D03*
X1185500Y362500D03*
X1195000Y422500D03*
X1194000Y484000D03*
X1189500D03*
X1194000Y488500D03*
X1189500D03*
Y492900D03*
X1194000Y493000D03*
X1188500Y500000D03*
X1196500Y640000D03*
X1191000Y651500D03*
X1187230Y702250D03*
X1193960Y713250D03*
X1194000Y703000D03*
X1190760Y719450D03*
X1196100Y719100D03*
X1184850Y720120D03*
X1187330Y715720D03*
X1194573Y727580D03*
X1193100Y736900D03*
X1195920Y753700D03*
X1195000Y970000D03*
X1213677Y191000D03*
X1203500Y193800D03*
Y198000D03*
X1208000D03*
Y193800D03*
X1204000Y206000D03*
X1208500Y207000D03*
X1204000Y210500D03*
Y215000D03*
X1207500Y225000D03*
X1203300Y226600D03*
X1207500Y239500D03*
X1209500Y546000D03*
X1217000Y537000D03*
X1207700Y601800D03*
X1213000Y624500D03*
X1216000Y664500D03*
X1216500Y710125D03*
X1217500Y705200D03*
X1209000Y722500D03*
X1206000Y731000D03*
X1216500Y735000D03*
X1202200Y741600D03*
X1215000Y970000D03*
X1231000Y543775D03*
X1219300Y567800D03*
X1222500Y620500D03*
X1225500Y653000D03*
X1226500Y668500D03*
X1222000Y666500D03*
X1218040Y716000D03*
X1229500Y735700D03*
X1249300Y166000D03*
X1240600Y167000D03*
X1240700Y171200D03*
X1240800Y179800D03*
X1240700Y175500D03*
Y184000D03*
X1241000Y219000D03*
X1239500Y227500D03*
X1242000Y223500D03*
X1244000Y227500D03*
X1246000Y263500D03*
X1241500Y654000D03*
X1236000Y660500D03*
X1240500Y679500D03*
X1246700Y675500D03*
X1243000Y691500D03*
X1235000Y687500D03*
X1245500Y683500D03*
X1234500Y695500D03*
X1243500Y699500D03*
X1235000Y703500D03*
X1243000Y707500D03*
X1235500Y711500D03*
X1241000Y730400D03*
X1243000Y715500D03*
X1234700Y733700D03*
X1256500Y431000D03*
X1251500Y536000D03*
X1264000Y613500D03*
X1257500Y620500D03*
X1263000Y717000D03*
X1269000Y252000D03*
X1280500Y433000D03*
X1268500Y427000D03*
X1272000Y463500D03*
X1281000Y475000D03*
X1276500D03*
X1267500Y625500D03*
X1275500Y647000D03*
X1278000Y657000D03*
X1277500Y757500D03*
Y778500D03*
X1270000Y794000D03*
X1274000Y875000D03*
X1287500Y428000D03*
X1288000Y442000D03*
X1292500Y441000D03*
X1288000Y470000D03*
X1285500Y475000D03*
X1293500D03*
Y607500D03*
X1288000Y674687D03*
X1293000Y682500D03*
X1297750Y691350D03*
X1294000Y712000D03*
X1294500Y720000D03*
X1296000Y733000D03*
X1286500Y747500D03*
X1312750Y314000D03*
X1300000Y669000D03*
X1315000Y704000D03*
X1301800Y727199D03*
X1300500Y739750D03*
X1308500Y771500D03*
X1303000D03*
X1314000D03*
X1322500Y299000D03*
X1324000Y290500D03*
X1324500Y345400D03*
Y341000D03*
X1329000Y341100D03*
Y345500D03*
X1323000Y368000D03*
X1327500D03*
X1332000D03*
X1318000Y369500D03*
X1332000Y372400D03*
X1327500D03*
X1323000D03*
X1318000Y375500D03*
Y381500D03*
X1330000Y428000D03*
X1331500Y432500D03*
X1330500Y452500D03*
X1324145Y668376D03*
X1320500Y671500D03*
X1331500Y703000D03*
X1342000Y107000D03*
X1338000Y341100D03*
X1333500D03*
Y345500D03*
X1338000D03*
X1342500Y452500D03*
X1350000Y105500D03*
X1349800Y257900D03*
X1354000Y281000D03*
X1358500Y346500D03*
Y351000D03*
X1354000D03*
Y346500D03*
X1349000Y399500D03*
X1358250Y445750D03*
X1351000Y452000D03*
X1354500Y480500D03*
Y475000D03*
X1360500D03*
Y480500D03*
X1354500Y486500D03*
X1360500D03*
X1360000Y631500D03*
X1355500Y631000D03*
X1358000Y626000D03*
X1357500Y635500D03*
X1351000Y677000D03*
Y672000D03*
X1355000Y674500D03*
X1354500Y669000D03*
Y703500D03*
X1371500Y254000D03*
X1366000D03*
X1371500Y264000D03*
X1366000D03*
X1371500Y259500D03*
X1366000D03*
X1377000Y277000D03*
X1381500Y288500D03*
X1376300Y289000D03*
X1365800Y306600D03*
X1378500Y370000D03*
Y365000D03*
Y360000D03*
X1377000Y384000D03*
Y379000D03*
X1378500Y374500D03*
X1377000Y390000D03*
X1374500Y395000D03*
Y402000D03*
X1375000Y409000D03*
X1372500Y415000D03*
X1372000Y495500D03*
X1384500Y271000D03*
Y327500D03*
G54D11*
X19272Y337795D03*
Y396850D03*
X98838Y337795D03*
Y396850D03*
G54D20*
X43520Y914388D03*
X48020D03*
X52520D03*
X57020D03*
X61520D03*
X66020D03*
X99804Y916420D03*
X103804D03*
X107804D03*
X111804D03*
X115804D03*
X119804D03*
X123804D03*
X127804D03*
X131804D03*
X135804D03*
X313000Y92700D03*
X330000Y87700D03*
X314453Y248552D03*
X344040Y210700D03*
X357040D03*
X348540D03*
X353040D03*
X351000Y396200D03*
X373200Y183240D03*
X371429Y207200D03*
X380829Y191300D03*
X393000Y944200D03*
X406555Y326700D03*
X405000Y944200D03*
X409000D03*
X397000D03*
X401000D03*
X425278Y812200D03*
X413000Y944200D03*
X417000D03*
X429940Y155000D03*
X444055Y298700D03*
X431778Y812200D03*
X431278Y875700D03*
X437778D03*
X456278Y812200D03*
X460778Y875700D03*
X462778Y812200D03*
X467278Y875700D03*
X544178Y968200D03*
X548555Y345200D03*
X554955Y371600D03*
X558955D03*
X641000Y475700D03*
X646500Y452200D03*
X678500Y410200D03*
X787000Y414700D03*
X1010500Y78200D03*
X1178500Y647700D03*
X1281000Y690700D03*
Y709200D03*
X1273000Y701700D03*
X1281000D03*
X1277000Y719700D03*
X1281000Y727700D03*
X1292500Y416700D03*
X1372300Y284400D03*
X1384300D03*
G54D30*
X195295Y301709D03*
X188295Y301209D03*
X195295Y307709D03*
X188295Y315209D03*
X184295Y305709D03*
X195795Y313709D03*
X189795Y308709D03*
X183795Y311709D03*
X483178Y861500D03*
G54D21*
G01X200000Y421500D02*
Y468000D01*
X172000Y496000D01*
Y523000D01*
X166639Y528361D01*
Y540639D01*
X170000Y544000D01*
Y570500D01*
X178000Y578500D01*
Y590000D01*
G01X216500Y421500D02*
X200000D01*
G01X345500Y556500D02*
X364000D01*
X370505Y549995D01*
Y547783D01*
X371255Y547033D01*
Y543967D01*
X370505Y543217D01*
Y518005D01*
X370500Y518000D01*
G01X709750Y585200D02*
X705500Y580950D01*
Y575600D01*
G01X740000Y634500D02*
Y615450D01*
X709750Y585200D01*
G01X740000Y681000D02*
Y634500D01*
G01D02*
X801500Y573000D01*
G01D02*
Y538000D01*
X774500Y511000D01*
Y489500D01*
G01X819000Y473000D02*
X818500Y472500D01*
Y469000D01*
X798000Y448500D01*
Y414000D01*
X804000Y408000D01*
Y394500D01*
X798000Y388500D01*
Y362500D01*
X792000Y356500D01*
G01X930500Y536500D02*
X924930Y530930D01*
Y455640D01*
X918420Y449130D01*
G01X961700Y477500D02*
X958500D01*
X938540Y457540D01*
X936030D01*
G01X961000Y495000D02*
X950500D01*
X943500Y488000D01*
G01X1015000Y477500D02*
X961700D01*
G01X961000Y495000D02*
X1013000D01*
X1019475Y488525D01*
X1049025D01*
X1074000Y513500D01*
X1193500D01*
X1217000Y537000D01*
G01X1027716Y914784D02*
Y913216D01*
X1016968Y902468D01*
X1007532D01*
G01X1211000Y712800D02*
X1214200D01*
X1216500Y710500D01*
Y710125D01*
G01X1352000Y85500D02*
Y69500D01*
X1341100Y58600D01*
X1333100D01*
X56000Y7500D03*
X57500Y993500D03*
X422678Y895000D03*
X483178Y821000D03*
X1322500Y69000D03*
X1367500Y995000D03*
G54D12*
G01X176938Y680465D02*
X161832Y665359D01*
Y626332D01*
X124000Y588500D01*
Y587078D01*
X121200Y584278D01*
G01X294500Y98500D02*
X297750D01*
G01X291000D02*
X294500D01*
G01X313250Y85250D02*
X317000D01*
G01X316598Y91500D02*
X315994D01*
X313744Y89250D01*
X313000D01*
G01D02*
X309875D01*
X307250Y91875D01*
G01X301250Y98500D02*
Y97250D01*
X299000Y95000D01*
Y88750D01*
X299750Y88000D01*
G01X310000Y102500D02*
X309750D01*
X305750Y98500D01*
G01D02*
X301250D01*
G01X312000Y292750D02*
Y295500D01*
X314500Y298000D01*
X322500D01*
G01X332500Y68500D02*
X331700Y68700D01*
X326000Y67700D01*
G01X330000Y87750D02*
X330250D01*
X333000Y90500D01*
G01X321500Y85250D02*
Y88000D01*
X323000Y89500D01*
G01Y93000D02*
Y89500D01*
G01X316598Y91500D02*
X318000D01*
X319309Y90191D01*
Y89503D01*
G01X322500Y298000D02*
X325750D01*
X329500Y294250D01*
G01D02*
X333250D01*
X335750Y291750D01*
Y291500D01*
G01X337500Y68500D02*
X332500D01*
G01X337500D02*
X339500Y70500D01*
Y75500D01*
G01X349000Y78000D02*
X343000Y84000D01*
Y89000D01*
G01X343250Y295375D02*
X353125D01*
X362500Y286000D01*
G01X352000Y66000D02*
Y75000D01*
X349000Y78000D01*
G01X363400Y134500D02*
X362400Y135500D01*
X360140D01*
G01X365600Y134500D02*
Y131571D01*
X365529Y131500D01*
G01X385600Y149500D02*
Y150461D01*
X384093Y151968D01*
G01X383400Y149500D02*
X381589D01*
X380888Y148799D01*
G01X380389Y164630D02*
Y161972D01*
X380944Y161417D01*
G01X387250Y190000D02*
X386967D01*
X384055Y192912D01*
G01X403600Y148500D02*
X405821D01*
X406125Y148804D01*
G01X401400Y148500D02*
Y150412D01*
X402938Y151950D01*
G01X438000Y245000D02*
X454500D01*
X456000Y243500D01*
G01X430250Y241000D02*
X432500D01*
X436500Y245000D01*
X438000D01*
G01X430250D02*
X432500D01*
X435000Y247500D01*
X456000D01*
X460000Y243500D01*
G01X464000D02*
X460000D01*
G01X647500Y425500D02*
X666250Y406750D01*
X670919D01*
G01X654875Y434750D02*
X657025Y432600D01*
X659700D01*
G01X678500Y406750D02*
X670919D01*
G01X660500Y436538D02*
Y433400D01*
X659700Y432600D01*
G01X691400Y231100D02*
X691000Y231500D01*
Y292500D01*
X687500Y296000D01*
Y311000D01*
X691000Y314500D01*
Y321500D01*
X698000Y328500D01*
Y431500D01*
X692962Y436538D01*
X660500D01*
G01X678400Y402350D02*
X678500Y402450D01*
Y406750D01*
G01X788774Y482774D02*
X778383D01*
X777609Y482000D01*
X775048D01*
X772024Y478976D01*
G01X787000Y406500D02*
Y411250D01*
G01D02*
X789750D01*
X791000Y412500D01*
Y466603D01*
G01X778688Y470790D02*
X779000Y470478D01*
Y458000D01*
G01X778688Y470790D02*
X778114Y471364D01*
Y476714D01*
X776000Y478828D01*
G01X788774Y482774D02*
X805926D01*
X811600Y477100D01*
G01X823500Y480000D02*
Y466500D01*
X803500Y446500D01*
Y423500D01*
X808500Y418500D01*
Y363500D01*
G01X796074Y479000D02*
X791000Y473926D01*
Y466603D01*
G01X811600Y477100D02*
X814500Y474200D01*
Y472500D01*
G01X860400Y231000D02*
X882000D01*
X885500Y234500D01*
X1039097D01*
X1053800Y219797D01*
X1054487D01*
X1055000Y219284D01*
G01X882500Y339500D02*
X884500Y337500D01*
Y323500D01*
G01X879510Y355410D02*
X879500Y355400D01*
Y347797D01*
X879520Y347777D01*
Y345953D01*
X879500Y345933D01*
Y342500D01*
X882500Y339500D01*
G01X1015500Y871500D02*
Y885536D01*
X1031464Y901500D01*
X1032657D01*
G01X1027504Y853366D02*
X1015500Y865370D01*
Y871500D01*
G01X1025500Y129500D02*
Y128500D01*
X1030000Y124000D01*
X1033500D01*
G01X1025500Y140500D02*
Y129500D01*
G01X1035750Y141000D02*
Y141250D01*
X1025800Y151200D01*
Y167800D01*
X1036000Y178000D01*
G01X1023000Y155000D02*
Y150000D01*
X1025500Y147500D01*
Y140500D01*
G01X1023000Y155000D02*
Y171500D01*
X1023600Y172100D01*
Y173000D01*
G01X1040000Y182000D02*
X1036000Y178000D01*
G01X1027504Y853366D02*
X1042945Y837925D01*
X1109075D01*
X1111000Y836000D01*
G01X1054000Y124500D02*
X1049585D01*
X1037085Y137000D01*
G01X1039250Y141000D02*
Y139644D01*
X1041485Y137409D01*
G01X1039250Y145500D02*
Y141000D01*
G01Y145500D02*
X1070000D01*
G01X1060250Y124500D02*
Y120500D01*
G01X1054000Y124500D02*
X1060250D01*
G01X1061000Y211500D02*
X1063500Y214000D01*
X1086000D01*
X1091500Y208500D01*
Y149500D01*
X1087500Y145500D01*
X1070000D01*
G01X1294600Y524200D02*
X1291800D01*
X1273726Y506126D01*
X1247287D01*
X1207910Y466749D01*
X1128251D01*
X1127409Y467591D01*
X1101091D01*
X1098500Y465000D01*
G01X1099500Y866000D02*
Y869000D01*
X1099623Y869123D01*
G01X1181500Y949000D02*
X1167000Y963500D01*
X1158888D01*
X1107160Y911772D01*
Y843160D01*
G01X1129260Y714350D02*
Y716740D01*
X1128000Y718000D01*
G01X1248250Y439250D02*
X1256500Y431000D01*
G01X1256000Y252000D02*
X1269000D01*
G01X1256500Y431000D02*
X1264500Y423000D01*
X1280612D01*
X1284000Y419612D01*
Y416001D01*
X1290751Y409250D01*
X1292500D01*
G01X1288000Y470000D02*
X1267580D01*
X1259209Y461629D01*
X1251371D01*
X1251000Y462000D01*
X1250450D01*
G01X1299500Y236000D02*
X1288500D01*
X1272500Y252000D01*
X1269000D01*
G01X1292500Y409250D02*
Y413250D01*
G01X1288000Y470000D02*
X1295500D01*
X1300500Y475000D01*
X1302000D01*
G01X1330500Y441000D02*
Y452500D01*
G01D02*
Y457750D01*
X1332000Y459250D01*
G01X1339500Y394500D02*
X1340750Y395750D01*
Y399500D01*
G01D02*
X1357000Y415750D01*
Y444000D01*
X1358250Y445250D01*
Y445750D01*
G01X1342500Y452500D02*
X1335000Y445000D01*
Y443250D01*
G01X1362500Y459000D02*
X1349000D01*
X1342500Y452500D01*
G01X1358250Y456000D02*
Y445750D01*
G01X1368000Y458600D02*
X1362900D01*
X1362500Y459000D01*
G01X1353500Y466500D02*
X1377000D01*
X1381000Y462500D01*
Y415000D01*
X1375000Y409000D01*
G01X1354750Y456000D02*
X1354500Y455750D01*
X1351000D01*
G01Y452000D02*
Y455750D01*
G01X1370500Y356500D02*
Y404500D01*
X1375000Y409000D01*
X21220Y373228D03*
X15000Y1008622D03*
X35435Y373228D03*
X82675D03*
X90119Y72219D03*
X96890Y373228D03*
X157480Y283071D03*
X220472D03*
X227041Y1008622D03*
X270078Y92125D03*
Y155117D03*
X332086Y408858D03*
X355708Y96456D03*
X450196Y257874D03*
X490944Y79921D03*
Y255118D03*
X537994Y303150D03*
X572243Y337992D03*
X600925Y44134D03*
X638917D03*
X653974Y1008621D03*
X743897Y353543D03*
Y410629D03*
X825984Y303150D03*
X945197Y380000D03*
X955315Y850829D03*
X968819Y380000D03*
X1008268Y244094D03*
Y411417D03*
X1157095Y128841D03*
X1227166Y155511D03*
X1224016Y180709D03*
Y386221D03*
X1227165Y411417D03*
X1272441Y7087D03*
X1299213D03*
X1305117Y87548D03*
Y262745D03*
X1379862Y108465D03*
Y119095D03*
X1376968Y147243D03*
Y216535D03*
X1385000Y1008622D03*
X1387875Y-15015D03*
G54D40*
X314753Y235852D03*
X307153D03*
X314753Y227852D03*
X307153D03*
X389629Y181700D03*
X382029D03*
X389600Y206929D03*
X382000D03*
X394355Y441000D03*
X386755D03*
X458355Y314600D03*
X471887Y302717D03*
X464287D03*
X465955Y314600D03*
X472455D03*
X480055D03*
X486478Y875500D03*
X494078D03*
X486478Y867500D03*
X494078D03*
X506629Y141000D03*
X499055Y337700D03*
X506655D03*
X499755Y385500D03*
X507355D03*
X499755Y400500D03*
X507355D03*
X514229Y141000D03*
X656162Y465964D03*
X663762D03*
X688300Y446000D03*
X680700D03*
X718948Y107500D03*
X726548D03*
X1050200Y140500D03*
X1057800D03*
X1275300Y433000D03*
X1267700D03*
G54D22*
X59504Y669720D03*
X60536Y693503D03*
Y690003D03*
X64972Y822004D03*
X77472Y730004D03*
X74472Y752504D03*
X70004Y853220D03*
X94504Y669720D03*
X95036Y694003D03*
Y690503D03*
X337129Y201500D03*
X348255Y538500D03*
Y542500D03*
X369689Y215420D03*
X377389Y215390D03*
X385069Y215400D03*
X405229Y165000D03*
X405129Y170500D03*
X412629D03*
X412729Y165000D03*
X405129Y183500D03*
Y177000D03*
X412629D03*
Y183500D03*
X405129Y190000D03*
X412629D03*
X427240Y139000D03*
X419740D03*
X420229Y165000D03*
X420129Y170500D03*
Y177000D03*
Y183500D03*
Y190000D03*
X434740Y139000D03*
X444255Y372500D03*
X455629Y118000D03*
X456755Y372500D03*
X464255D03*
X483629Y158500D03*
Y172500D03*
Y166000D03*
Y179000D03*
X487978Y832000D03*
X498655Y351500D03*
Y347500D03*
X522129Y141000D03*
X706916Y122784D03*
Y133284D03*
Y126284D03*
Y129784D03*
X1140668Y688284D03*
X1141800Y684800D03*
X1160800Y679300D03*
X1255700Y719500D03*
G54D31*
X200000Y391500D03*
Y401500D03*
Y411500D03*
Y421500D03*
X216500Y391500D03*
Y401500D03*
Y411500D03*
Y421500D03*
X1296000Y319500D03*
Y329500D03*
X1367067Y42323D03*
Y60039D03*
Y78544D03*
Y96260D03*
X1392657Y42323D03*
Y60039D03*
Y78544D03*
Y96260D03*
G54D13*
G01X427028Y824500D02*
X428278D01*
X431078Y827300D01*
X432678D01*
G01X1170218Y700284D02*
X1171656D01*
X1173350Y698590D01*
X8200Y857700D03*
X8000Y853500D03*
X8442Y847311D03*
X35304Y832220D03*
X34304Y897720D03*
X50395Y384679D03*
X40945Y384710D03*
X47483Y387776D03*
X43883Y387769D03*
X48820Y412435D03*
X39370Y412673D03*
X52000Y655500D03*
X40054Y823970D03*
X44804Y837220D03*
X36004Y839500D03*
X44500Y851500D03*
X49000Y861500D03*
X52000Y872720D03*
X37232Y877242D03*
X51896Y878668D03*
X42554Y891720D03*
X37211Y881115D03*
X37758Y884674D03*
X40304Y887220D03*
X51304Y882220D03*
X47804Y906720D03*
X43804Y907720D03*
X38804Y906220D03*
X41304Y927220D03*
X50270Y929186D03*
X41500Y941500D03*
X46500Y944500D03*
X59840Y384679D03*
X62783Y387776D03*
X66483Y387876D03*
X56883D03*
X53183Y387676D03*
X67715Y412518D03*
X58270Y412485D03*
X60304Y663220D03*
X55304Y669720D03*
X58804Y710220D03*
X64304Y698720D03*
X63304Y706720D03*
X68147Y722511D03*
X62704Y739620D03*
X64272Y736004D03*
X55304Y746220D03*
X65272Y758504D03*
X64683Y762056D03*
X59272Y790504D03*
X57772Y801504D03*
X61492Y803004D03*
X55022Y826720D03*
X66022Y827254D03*
X57304Y815720D03*
X61304Y815220D03*
X65804Y835720D03*
X57804Y834720D03*
X61804D03*
X55304Y849720D03*
X52304Y868220D03*
X60804Y907720D03*
X56804Y907220D03*
X52304Y906720D03*
X64804Y907720D03*
X52804Y943220D03*
X57770Y932686D03*
X55270Y929186D03*
X52770Y932686D03*
X62770D03*
X60270Y929186D03*
X52804Y938795D03*
X78740Y384915D03*
X69290Y384865D03*
X71883Y387976D03*
X76083D03*
X77165Y412590D03*
X76804Y662720D03*
Y710220D03*
X73804Y699720D03*
X81304Y710220D03*
X71846Y722426D03*
X77272Y724004D03*
X75432Y735059D03*
X83849Y735513D03*
X80272Y735103D03*
X68910Y760642D03*
X83112Y760720D03*
X75432Y758844D03*
X76272Y762504D03*
X80624Y764241D03*
X68762Y764239D03*
X77804Y773720D03*
X71804Y789720D03*
X82804Y794920D03*
X84804Y808720D03*
X73772Y822004D03*
X79000Y836500D03*
X69804Y835720D03*
X84221Y836078D03*
X77500Y832000D03*
X83838Y848133D03*
X76804Y847720D03*
X70909Y847325D03*
X72304Y869720D03*
X76304D03*
X81304Y884470D03*
X81804Y888720D03*
X72770Y906488D03*
X95304Y663720D03*
X89804Y669720D03*
X95304Y686220D03*
X97737Y698653D03*
X94804Y708220D03*
X99804Y709220D03*
X87772Y735059D03*
X92365Y735040D03*
X85672Y763504D03*
X96060Y762476D03*
X86404Y774720D03*
X85304Y768720D03*
X100804Y774720D03*
X93347Y765754D03*
X99804Y799720D03*
X85204Y798220D03*
X85804Y816220D03*
X92304Y835720D03*
X87804D03*
X87928Y848107D03*
X98304Y888220D03*
X95700Y926300D03*
X97804Y940720D03*
X112654Y314453D03*
X111304Y663720D03*
X111907Y698617D03*
X115804Y798720D03*
X105000Y834500D03*
X113222Y831222D03*
X112500Y835000D03*
X110500Y848500D03*
X115500D03*
X109054Y892720D03*
X102304Y895220D03*
X114054Y892720D03*
X106554Y895720D03*
X116554D03*
X111554Y896220D03*
X105804Y943220D03*
X109054Y932720D03*
X116600Y929924D03*
X114054Y932470D03*
X111554Y929720D03*
X101804Y940720D03*
X108804Y938795D03*
X115500Y983500D03*
X127654Y293453D03*
X132500Y312500D03*
X124500Y316000D03*
X131500Y324000D03*
X122906Y331953D03*
X122874Y354709D03*
X127301D03*
X131147D03*
X132500Y547000D03*
Y559600D03*
Y556000D03*
Y551500D03*
X133500Y582500D03*
X125050Y583000D03*
X126500Y587500D03*
X121685Y587919D03*
X134000Y587000D03*
X130000Y666500D03*
X129304Y798720D03*
X122500Y845500D03*
X128000Y870500D03*
X129100Y892924D03*
X124054Y892220D03*
X121600Y895266D03*
X119054Y892720D03*
X132804Y894220D03*
X126554Y895470D03*
X121598Y929924D03*
X131554Y929470D03*
X129054Y932720D03*
X126554Y929882D03*
X124098Y932515D03*
X119099Y932516D03*
X118000Y991500D03*
X145500Y283500D03*
X134874Y354709D03*
X147374D03*
X143147D03*
X139301D03*
X147500Y472100D03*
X135500Y511000D03*
X136000Y566000D03*
X136500Y576900D03*
Y573300D03*
Y580500D03*
Y569700D03*
X140500Y568000D03*
X144000Y572500D03*
X149100Y661100D03*
X143010Y676400D03*
X143500Y710500D03*
X141054Y795820D03*
X150225Y790412D03*
X146304Y804220D03*
X146500Y808220D03*
X162595Y296709D03*
X165793Y294309D03*
X153437Y320458D03*
X155874Y310209D03*
Y313961D03*
Y317807D03*
X152995Y329119D03*
X159674Y328609D03*
X159774Y320709D03*
X164147Y328699D03*
X155874Y326957D03*
Y323111D03*
X158874Y354709D03*
X155147D03*
X162801D03*
X166647D03*
X151301D03*
X160000Y465500D03*
X158500Y461500D03*
X153050Y486500D03*
X163225Y522080D03*
X154625Y550290D03*
X154755Y539310D03*
X163305Y554750D03*
X160500Y586500D03*
X156900D03*
X152948Y587000D03*
X166000Y662500D03*
X157750Y662250D03*
X166500Y650500D03*
X166875Y678285D03*
X162500Y670000D03*
X153500Y690275D03*
X163000Y710500D03*
X150900Y812500D03*
X154500D03*
X152500Y840000D03*
X157500Y867500D03*
X163000Y901000D03*
X158000D03*
X172285Y296964D03*
X181889Y297303D03*
X169639Y294309D03*
X179088Y294909D03*
X175242D03*
X183374Y328709D03*
X171874D03*
X171295Y320709D03*
X180315Y321209D03*
X167993Y328699D03*
X179622Y328749D03*
X175776D03*
X170374Y354709D03*
X182800Y465800D03*
Y471300D03*
X171500Y478699D03*
X177493Y533493D03*
X170339Y537396D03*
X180555Y560500D03*
X175993Y559938D03*
X175055Y569500D03*
X167469Y588969D03*
X172040Y688960D03*
X174000Y830500D03*
X170500Y835500D03*
X179500Y847000D03*
X172000Y868000D03*
X168400D03*
X183000Y865750D03*
X181000Y901000D03*
X174500Y901500D03*
X168500Y901000D03*
X197245Y296571D03*
X188295Y297209D03*
X193841Y297755D03*
X185039Y295209D03*
X191295D03*
X196063Y319209D03*
X186614Y319028D03*
X190295Y318709D03*
X192874Y326209D03*
X198864Y323297D03*
X192874Y334307D03*
Y330461D03*
X184295Y322209D03*
X192795Y321709D03*
X192874Y337907D03*
X189000Y347600D03*
X192874Y341611D03*
Y345457D03*
X192500Y431500D03*
X187300Y457300D03*
X191800D03*
X190800Y462800D03*
X189355Y526470D03*
X185000Y533562D03*
X185305Y521100D03*
X195725Y540750D03*
X195865Y552940D03*
X198500Y563000D03*
X189500Y573500D03*
X194500Y724000D03*
X198000Y785000D03*
X191875Y803125D03*
X186000Y841500D03*
X185000Y856000D03*
X185500Y848260D03*
X187000Y878000D03*
X199000Y891500D03*
X190500Y894000D03*
X195000Y891500D03*
X188000Y901000D03*
X197000D03*
Y897000D03*
X207086Y297418D03*
X204285Y294909D03*
X213733D03*
X200439D03*
X209887D03*
X205511Y320709D03*
X214960Y321044D03*
X208338Y323297D03*
X202710D03*
X212134D03*
X212500Y435000D03*
X204500Y470000D03*
X207773Y516562D03*
X208305Y548670D03*
Y536320D03*
Y562640D03*
X203000Y564500D03*
X201000Y625500D03*
X212500Y716500D03*
X204500Y721000D03*
X212500Y786000D03*
X204500Y817500D03*
X215250Y833750D03*
X205500Y830000D03*
X204000Y862000D03*
X212000Y891500D03*
X203500Y894000D03*
X208000Y892000D03*
X205500Y901000D03*
Y897000D03*
X217295Y296709D03*
X232500Y419000D03*
Y431000D03*
Y425000D03*
X229055Y497000D03*
X216500Y516000D03*
X228319Y524798D03*
X230000Y680500D03*
X221000Y723000D03*
X218000Y801500D03*
X223500Y825500D03*
X228000Y825000D03*
X232000D03*
X227000Y858000D03*
X217000Y858500D03*
X222000Y853500D03*
Y858500D03*
Y863500D03*
Y893600D03*
X231500Y898500D03*
X243755Y490890D03*
X242003Y506327D03*
X234755Y509700D03*
X245205Y504679D03*
X246613Y501365D03*
X237055Y513500D03*
X234185Y527138D03*
X248855Y532300D03*
X239555Y519500D03*
X240000Y829250D03*
X247500Y829500D03*
X237953Y861453D03*
X236500Y866000D03*
X259055Y500500D03*
X260288Y514589D03*
X264655Y511100D03*
X250055Y510800D03*
X256055Y531016D03*
X260555Y525500D03*
X253679Y523137D03*
X260605Y519245D03*
X263555Y534500D03*
X261255Y549000D03*
X265455Y544853D03*
X252055Y548760D03*
X257555Y549000D03*
X258500Y608500D03*
Y613500D03*
X253500Y608500D03*
X253555Y613500D03*
X251000Y835500D03*
X251500Y855500D03*
X261500Y857500D03*
X252000Y846500D03*
X252500Y851500D03*
X250362Y865000D03*
X253610Y863447D03*
X268300Y219800D03*
X279997Y514179D03*
X275555Y531500D03*
X275055Y521825D03*
X266055Y531725D03*
X272571Y541150D03*
X278367Y535140D03*
X269555Y536000D03*
X271451Y544616D03*
X278676Y539500D03*
X273000Y674000D03*
X270000Y870000D03*
Y865500D03*
X276500Y888500D03*
X269000Y921500D03*
X274000D03*
X280500Y955000D03*
X278050Y958500D03*
X273678Y958000D03*
X268178Y955500D03*
X296200Y94400D03*
X294500Y98500D03*
X297929Y332000D03*
Y336000D03*
X293929Y342000D03*
X292525Y498780D03*
X292045Y504897D03*
X293273Y509500D03*
X282626Y516639D03*
X291530Y525407D03*
X283103Y520208D03*
X286588Y519305D03*
X292555Y533043D03*
X291755Y529000D03*
X286555Y524524D03*
X282555Y540700D03*
X283038Y536850D03*
X299300Y84200D03*
X309500Y78500D03*
X313250Y85250D03*
X311500Y81500D03*
X314000Y102500D03*
X302000Y94300D03*
X299831Y144328D03*
X303677D03*
X313402Y156000D03*
X305852Y163800D03*
X309698D03*
X305429Y219400D03*
Y223000D03*
X307500Y299000D03*
X299395Y449160D03*
X303545Y445840D03*
X312925Y462560D03*
X300112Y483783D03*
X298662Y479783D03*
X305055Y472500D03*
X302555Y476000D03*
X312773Y529878D03*
X305255Y542600D03*
X313000Y582000D03*
X324500Y6000D03*
Y10500D03*
X316900Y65900D03*
X320500Y66000D03*
X327000Y89500D03*
X323000D03*
X319309Y89503D03*
X317500Y101000D03*
X317660Y96400D03*
X324200Y101900D03*
X330000Y118500D03*
X325929D03*
X321500D03*
X329929Y128500D03*
X325929Y127700D03*
X327100Y136294D03*
Y139857D03*
X326422Y152507D03*
Y148944D03*
X317248Y156000D03*
X319800Y146898D03*
Y143052D03*
X322229Y218800D03*
X316129Y213000D03*
X329929Y241500D03*
X328000Y285000D03*
X326000Y292500D03*
X327000Y308000D03*
X331000Y308018D03*
X330555Y467500D03*
X325873Y477006D03*
X325854Y480606D03*
X317195Y493280D03*
X317255Y514170D03*
X330491Y525490D03*
X315725Y549790D03*
X321555Y534500D03*
X329695Y534650D03*
X315135Y554980D03*
X317758Y581297D03*
X329055Y569500D03*
X321780Y575000D03*
X314930Y585500D03*
X321500Y688000D03*
X336700Y4300D03*
X341200D03*
X346000Y4400D03*
X333000Y90500D03*
X343000Y89000D03*
X339500Y75500D03*
X337500Y84250D03*
X342000Y102000D03*
X346000D03*
X334500Y118500D03*
X334600Y129468D03*
Y133031D03*
X345929Y183000D03*
X340679Y204900D03*
X332429Y210000D03*
X346404Y260000D03*
X344429Y312000D03*
X341500Y309500D03*
X343929Y320700D03*
X345929Y336500D03*
X341351Y336434D03*
X344929Y325500D03*
X342500Y340000D03*
X338500Y397500D03*
X343095Y446200D03*
X336375Y452870D03*
X338985Y467405D03*
X338595Y482590D03*
X339140Y512500D03*
X336445Y509330D03*
X343555Y517000D03*
X343688Y509533D03*
X334055Y526000D03*
X347213Y546700D03*
X340715Y545840D03*
X334555Y548500D03*
X341055Y534500D03*
X344655D03*
X345500Y556500D03*
X339888Y586388D03*
X346402Y653004D03*
X342500Y653000D03*
X335500Y868000D03*
X332129Y889371D03*
X331829Y885500D03*
X338000Y942000D03*
X339500Y936500D03*
Y960000D03*
X333500Y954000D03*
X355000Y4400D03*
X350500D03*
X360400D03*
X352000Y66000D03*
X357500Y79500D03*
Y75500D03*
X352500Y113000D03*
X348429Y130000D03*
X353929Y128500D03*
X351429Y126500D03*
X353300Y218400D03*
X362500Y286000D03*
X348000Y292500D03*
X351929Y332500D03*
X357055Y385000D03*
Y380500D03*
Y376500D03*
X355055Y394000D03*
Y389500D03*
X364015Y468450D03*
X349575Y479503D03*
X349815Y475550D03*
X364055Y512000D03*
X358797Y532258D03*
X354055Y534000D03*
X352095Y524040D03*
X362555Y534500D03*
X351815Y546880D03*
X348255Y534500D03*
X360500Y588500D03*
X350000Y652878D03*
X362210Y876200D03*
X364000Y869500D03*
X363480Y907783D03*
X362000Y904500D03*
X363000Y931500D03*
X359000D03*
X354000Y960000D03*
X363614Y971524D03*
X361000Y974000D03*
X360024Y979100D03*
X364900Y4400D03*
X369400D03*
X366600Y285800D03*
X377855Y300110D03*
X374000Y293500D03*
X372055Y319500D03*
X369555Y322500D03*
X371555Y347500D03*
X372055Y364000D03*
X375805Y380250D03*
X370275Y413540D03*
X371710Y406535D03*
X369555Y417500D03*
X370575Y409952D03*
X375055Y444500D03*
X367022Y482783D03*
X373555Y482500D03*
X378255Y471840D03*
X379000Y531000D03*
X367555Y545500D03*
X380000Y872000D03*
X371000Y866500D03*
X376041Y866041D03*
X375500Y906000D03*
Y901500D03*
X365500Y916000D03*
X369341Y916117D03*
X371100Y926000D03*
X377000Y927500D03*
X372300Y918749D03*
X371938Y922438D03*
X369500Y936500D03*
X368000Y932000D03*
X371000Y930000D03*
X376000Y960000D03*
X364396Y980109D03*
X366878Y977500D03*
X369200Y980252D03*
X372500Y977918D03*
X377464Y987493D03*
X377250Y982250D03*
X390000Y13500D03*
X385000D03*
X391000Y238500D03*
X395500Y237000D03*
X388000Y233500D03*
X388149Y229780D03*
X393429Y229500D03*
X394929Y247000D03*
X395450Y265400D03*
X390100Y263600D03*
X387500Y261000D03*
X381500Y297000D03*
X395104Y291056D03*
X382455Y331870D03*
X386755Y447300D03*
X393055Y451000D03*
Y447400D03*
X385463Y450948D03*
X396055Y456500D03*
X386055Y454500D03*
X388885Y471100D03*
X381500Y534000D03*
X384046Y536546D03*
X389000Y604000D03*
X396000Y714500D03*
X392500Y718500D03*
X391000Y866500D03*
X395500Y867000D03*
X396500Y888500D03*
X396600Y895855D03*
X396330Y899705D03*
X396500Y904000D03*
X384000Y926500D03*
X389838Y942300D03*
X383500Y938500D03*
X388500Y955250D03*
X390000Y946500D03*
X397900Y231800D03*
X409929Y245400D03*
X399500Y240500D03*
X412513Y294800D03*
X398385Y292540D03*
X401855Y293500D03*
X408656Y291500D03*
X405555Y293500D03*
X401555Y318000D03*
X406555Y320500D03*
X403255Y425950D03*
X404500Y877300D03*
X410500Y885500D03*
X397600Y892000D03*
X399500Y901500D03*
X403250Y949000D03*
X408250Y949500D03*
X410500Y954500D03*
X405704Y952046D03*
X398250Y955000D03*
X400750Y952000D03*
X410000Y983500D03*
X410500Y987500D03*
X401500Y994500D03*
X414000Y8000D03*
X418192Y114237D03*
X421000Y231500D03*
X420429Y246400D03*
X424929Y264700D03*
X428100Y266500D03*
X419600Y282900D03*
X416500Y284800D03*
X422500Y271501D03*
X419455Y293000D03*
X416187Y294711D03*
X429500Y311000D03*
X425178Y798000D03*
X425278Y802000D03*
X418278Y828000D03*
Y840000D03*
X418500Y857500D03*
X418278Y854000D03*
Y846500D03*
X416046Y959546D03*
X414500Y948500D03*
X414215Y952089D03*
X422098Y948630D03*
X418500Y948500D03*
X413500Y957000D03*
X416000Y964000D03*
X420000D03*
X413600Y983500D03*
X425000Y994500D03*
X440000Y5000D03*
X438500Y9000D03*
X433929Y100000D03*
X430540Y108750D03*
X439000Y254500D03*
X440500Y267000D03*
X433929Y264300D03*
X439800Y284100D03*
X444255Y283700D03*
X430900Y294550D03*
X439200D03*
X432500Y301000D03*
X435000Y294000D03*
X436416Y357676D03*
X432178Y798000D03*
X438178Y798500D03*
X444678Y798400D03*
X444778Y802100D03*
X438278D03*
X431778Y802000D03*
X442278Y846000D03*
X431500Y886000D03*
X437678D03*
X443178D03*
X431278Y883000D03*
X444278D03*
X437778D03*
X432000Y933500D03*
X430500Y962000D03*
X460000Y5000D03*
X459429Y106000D03*
X448929Y99500D03*
X457500Y121000D03*
X450929Y118000D03*
X457429Y171500D03*
X462500Y169000D03*
X455054Y179475D03*
X458429Y175590D03*
X456000Y243500D03*
X460000D03*
X461100Y260050D03*
X459055Y263500D03*
X459500Y290100D03*
X458685Y425710D03*
X456178Y798000D03*
X452978Y805400D03*
X456278Y802100D03*
X455278Y846000D03*
X451278D03*
X459278D03*
X451178Y886000D03*
X460678D03*
X457578Y879700D03*
X450778Y883000D03*
X460778D03*
X471290Y118361D03*
X469000Y113000D03*
X472990Y113350D03*
X462700Y120800D03*
X471429Y133500D03*
X477291Y147500D03*
X477900Y153600D03*
X471000Y141000D03*
X477929Y158000D03*
X467600Y158400D03*
X465600Y162000D03*
X475216Y182917D03*
X470000Y188500D03*
X462679Y176900D03*
X466700Y259400D03*
X464055Y256500D03*
X469155Y297800D03*
X463371Y290371D03*
X474755Y308300D03*
X464200Y307838D03*
X463945Y349700D03*
X466655Y425340D03*
X472055Y425000D03*
X475678Y798500D03*
X463178D03*
X469178D03*
X475778Y802100D03*
X462778D03*
X469278D03*
X467278Y846000D03*
X468178Y886000D03*
X472178D03*
X473778Y883000D03*
X467278D03*
X485000Y5000D03*
X488500Y114200D03*
X481929Y126500D03*
X481429Y150000D03*
X490100Y162100D03*
X491257Y315952D03*
X495103D03*
X487612Y318606D03*
X492555Y431250D03*
X482178Y886000D03*
X480278Y883000D03*
X488000Y904500D03*
X483500Y907500D03*
X503929Y127500D03*
X499390Y153500D03*
X503500D03*
X503929Y146500D03*
X506429Y149500D03*
X495929Y164500D03*
X499629Y178400D03*
X498855Y302851D03*
X508500Y320000D03*
X504453Y314200D03*
X500607D03*
X496155Y321700D03*
X495555Y369500D03*
X507355Y390800D03*
X505922Y415371D03*
X506163Y419973D03*
X508100Y605500D03*
X506000Y610000D03*
X497778Y843000D03*
Y838500D03*
Y847000D03*
X498500Y867500D03*
X515000Y5000D03*
X513200Y121450D03*
X521700Y114000D03*
X525679Y136250D03*
X517679Y125750D03*
X513000Y156500D03*
X512000Y320000D03*
X519706Y314000D03*
X515860D03*
X527002Y319359D03*
X523348D03*
X526500Y346532D03*
Y342969D03*
Y352969D03*
X520500Y351500D03*
Y347937D03*
Y358937D03*
X526500Y356532D03*
X520500Y362500D03*
X521500Y632500D03*
X533000Y153800D03*
X528500Y172000D03*
X539714Y179150D03*
X542500Y188500D03*
X537479Y197875D03*
X539073Y237300D03*
X531590Y297620D03*
X534500Y295500D03*
X528500Y310000D03*
X534629Y311171D03*
X534960Y321000D03*
X538614D03*
X529848Y325500D03*
X533502D03*
X545000Y5000D03*
X550500Y188000D03*
X560500Y186000D03*
X555500Y194000D03*
X559500D03*
X545000Y195000D03*
X549926Y204000D03*
X557275Y214918D03*
X553675Y215913D03*
X550075D03*
X559961Y209419D03*
X546916Y217641D03*
X548000Y231000D03*
X547746Y225303D03*
X559971Y237753D03*
X553555Y321000D03*
X560253Y329500D03*
X557061Y334194D03*
X553155Y334300D03*
X548000Y369500D03*
X555935Y363000D03*
X559500Y604500D03*
X575000Y5000D03*
X577000Y58000D03*
X572000Y189000D03*
X571398Y183602D03*
X561429Y174441D03*
X575500Y198400D03*
X576650Y204500D03*
X563100Y194000D03*
X568158Y206455D03*
X571461Y207887D03*
X569000Y217000D03*
X569127Y213100D03*
X564583Y206028D03*
X577119Y233139D03*
X564631Y234356D03*
X569322Y234220D03*
X573179Y233535D03*
X575425Y228505D03*
X574000Y269000D03*
X563704Y272000D03*
X563555Y333000D03*
X571555Y326000D03*
X562055Y347500D03*
X564215Y369339D03*
X566430Y366500D03*
X569555Y364000D03*
X562555Y364500D03*
X587175Y202525D03*
X591413Y199087D03*
X583500Y204500D03*
X585325Y198000D03*
X583325Y208500D03*
X583204Y236805D03*
X580709Y232091D03*
X619876Y195000D03*
X617828Y303250D03*
X613962D03*
X623500Y576500D03*
X622500Y608500D03*
X633578Y303250D03*
X629712D03*
X642800Y433587D03*
X641500Y449500D03*
X636500Y444800D03*
X640500Y444500D03*
X641625Y465375D03*
X635325Y457500D03*
X628250Y570200D03*
X628524Y591976D03*
X646500Y101000D03*
X650500D03*
X649323Y303250D03*
X645457D03*
X647125Y429375D03*
X652714Y428214D03*
X647500Y425500D03*
X645500Y459500D03*
X656162Y472338D03*
X654500Y494000D03*
X654300Y490300D03*
X647252Y576500D03*
X674469Y99380D03*
X674358Y103170D03*
X662248Y101000D03*
X667748Y104000D03*
X665073Y303250D03*
X661207D03*
X663500Y452000D03*
X672500D03*
X660000Y443500D03*
X669025Y441725D03*
X660500Y436538D03*
X663500Y456000D03*
Y460500D03*
X667500Y454000D03*
Y458500D03*
X672500Y456000D03*
Y460500D03*
X669462Y472500D03*
X667056Y475500D03*
X673010Y474436D03*
X673300Y579000D03*
X669000D03*
X663500Y610500D03*
X674688Y696751D03*
X670474Y808700D03*
X671500Y861000D03*
X673500Y864000D03*
X672000Y967750D03*
X667000Y969700D03*
X666750Y961550D03*
X685000Y5000D03*
X685519Y55019D03*
X676748Y52000D03*
X684861Y58584D03*
X686000Y62000D03*
X684197Y74703D03*
X687055Y258500D03*
X683055D03*
X678055D03*
X681000Y452000D03*
X687500Y440500D03*
X681000Y456000D03*
Y460500D03*
X676500Y454000D03*
Y458500D03*
X690000Y460500D03*
X677500Y472500D03*
X688500Y606000D03*
X683000Y603950D03*
X677500Y612000D03*
X680000Y640000D03*
X691000Y704500D03*
X677500Y699000D03*
X682968Y758284D03*
X687968Y755284D03*
X677500Y773500D03*
X687968Y781784D03*
X678468Y805284D03*
X691300Y807300D03*
X679000Y865050D03*
X676500Y967750D03*
X695000Y20000D03*
X700000Y60500D03*
X706716Y82448D03*
X706055Y258500D03*
X705500Y575600D03*
X705900Y569200D03*
X698818Y759350D03*
X702918Y782734D03*
X703328Y800144D03*
X697250Y876750D03*
X704000Y892500D03*
X715000Y5000D03*
X725000Y20000D03*
X716034Y53966D03*
X716466Y65466D03*
X711216Y82402D03*
X720216Y82138D03*
X715716Y82652D03*
X713716Y121284D03*
X721716Y112784D03*
Y116784D03*
X717716Y121284D03*
X721716D03*
Y129284D03*
Y125284D03*
X711500Y179400D03*
X721200Y205800D03*
X710055Y258500D03*
X714055D03*
X725000Y452300D03*
X720700Y564200D03*
X717036Y563783D03*
X709750Y585200D03*
X719918Y754734D03*
X715118Y776134D03*
X723168Y774984D03*
X717468Y810784D03*
X722000Y808500D03*
X720500Y860000D03*
X712500Y859750D03*
X716250Y860250D03*
X710750Y863250D03*
X714000Y867500D03*
X714500Y891000D03*
X728966Y53966D03*
Y65466D03*
X740500Y75000D03*
X729716Y121284D03*
X725716D03*
X733498Y180750D03*
X733000Y193000D03*
X728100Y213800D03*
X732500Y455500D03*
X736000Y464500D03*
X728500Y482500D03*
X732500Y485500D03*
X734500Y547500D03*
X730000Y536500D03*
X734462Y553538D03*
X733500Y568500D03*
X729900D03*
X741500Y582450D03*
X737000Y583640D03*
X733268Y757984D03*
X740768Y763984D03*
X735500Y771984D03*
X735000Y780500D03*
X736000Y810500D03*
X733768Y800734D03*
X727468Y819284D03*
X733440Y875560D03*
X741050Y869500D03*
X740000Y886000D03*
X737290Y903000D03*
X733000Y969700D03*
X745000Y5000D03*
X755000Y20000D03*
X747800Y50200D03*
X754500Y67500D03*
X757200Y103100D03*
X745500Y145000D03*
X747000Y210000D03*
X755697Y303250D03*
X749750Y454000D03*
X755300Y489300D03*
X751484Y540600D03*
X746750Y571750D03*
X748000Y579500D03*
X755000Y727500D03*
X757500Y743500D03*
X745400Y877600D03*
X757000Y896400D03*
X749500Y974300D03*
X762250Y71000D03*
X761000Y88500D03*
Y82500D03*
X760600Y94500D03*
X770500Y136000D03*
X770900Y144300D03*
X765116Y187659D03*
X759563Y303250D03*
X771447D03*
X773500Y326000D03*
X758500Y457000D03*
X771000Y464000D03*
X772024Y478976D03*
X774500Y489500D03*
X760500D03*
X765009Y563491D03*
X766000Y635000D03*
X763000Y648000D03*
X767000Y648500D03*
X760125Y666875D03*
X771000Y689500D03*
X770646Y685354D03*
X760500Y707950D03*
X768000Y728000D03*
X763500Y839500D03*
X768000Y833000D03*
X766750Y849250D03*
X774500Y890500D03*
X775000Y5000D03*
X785000Y20000D03*
X775748Y188500D03*
X789500Y235837D03*
X787192Y303250D03*
X775313D03*
X788600Y449300D03*
X784800D03*
X784900Y453000D03*
X788800D03*
X779000Y458000D03*
X776000Y478828D03*
X788774Y482774D03*
X784274Y486274D03*
X790600Y547600D03*
X790000Y554500D03*
X786500Y575688D03*
X786032Y570468D03*
X783500Y649000D03*
X784804Y673304D03*
X785500Y666500D03*
X783746Y692754D03*
X779500Y705000D03*
X787500Y783500D03*
X782750Y845750D03*
X781000Y877000D03*
X785000Y892000D03*
X776750Y964750D03*
X785500Y969700D03*
X805000Y5000D03*
X796000Y167600D03*
X795500Y163408D03*
X802942Y303250D03*
X791058D03*
X806808D03*
X798000Y400500D03*
X806274Y434726D03*
X796074Y479000D03*
X791000Y562000D03*
X802500Y579500D03*
X803500Y655000D03*
X798000Y706000D03*
X802000Y724000D03*
X794000Y723500D03*
X791500Y783500D03*
X801750Y867500D03*
X805250Y865750D03*
X794500Y897000D03*
X815000Y20000D03*
X818000Y240900D03*
X821100Y348480D03*
Y352480D03*
X808500Y363500D03*
X811000Y430500D03*
X823500Y480000D03*
X814500Y472500D03*
X823500Y556500D03*
X815900Y564000D03*
X819500D03*
X810000Y735500D03*
X821250Y845750D03*
X810500Y851000D03*
X814000Y849500D03*
X819000Y868500D03*
X810000Y980000D03*
X835000Y5000D03*
X832000Y137500D03*
X826198Y239950D03*
X833555Y262000D03*
X838055Y262500D03*
X825500Y411100D03*
X832500Y404000D03*
X826500Y436000D03*
X826000Y465078D03*
X831000Y598500D03*
X833500Y613000D03*
X835000Y719000D03*
X826500Y743000D03*
X839250Y854500D03*
X826060Y863440D03*
X824560Y868560D03*
X840000Y980000D03*
X850000Y20000D03*
X856055Y262500D03*
X842555Y262000D03*
X847055Y262500D03*
X851555D03*
X854820Y352380D03*
X850540Y346070D03*
X844410Y346360D03*
X847500Y352000D03*
X852000Y401500D03*
X842000D03*
X847000Y396500D03*
Y401500D03*
Y406500D03*
X854000Y436500D03*
X849500Y622000D03*
X846250Y642250D03*
X854000Y640500D03*
X846500Y710000D03*
X852500Y710500D03*
X842500Y719500D03*
X845500Y865000D03*
X852600Y868500D03*
X865000Y5000D03*
X873000Y68500D03*
X872000Y75500D03*
X870100Y237500D03*
X869544Y226000D03*
X860400Y231000D03*
X860555Y262500D03*
X865055D03*
X863820Y363880D03*
X868820D03*
X870500Y444000D03*
Y448000D03*
X871500Y484000D03*
X857500Y485500D03*
X862500Y621250D03*
X859500Y629500D03*
X872000Y636000D03*
X871000Y639500D03*
X870500Y665060D03*
X861250Y649250D03*
X867500Y655200D03*
X865500Y690500D03*
X860718Y683684D03*
X860500Y734000D03*
X870000Y980000D03*
X880000Y20000D03*
X877860Y316330D03*
X888750Y324660D03*
X884120Y351630D03*
X887950Y359730D03*
X874910Y360160D03*
X879510Y355410D03*
X887940Y380200D03*
X878000Y404500D03*
X877000Y409500D03*
X876000Y435500D03*
X886300Y443100D03*
X882700D03*
X885000Y438700D03*
X874450Y463500D03*
X877000Y479500D03*
X877500Y612500D03*
X876000Y631700D03*
X884200Y636500D03*
X878500Y695500D03*
X881000Y710000D03*
X895000Y5000D03*
X899000Y312500D03*
X898000Y316000D03*
X903480Y324230D03*
X904600Y406600D03*
X893500Y427000D03*
X893600Y443100D03*
X889900D03*
X903075Y472000D03*
X900000Y980000D03*
X910000Y20000D03*
X918420Y449130D03*
X907000Y465050D03*
X917000Y752500D03*
X925000Y5000D03*
X923000Y51500D03*
X936000Y373500D03*
X924465Y388465D03*
X934000Y448700D03*
X936030Y457540D03*
X937000Y489000D03*
X935400Y597300D03*
X955000Y5000D03*
X940000Y20000D03*
X939500Y352000D03*
X953500Y348927D03*
X944000Y434000D03*
X970000Y20000D03*
X958500Y187500D03*
X957990Y191064D03*
X962000Y251500D03*
X965500Y260500D03*
X963500Y256000D03*
X959500Y351688D03*
X965000Y364500D03*
X964000Y354000D03*
X968085Y452065D03*
X970382Y455872D03*
X961700Y477500D03*
X957500Y585500D03*
X961500D03*
X970750Y703000D03*
X985000Y5000D03*
X980078Y204578D03*
X980960Y195257D03*
X980490Y198827D03*
X982075Y439500D03*
X973015Y453416D03*
X977000Y547500D03*
X982500Y549500D03*
X978000Y554000D03*
X975000Y701000D03*
X1000000Y20000D03*
X989000Y66500D03*
X1003000Y59500D03*
X996500Y167000D03*
X988660Y190500D03*
X988900Y434800D03*
X992690Y466750D03*
X996910Y466560D03*
X998000Y461500D03*
X994500Y491000D03*
X1003422Y490578D03*
X992000Y505500D03*
X1002500Y520000D03*
X990500Y536500D03*
X994500Y543800D03*
X998500Y591500D03*
X989000Y659500D03*
Y757150D03*
X1001000Y771500D03*
X1015000Y5000D03*
X1012000Y43000D03*
X1016500Y87500D03*
X1020500Y124500D03*
Y142000D03*
X1017274Y219274D03*
X1014000Y487000D03*
X1007500Y487500D03*
Y507000D03*
X1008500Y533400D03*
X1016500Y519500D03*
X1008500Y543700D03*
X1013500Y559000D03*
X1016900Y561000D03*
X1017982Y585018D03*
X1007032Y879968D03*
X1011966Y893534D03*
X1007532Y902468D03*
X1020282Y911218D03*
X1010000Y980000D03*
X1033500Y118000D03*
X1025500Y129500D03*
X1033500Y124000D03*
X1037085Y137000D03*
X1023000Y155000D03*
X1034000D03*
X1028000Y164500D03*
X1023600Y173000D03*
X1036019Y203177D03*
X1036000Y199500D03*
X1035922Y209578D03*
X1031524Y218476D03*
X1033900Y225500D03*
X1027426Y346500D03*
X1023000Y347000D03*
X1031000Y348500D03*
Y355950D03*
X1030000Y403500D03*
X1036500Y581500D03*
X1035000Y594500D03*
X1021000Y588500D03*
X1025500Y657000D03*
X1023500Y727000D03*
X1037000Y734000D03*
X1024387Y738230D03*
X1035000Y800000D03*
Y804500D03*
X1021468Y866968D03*
X1032600Y867657D03*
X1031500Y884500D03*
X1035216Y884468D03*
X1035000Y888500D03*
Y880500D03*
X1032657Y901500D03*
X1027716Y914784D03*
X1032200Y921500D03*
X1045000Y5000D03*
X1045031Y138031D03*
X1041485Y137409D03*
X1039468Y155284D03*
X1048968D03*
X1053500Y153000D03*
X1044000D03*
X1048968Y150784D03*
X1039500Y151000D03*
X1048968Y159284D03*
X1039500Y159500D03*
X1053500Y157500D03*
X1044000D03*
X1040000Y182000D03*
X1052500Y187500D03*
X1045968Y185500D03*
X1037500Y225500D03*
X1040000Y579000D03*
X1038000Y604000D03*
X1053500Y620500D03*
X1046000Y644000D03*
X1038000Y635000D03*
X1042450Y648500D03*
X1045500Y639500D03*
X1050092Y655052D03*
X1042400Y684500D03*
X1052500Y693000D03*
X1052678Y704084D03*
X1038500Y706500D03*
X1052500Y709000D03*
Y700000D03*
X1041410Y708804D03*
Y704224D03*
X1052648Y712724D03*
X1040208Y745020D03*
X1052500Y773350D03*
X1044000Y763940D03*
X1039000Y884500D03*
X1042500Y930000D03*
X1040000Y980000D03*
X1060000Y20000D03*
X1064000Y80000D03*
X1055500D03*
X1059500D03*
X1068000D03*
Y76000D03*
X1064000D03*
X1059500D03*
X1055500D03*
X1068500Y118500D03*
X1069000Y124500D03*
X1057968Y155284D03*
X1058000Y150500D03*
Y159500D03*
X1060900Y173534D03*
X1060509Y177126D03*
X1066500Y185500D03*
X1056500Y194000D03*
X1060000Y207500D03*
X1061000Y211500D03*
X1055000Y219284D03*
X1060766Y395426D03*
X1061200Y399000D03*
X1068300Y488700D03*
X1059000Y558190D03*
X1058000Y599500D03*
X1056000Y604000D03*
X1058500Y660900D03*
X1054900D03*
X1070000Y650725D03*
X1058350Y681450D03*
X1068500Y677000D03*
X1054500Y697000D03*
X1068500Y687000D03*
X1066000Y717000D03*
X1059800Y719740D03*
X1054000Y735000D03*
X1056350Y748000D03*
X1063000Y780000D03*
X1075000Y5000D03*
X1071000Y71000D03*
X1077250Y102000D03*
X1077500Y97000D03*
Y107500D03*
X1072000Y136000D03*
X1086000Y126500D03*
X1074500Y185500D03*
X1080300Y191000D03*
X1084500Y202500D03*
X1072500Y208924D03*
X1078500Y464000D03*
X1080000Y520000D03*
X1081000Y548000D03*
Y544400D03*
X1084599Y544520D03*
X1086000Y556000D03*
X1071500Y589000D03*
X1074500Y627500D03*
X1073000Y637500D03*
X1085000Y661000D03*
X1074000Y677000D03*
X1073500Y672000D03*
X1074000Y683000D03*
X1074500Y694754D03*
X1074426Y687255D03*
X1074389Y691155D03*
X1074000Y699500D03*
X1074148Y711624D03*
X1074600Y707724D03*
X1074000Y703500D03*
X1073384Y722384D03*
X1073000Y730834D03*
Y726444D03*
X1074288Y715534D03*
X1084300Y741874D03*
X1077500Y745374D03*
X1072000Y743500D03*
X1071500Y739000D03*
X1077500Y759000D03*
X1084000Y748099D03*
X1070098Y764500D03*
X1083700Y835725D03*
X1085468Y895968D03*
X1077000Y943075D03*
X1083200Y956500D03*
X1070000Y980000D03*
X1090000Y20000D03*
X1088000Y85500D03*
X1098000Y126500D03*
X1093894D03*
X1090028D03*
X1092500Y461500D03*
X1098500Y465000D03*
X1089000Y508500D03*
X1100575Y559075D03*
X1098000Y562000D03*
X1091425Y551425D03*
X1093500Y640000D03*
X1094500Y657500D03*
X1091000Y692519D03*
X1090257Y724253D03*
X1087600Y727029D03*
X1094853Y726853D03*
X1098000Y775000D03*
X1093000Y791000D03*
X1097500Y784500D03*
X1095500Y812000D03*
X1098500Y823344D03*
X1097500Y849000D03*
X1092718Y859984D03*
X1089000Y867284D03*
X1099623Y869123D03*
X1093468Y896968D03*
X1097423Y906546D03*
X1093500Y905500D03*
X1100000Y980000D03*
X1105000Y5000D03*
Y15000D03*
Y75000D03*
Y105000D03*
Y135000D03*
X1110318Y275600D03*
X1111500Y517500D03*
X1107500Y580000D03*
X1114883Y591925D03*
X1106000Y609500D03*
Y605500D03*
X1111500Y718500D03*
X1107000Y763000D03*
Y757500D03*
X1110300Y790000D03*
X1111834Y813334D03*
X1113500Y824500D03*
X1111000Y836000D03*
X1107160Y843160D03*
X1118034Y847034D03*
X1113768D03*
X1116468Y870284D03*
Y874284D03*
Y865784D03*
X1112468Y870284D03*
X1114500Y886000D03*
X1103000Y888300D03*
X1118500Y886000D03*
X1123000Y250500D03*
X1120600Y282300D03*
X1128000Y288500D03*
X1132300Y288800D03*
X1130000Y361500D03*
X1124327Y465391D03*
X1123500Y521500D03*
X1128149Y525261D03*
X1130928Y527550D03*
X1132000Y562000D03*
X1125600Y570600D03*
X1135000Y597000D03*
X1132222Y593278D03*
X1119487Y588088D03*
X1122353Y590268D03*
X1125000Y603050D03*
X1134000Y613500D03*
X1126000Y618000D03*
Y627329D03*
X1131000Y631000D03*
X1121500Y621600D03*
X1130490Y627436D03*
X1125041Y631000D03*
X1120500Y729500D03*
X1124000Y729000D03*
X1128430Y749640D03*
X1132960Y752950D03*
X1126210Y752810D03*
X1126642Y785505D03*
X1123200Y783900D03*
X1130030Y820000D03*
X1121000Y823500D03*
X1135468Y854032D03*
X1120468Y870284D03*
X1131275Y867725D03*
X1130000Y980000D03*
X1146500Y267000D03*
X1146000Y258500D03*
X1151000Y264500D03*
X1146500Y275500D03*
X1145800Y282284D03*
X1136100Y288900D03*
X1136450Y294650D03*
X1150640Y359860D03*
X1146640D03*
X1142640D03*
X1151500Y449000D03*
Y522000D03*
X1143500Y542000D03*
X1147500D03*
X1136075Y559075D03*
X1145900Y579800D03*
X1136500Y592500D03*
X1139632Y594441D03*
X1140500Y589000D03*
X1141100Y585400D03*
X1147000Y619000D03*
X1147400Y729900D03*
X1166000Y232000D03*
X1162468Y257968D03*
X1153700Y267700D03*
X1168000Y302500D03*
X1166000Y290000D03*
X1156100Y316405D03*
X1168076Y310046D03*
X1152500Y311000D03*
X1158000Y309500D03*
X1152500Y318500D03*
X1160000D03*
X1156100Y312795D03*
X1165000Y308175D03*
Y304565D03*
X1167000Y321000D03*
Y326450D03*
X1161530Y360430D03*
X1157480Y361620D03*
X1157700Y368500D03*
X1160058Y364558D03*
X1155400Y371500D03*
X1164000Y397000D03*
X1168000Y390250D03*
X1166500Y415500D03*
X1155500Y450758D03*
Y446892D03*
X1161000Y541500D03*
X1154000Y589000D03*
X1155000Y594500D03*
X1165476Y613393D03*
X1152500Y608500D03*
X1165672Y609672D03*
X1164500Y628723D03*
X1159075Y630600D03*
X1154847Y630908D03*
X1156377Y627623D03*
X1160333Y753600D03*
X1153500Y784190D03*
X1164500Y857500D03*
X1162000Y960625D03*
X1155000Y980000D03*
X1171000Y232000D03*
X1181427Y251500D03*
X1180677Y256500D03*
X1173777Y290125D03*
X1169777D03*
X1177500Y290000D03*
X1174752Y320504D03*
X1173125Y323716D03*
X1169515D03*
X1175000Y327000D03*
X1184000Y351500D03*
X1174500Y366000D03*
X1182000Y357000D03*
X1174400Y356500D03*
X1178000D03*
X1175125Y370000D03*
X1176500Y383500D03*
X1174500Y404000D03*
X1182500Y407000D03*
X1173500Y422500D03*
Y554000D03*
X1179934Y567000D03*
X1181350Y595450D03*
X1169075Y613500D03*
X1183000Y628000D03*
X1177100Y624750D03*
X1178500Y653100D03*
X1184500Y749500D03*
Y772782D03*
X1173200Y789500D03*
X1184750Y781000D03*
X1177000Y860000D03*
X1169000Y856000D03*
X1181500Y949000D03*
X1186500Y232000D03*
X1188000Y248500D03*
X1196334Y290561D03*
X1185283Y290513D03*
X1192743Y289800D03*
X1188877D03*
X1199685Y344588D03*
X1196075D03*
X1198000Y348000D03*
X1192000Y344500D03*
X1197000Y372500D03*
X1187500Y411000D03*
X1197000Y409500D03*
X1189000Y421500D03*
X1195000Y428000D03*
X1197675Y533125D03*
X1191000Y528000D03*
X1189000Y533825D03*
X1194564Y530936D03*
X1185500Y548075D03*
X1200500Y547925D03*
X1186000Y615500D03*
X1196000Y605800D03*
X1184956Y619272D03*
X1191000Y663000D03*
X1193804Y657175D03*
X1191000Y667000D03*
X1197500Y665500D03*
X1199551Y683968D03*
X1195937Y683849D03*
X1189890Y684053D03*
X1192937Y683911D03*
X1196500Y745500D03*
Y736687D03*
X1192500Y745500D03*
X1199500Y743500D03*
X1192038Y761481D03*
X1188000Y762500D03*
X1188500Y773000D03*
X1184975Y767500D03*
X1194000Y764500D03*
X1190000Y767500D03*
X1198718Y800782D03*
X1196000Y847500D03*
X1188875Y856625D03*
X1196000Y874500D03*
X1185000Y980000D03*
X1211500Y5500D03*
Y35500D03*
Y65500D03*
Y85500D03*
Y107500D03*
Y137500D03*
X1208500Y202000D03*
X1209000Y212500D03*
X1208000Y231000D03*
X1201922Y248500D03*
X1202177Y260000D03*
X1208500Y283500D03*
X1208000Y271499D03*
Y297638D03*
Y309000D03*
X1206500Y330000D03*
X1208500Y321500D03*
X1203500Y345000D03*
X1208500Y346400D03*
Y359000D03*
X1210800Y379700D03*
X1208000Y371000D03*
X1216000Y390000D03*
X1209500Y404500D03*
X1216500Y439500D03*
X1212500Y436000D03*
X1209000Y438500D03*
X1217000Y452500D03*
X1210000Y507500D03*
X1209500Y514000D03*
X1213100D03*
X1214450Y509000D03*
X1206400Y536800D03*
X1210000D03*
X1201500Y535000D03*
X1209500Y561910D03*
X1205240Y568760D03*
X1215500Y605300D03*
X1207700Y605500D03*
X1208500Y623000D03*
X1204500Y659500D03*
X1203181Y683968D03*
X1206781Y684003D03*
X1213598Y699164D03*
X1216000Y702500D03*
X1210500Y733500D03*
X1206500Y757000D03*
X1213500Y756000D03*
X1201968Y757500D03*
X1212840Y781000D03*
X1202218Y811282D03*
X1211000Y847500D03*
X1204000Y862000D03*
X1217250Y862250D03*
X1208940Y874560D03*
X1211500Y882500D03*
X1215000Y980000D03*
X1227500Y500500D03*
Y504246D03*
X1220500Y513000D03*
X1229500Y533000D03*
X1231632Y537000D03*
X1221500Y539500D03*
X1233000Y554502D03*
X1219200Y564600D03*
X1221500Y633000D03*
X1231450Y677500D03*
X1225500Y714500D03*
X1229000Y716000D03*
Y726500D03*
Y719600D03*
Y740000D03*
X1230219Y747469D03*
X1232000Y738000D03*
X1234000Y747500D03*
X1224500Y757500D03*
X1228547Y772547D03*
Y778453D03*
X1231000Y768500D03*
X1221000Y764750D03*
X1233000Y782500D03*
X1223500Y798500D03*
X1223000Y826500D03*
X1230500Y841000D03*
X1218500Y834500D03*
X1229807Y847000D03*
X1235500Y5000D03*
X1239000Y190500D03*
X1239500Y204000D03*
X1240000Y209449D03*
X1239500Y214000D03*
X1239000Y251500D03*
X1241777Y265700D03*
X1241377Y274900D03*
X1238500Y290000D03*
X1239000Y302437D03*
X1238500Y316500D03*
X1250158Y326463D03*
X1238500Y325985D03*
X1239000Y338900D03*
Y352800D03*
X1239500Y366000D03*
X1234177Y379500D03*
X1243000Y431500D03*
X1250000Y422000D03*
X1234500Y439000D03*
X1248250Y439250D03*
X1243000Y446650D03*
X1250450Y462000D03*
X1242000Y459000D03*
X1247800Y472750D03*
X1246750Y476250D03*
X1249000Y509500D03*
X1249251Y528688D03*
X1235482Y546982D03*
X1240000Y546500D03*
Y542900D03*
X1240173Y550327D03*
X1250500Y567000D03*
X1241000Y631500D03*
X1237500Y675500D03*
X1239500Y671000D03*
X1235000Y682000D03*
X1244371Y733129D03*
X1236500Y737925D03*
X1243000Y743000D03*
X1241000Y734500D03*
X1240016Y761500D03*
X1238000Y764500D03*
X1249500Y765500D03*
X1248950Y769500D03*
X1248500Y775500D03*
X1248950Y782450D03*
X1238047Y791953D03*
X1240045Y788957D03*
X1241984Y796000D03*
X1243953Y789000D03*
X1240660Y829000D03*
X1245650Y821850D03*
X1235258Y820758D03*
X1245000Y980000D03*
X1257000Y33000D03*
X1256500Y166500D03*
X1261000D03*
X1265000Y169000D03*
Y174000D03*
X1258000Y205000D03*
X1265000Y211500D03*
X1261000Y207500D03*
Y211500D03*
X1260677Y237000D03*
X1264177Y233500D03*
X1256000Y252000D03*
X1262558Y254942D03*
X1261677Y241500D03*
Y245500D03*
X1251500Y266500D03*
X1264500Y260000D03*
X1254944Y268567D03*
X1263000Y278500D03*
X1250677Y287500D03*
Y283500D03*
X1251700Y274000D03*
X1254203Y282770D03*
X1254944Y272433D03*
X1260577Y299968D03*
Y296102D03*
X1261000Y292500D03*
X1261006Y303543D03*
X1252564Y290566D03*
X1253477Y312800D03*
X1253577Y308800D03*
X1253500Y316500D03*
Y305000D03*
X1257000Y311000D03*
X1253177Y320500D03*
Y324500D03*
X1265000Y426500D03*
X1259968Y444284D03*
X1260000Y448500D03*
X1264500Y446500D03*
X1260000Y440000D03*
X1264500Y442000D03*
X1257468Y478500D03*
X1253000Y511000D03*
X1251500Y531500D03*
X1260500Y546400D03*
X1263500Y550000D03*
X1258000Y555400D03*
X1255000Y609300D03*
X1266500Y617500D03*
X1265000Y647500D03*
X1257500Y635500D03*
X1265000Y661000D03*
Y657000D03*
X1265500Y652500D03*
X1257100Y664300D03*
X1263121Y678621D03*
X1259000Y678950D03*
X1262300Y670700D03*
X1266000Y665600D03*
X1262500Y699825D03*
X1253500Y778465D03*
X1257950Y809250D03*
X1264000Y853000D03*
X1268000Y5000D03*
X1279500Y150500D03*
X1276500Y234000D03*
X1267677Y232500D03*
X1280500Y338000D03*
Y404550D03*
X1280000Y420500D03*
X1278500Y448500D03*
Y444000D03*
X1274000Y447000D03*
X1269468Y444284D03*
Y448284D03*
X1278500Y439500D03*
X1269468Y439784D03*
X1274000Y442000D03*
X1272500Y466600D03*
X1270000Y477000D03*
X1271000Y573500D03*
Y568500D03*
X1282500Y598000D03*
X1274500Y606000D03*
X1278500Y603500D03*
X1271000Y617500D03*
X1279340Y618660D03*
X1282500Y645000D03*
X1272451Y642500D03*
X1272502Y638900D03*
X1281268Y661780D03*
X1268805Y655405D03*
X1282300Y678000D03*
X1282500Y669561D03*
X1273702Y667662D03*
X1275885Y670525D03*
X1267500Y675000D03*
Y684878D03*
X1281500Y713000D03*
X1279000Y746575D03*
X1267500Y779000D03*
Y783000D03*
X1269500Y835000D03*
X1275000Y980000D03*
X1290874Y34376D03*
X1299500Y236000D03*
X1295500Y291500D03*
X1292500Y402000D03*
X1289000Y415500D03*
X1285700Y529700D03*
X1293960Y528740D03*
X1294600Y524200D03*
X1291300Y540900D03*
X1297500Y562000D03*
X1286500Y569000D03*
X1294000Y587500D03*
X1288335Y594048D03*
X1287482Y590500D03*
X1293500Y593000D03*
X1285557Y585000D03*
X1289570Y597430D03*
X1284825Y621500D03*
X1294000Y628000D03*
X1299000Y641500D03*
X1296000Y638500D03*
X1290500Y635500D03*
X1286500Y652500D03*
X1297500Y665000D03*
X1291500Y666000D03*
X1289500Y669000D03*
X1284490Y710936D03*
X1296500Y830782D03*
X1298034Y907034D03*
X1307500Y5000D03*
X1306000Y43000D03*
X1309500Y51000D03*
X1304050Y296500D03*
X1307500Y320500D03*
X1308000Y311000D03*
X1306000Y329000D03*
Y334500D03*
Y338500D03*
X1311000Y435000D03*
Y463500D03*
X1302000Y475000D03*
X1304700Y536000D03*
X1302500Y559500D03*
X1307000Y573412D03*
X1307900Y577412D03*
X1306817Y592412D03*
X1306617Y587512D03*
X1308817Y595412D03*
X1310500Y625000D03*
X1312000Y645784D03*
X1311000Y651900D03*
X1310425Y660062D03*
X1311100Y656400D03*
X1304400Y661400D03*
X1311700Y681500D03*
X1312115Y672000D03*
X1311000Y677284D03*
X1311300Y687500D03*
X1313500Y710000D03*
X1305000Y739750D03*
X1308100Y748200D03*
X1306000Y782500D03*
X1314284D03*
X1304500Y838000D03*
X1300784Y838716D03*
X1312500Y838000D03*
X1305000Y850500D03*
X1303750Y862250D03*
X1312000Y850500D03*
X1307468Y884532D03*
X1314500Y921500D03*
X1300000Y980000D03*
X1331000Y120000D03*
X1322000Y318500D03*
X1322500Y337000D03*
X1317000Y336000D03*
X1330500Y441000D03*
X1332000Y459250D03*
X1323500Y452500D03*
X1326617Y594412D03*
X1325950Y599000D03*
X1329317Y626512D03*
X1323117Y626412D03*
X1328000Y649000D03*
X1328968Y679684D03*
X1329468Y666468D03*
X1323500Y702000D03*
X1322000Y705500D03*
X1318784Y793716D03*
X1325250Y834250D03*
X1316500Y839000D03*
X1317000Y850500D03*
X1318113Y846371D03*
X1321466Y907034D03*
X1330000Y980000D03*
X1337500Y5000D03*
X1339000Y54000D03*
X1347000Y48000D03*
X1342500Y51000D03*
X1333100Y58600D03*
X1347000Y88000D03*
X1347500Y116000D03*
X1343500Y112000D03*
X1336500Y270874D03*
X1339000Y274000D03*
X1339500Y305500D03*
X1341873Y344873D03*
X1344000Y434500D03*
X1340200D03*
X1335000Y443250D03*
X1340200Y438300D03*
X1343900Y438500D03*
X1343000Y466500D03*
X1334500Y557000D03*
X1335317Y575412D03*
X1344617Y588712D03*
Y593412D03*
X1342648Y612412D03*
X1347617Y610412D03*
X1346617Y626912D03*
X1342367Y627662D03*
X1334500Y636000D03*
X1333468Y680000D03*
X1334500Y669000D03*
X1352000Y85500D03*
X1349500Y112000D03*
X1350000Y276500D03*
X1354500Y276000D03*
X1350084Y296500D03*
X1358500Y288916D03*
X1353000Y390000D03*
Y402000D03*
X1362500Y459000D03*
X1353500Y466500D03*
X1351000Y455750D03*
X1355500Y556500D03*
X1360817Y557812D03*
X1356817Y579012D03*
X1364617Y592912D03*
X1349317Y593412D03*
X1360200Y614800D03*
X1353117Y610412D03*
X1353517Y627512D03*
X1363100Y627000D03*
X1349817Y628612D03*
X1357300Y617700D03*
X1360000Y980000D03*
X1369720Y106365D03*
X1379500Y274500D03*
X1381500Y292000D03*
X1376000D03*
X1379500Y314000D03*
X1375500Y328000D03*
X1370500Y356500D03*
X1368000Y450500D03*
X1374500Y462800D03*
X1369617Y557012D03*
X1367617Y570012D03*
X1394122Y5878D03*
X1390004Y106000D03*
Y122600D03*
X1384500Y274500D03*
Y331500D03*
G54D41*
X307953Y250652D03*
Y243052D03*
X326000Y67700D03*
Y75300D03*
X368500Y17300D03*
Y9700D03*
X391929Y156200D03*
Y163800D03*
X396500Y329300D03*
Y321700D03*
X401429Y197200D03*
Y204800D03*
X418929Y197200D03*
Y204800D03*
X480023Y420983D03*
Y428583D03*
X490429Y135300D03*
Y127700D03*
X498429Y135300D03*
Y127700D03*
X647000Y347700D03*
Y355300D03*
X739748Y137300D03*
Y129700D03*
X1211000Y705200D03*
Y712800D03*
X1227177Y198200D03*
Y205800D03*
G54D14*
X47476Y397079D03*
X43976D03*
X62976D03*
X56976D03*
X66476D03*
X53476D03*
X75476D03*
X71976D03*
X165795Y307509D03*
X179295D03*
X175295D03*
X169795D03*
X213795Y304009D03*
X209795D03*
X203795D03*
X200295D03*
X269678Y965800D03*
X273678D03*
X334000Y84300D03*
X346000Y116340D03*
X349000Y15300D03*
X361500D03*
X358000D03*
X360819Y210840D03*
X371239Y191970D03*
X371299Y199540D03*
X376929Y208800D03*
X386300Y164800D03*
X409429Y160800D03*
X399429D03*
X402929D03*
X422200Y160600D03*
X418714Y160650D03*
X415314D03*
X450678Y812300D03*
X507055Y412300D03*
X733716Y135584D03*
X730216D03*
X1006500Y78300D03*
X1277000Y701800D03*
X1273000Y719800D03*
G54D23*
X63104Y669720D03*
X64136Y693503D03*
Y690003D03*
X81072Y730004D03*
X78072Y752504D03*
X68572Y822004D03*
X73604Y853220D03*
X98104Y669720D03*
X98636Y694003D03*
Y690503D03*
X340729Y201500D03*
X351855Y538500D03*
Y542500D03*
X373289Y215420D03*
X388669Y215400D03*
X380989Y215390D03*
X408829Y165000D03*
X408729Y170500D03*
Y183500D03*
Y177000D03*
Y190000D03*
X423340Y139000D03*
X423829Y165000D03*
X423729Y170500D03*
X416229D03*
X416329Y165000D03*
X423729Y177000D03*
X416229D03*
Y183500D03*
X423729D03*
Y190000D03*
X416229D03*
X438340Y139000D03*
X430840D03*
X459229Y118000D03*
X447855Y372500D03*
X460355D03*
X467855D03*
X487229Y158500D03*
Y172500D03*
Y166000D03*
Y179000D03*
X491578Y832000D03*
X502255Y351500D03*
Y347500D03*
X525729Y141000D03*
X710516Y122784D03*
Y133284D03*
Y126284D03*
Y129784D03*
X1144268Y688284D03*
X1145400Y684800D03*
X1164400Y679300D03*
X1259300Y719500D03*
G54D50*
X367540Y125600D03*
Y123400D03*
X370040Y125600D03*
Y123400D03*
X373540Y125600D03*
Y123400D03*
X376040Y125600D03*
Y123400D03*
X379540Y125600D03*
Y123400D03*
X382040Y125600D03*
Y123400D03*
X385540Y125600D03*
Y123400D03*
X388040Y125600D03*
Y123400D03*
X391540Y125600D03*
Y123400D03*
X394040Y125600D03*
Y123400D03*
X397540Y125667D03*
Y123467D03*
X400040Y125667D03*
Y123467D03*
X403540Y125600D03*
Y123400D03*
X406040Y125600D03*
Y123400D03*
X409540Y125600D03*
Y123400D03*
X412040Y125600D03*
Y123400D03*
X403055Y326100D03*
Y323900D03*
X444255Y394600D03*
Y392400D03*
X436355Y394200D03*
Y392000D03*
X450455Y364800D03*
Y362600D03*
X453855Y381100D03*
Y378900D03*
Y388400D03*
Y386200D03*
X451355Y395000D03*
Y392800D03*
X463535Y354910D03*
Y352710D03*
X482000Y133100D03*
Y130900D03*
X484929Y133100D03*
Y130900D03*
X482055Y375100D03*
Y372900D03*
X488555Y388100D03*
Y385900D03*
X489055Y396100D03*
Y393900D03*
X488555Y412100D03*
Y409900D03*
G54D32*
X185039Y1007910D03*
X594488D03*
X794488D03*
G54D24*
X83788Y853252D03*
X119504Y796720D03*
Y800720D03*
X387129Y170500D03*
Y174000D03*
X386700Y197200D03*
Y200600D03*
X387200Y190000D03*
X395759Y215180D03*
X412240Y139000D03*
X397629Y170500D03*
X397729Y165000D03*
X397629Y177000D03*
Y183500D03*
Y190000D03*
X412329Y214680D03*
X406255Y338850D03*
X407155Y372000D03*
X424929Y205200D03*
X424869Y208670D03*
X419939Y214650D03*
X421755Y372500D03*
X423478Y824500D03*
X423378Y864000D03*
X435029Y151710D03*
X434079Y158620D03*
X434129Y170860D03*
X434219Y164850D03*
X434129Y177400D03*
X434329Y183800D03*
X434449Y202480D03*
X434129Y189750D03*
X434629Y196000D03*
X434439Y208870D03*
X456255Y326500D03*
X1006700Y70500D03*
X1060200Y120500D03*
X1166700Y685500D03*
X1166668Y695284D03*
Y689284D03*
Y700284D03*
X1159700Y704500D03*
X1176200Y701300D03*
X1354700Y456000D03*
G36*
G01X254328Y92115D02*
G03Y92135I15750J10D01*
G01X262578D01*
G02Y92115I7500J-10D01*
G01X254328D01*
G37*
G36*
G01Y155107D02*
G03Y155127I15750J10D01*
G01X262578D01*
G02Y155107I7500J-10D01*
G01X254328D01*
G37*
G36*
G01X475194Y79911D02*
G03Y79931I15750J10D01*
G01X483444D01*
G02Y79911I7500J-10D01*
G01X475194D01*
G37*
G36*
G01Y255108D02*
G03Y255128I15750J10D01*
G01X483444D01*
G02Y255108I7500J-10D01*
G01X475194D01*
G37*
G36*
G01X728146Y353533D02*
G03Y353553I15750J10D01*
G01X736396D01*
G02Y353533I7500J-10D01*
G01X728146D01*
G37*
G36*
G01Y410619D02*
G03Y410639I15750J10D01*
G01X736396D01*
G02Y410619I7500J-10D01*
G01X728146D01*
G37*
G36*
G01X1289366Y87538D02*
G03Y87558I15750J10D01*
G01X1297616D01*
G02Y87538I7500J-10D01*
G01X1289366D01*
G37*
G36*
G01X1289367Y262735D02*
G03Y262755I15750J10D01*
G01X1297617D01*
G02Y262735I7500J-10D01*
G01X1289367D01*
G37*
G36*
G01X1361218Y147233D02*
G03Y147253I15750J10D01*
G01X1369468D01*
G02Y147233I7500J-10D01*
G01X1361218D01*
G37*
G36*
G01Y216525D02*
G03Y216545I15750J10D01*
G01X1369468D01*
G02Y216525I7500J-10D01*
G01X1361218D01*
G37*
G54D51*
X375040Y147400D03*
Y149600D03*
X374629Y171100D03*
Y173300D03*
X389540Y130400D03*
Y132600D03*
X387029Y152600D03*
Y154800D03*
X380769Y152240D03*
Y154440D03*
X409040Y143900D03*
Y146100D03*
X399055Y441400D03*
Y443600D03*
X413929Y131400D03*
Y133600D03*
X453555Y362600D03*
Y364800D03*
X453455Y398100D03*
Y400300D03*
X451255Y398100D03*
Y400300D03*
X475855Y352700D03*
Y354900D03*
X474555Y417900D03*
X469055Y415900D03*
Y418100D03*
X474555Y420100D03*
X479055Y352900D03*
Y355100D03*
X482555Y378400D03*
Y380600D03*
X483055Y393900D03*
Y396100D03*
X481055Y405900D03*
Y408100D03*
X782324Y342948D03*
Y345148D03*
X778824Y342948D03*
Y345148D03*
G54D15*
X47476Y393479D03*
X43976D03*
X62976D03*
X56976D03*
X66476D03*
X53476D03*
X75476D03*
X71976D03*
X165795Y303909D03*
X179295D03*
X175295D03*
X169795D03*
X213795Y300409D03*
X209795D03*
X203795D03*
X200295D03*
X269678Y962200D03*
X273678D03*
X334000Y80700D03*
X346000Y112740D03*
X349000Y11700D03*
X361500D03*
X358000D03*
X360819Y207240D03*
X371239Y188370D03*
X371299Y195940D03*
X376929Y205200D03*
X386300Y161200D03*
X409429Y157200D03*
X399429D03*
X402929D03*
X422200Y157000D03*
X418714Y157050D03*
X415314D03*
X450678Y808700D03*
X507055Y408700D03*
X733716Y131984D03*
X730216D03*
X1006500Y74700D03*
X1277000Y698200D03*
X1273000Y716200D03*
G54D42*
X312000Y292700D03*
X321500Y85200D03*
X326000D03*
X317000D03*
X329500Y294200D03*
X341000Y116240D03*
X353500Y15200D03*
X393929Y224700D03*
X394555Y434700D03*
X402929Y233700D03*
X406929D03*
X399555Y434700D03*
X425940Y155000D03*
X413429Y240200D03*
X426523Y326983D03*
X425278Y808700D03*
X435055Y287700D03*
X430523Y326983D03*
X431778Y808700D03*
X437778Y879200D03*
X431278D03*
X456278Y808700D03*
X460778Y879200D03*
X462778Y808700D03*
X467278Y879200D03*
X509555Y420200D03*
X552555Y345200D03*
X556555D03*
X651000Y452200D03*
X645500Y475700D03*
X1137500Y656200D03*
X1166000Y648200D03*
X1153000D03*
X1158000D03*
X1162000D03*
X1213000Y634200D03*
X1209000D03*
X1217000D03*
X1260500Y641200D03*
X1277000Y690700D03*
X1273000Y709200D03*
X1281000Y719700D03*
X1277000Y727700D03*
X1358584Y284368D03*
X1384500Y322700D03*
G54D60*
X585315Y44134D03*
X654527D03*
G54D25*
X87388Y853252D03*
X123104Y796720D03*
Y800720D03*
X390729Y170500D03*
Y174000D03*
X390300Y197200D03*
Y200600D03*
X390800Y190000D03*
X401229Y170500D03*
X401329Y165000D03*
X401229Y177000D03*
Y183500D03*
Y190000D03*
X399359Y215180D03*
X409855Y338850D03*
X410755Y372000D03*
X415840Y139000D03*
X428529Y205200D03*
X428469Y208670D03*
X423539Y214650D03*
X415929Y214680D03*
X425355Y372500D03*
X427078Y824500D03*
X426978Y864000D03*
X438629Y151710D03*
X437679Y158620D03*
X437729Y170860D03*
X437819Y164850D03*
X437729Y177400D03*
X437929Y183800D03*
X438049Y202480D03*
X437729Y189750D03*
X438229Y196000D03*
X438039Y208870D03*
X459855Y326500D03*
X1010300Y70500D03*
X1063800Y120500D03*
X1163300Y704500D03*
X1170300Y685500D03*
X1170268Y695284D03*
Y689284D03*
X1179800Y701300D03*
X1170268Y700284D03*
X1358300Y456000D03*
G54D43*
X312000Y289300D03*
X321500Y81800D03*
X326000D03*
X317000D03*
X329500Y290800D03*
X341000Y112840D03*
X353500Y11800D03*
X393929Y221300D03*
X394555Y431300D03*
X402929Y230300D03*
X406929D03*
X399555Y431300D03*
X425940Y151600D03*
X413429Y236800D03*
X426523Y323583D03*
X425278Y805300D03*
X435055Y284300D03*
X430523Y323583D03*
X431778Y805300D03*
X437778Y875800D03*
X431278D03*
X456278Y805300D03*
X460778Y875800D03*
X462778Y805300D03*
X467278Y875800D03*
X509555Y416800D03*
X552555Y341800D03*
X556555D03*
X651000Y448800D03*
X645500Y472300D03*
X1137500Y652800D03*
X1166000Y644800D03*
X1153000D03*
X1158000D03*
X1162000D03*
X1213000Y630800D03*
X1209000D03*
X1217000D03*
X1260500Y637800D03*
X1277000Y687300D03*
X1273000Y705800D03*
X1281000Y716300D03*
X1277000Y724300D03*
X1358584Y280968D03*
X1384500Y319300D03*
G54D34*
X297800Y98500D03*
X305800D03*
X346380Y179800D03*
X361729Y199389D03*
X379800Y901500D03*
Y906000D03*
X403800Y889500D03*
Y893500D03*
Y905500D03*
Y897500D03*
Y909500D03*
Y901500D03*
X426800Y241000D03*
Y245000D03*
X425300Y314500D03*
X414823Y326283D03*
X423578Y828500D03*
Y837500D03*
Y842000D03*
Y833000D03*
Y846500D03*
Y851000D03*
Y860000D03*
Y855500D03*
X443340Y118000D03*
X433683Y145701D03*
X446229Y113500D03*
X448229Y171500D03*
Y184500D03*
Y180000D03*
X464729Y104000D03*
X467729Y122000D03*
X474300Y140000D03*
X470729Y149000D03*
Y153500D03*
X470800Y144500D03*
X471300Y157500D03*
X470800Y162000D03*
X466300Y169000D03*
Y176000D03*
X476331Y190291D03*
X462300Y286500D03*
X488078Y857000D03*
Y852500D03*
Y861500D03*
X508229Y135000D03*
X511229Y151000D03*
X524229Y129000D03*
X776800Y968500D03*
X1006800Y66500D03*
X1035800Y145500D03*
X1060300Y124500D03*
X1085300Y640000D03*
X1077800D03*
X1132138Y688864D03*
X1222300Y722500D03*
X1248300Y715500D03*
Y719500D03*
X1250300Y641000D03*
Y647000D03*
X1257800D03*
X1250300Y657000D03*
Y651000D03*
Y661000D03*
Y667000D03*
Y675500D03*
Y679500D03*
Y691500D03*
Y695500D03*
Y699500D03*
Y703500D03*
Y707500D03*
Y711500D03*
X1255800Y715500D03*
X1340800Y399500D03*
G54D70*
X1258504Y329331D03*
Y368701D03*
X1272677Y349016D03*
G54D52*
X402953Y23622D03*
X413189D03*
X423425D03*
G54D61*
X599941Y70118D03*
X607933D03*
X595905Y80118D03*
X603897D03*
X611889D03*
X615925Y70118D03*
X623917D03*
X627953Y80118D03*
X631909Y70118D03*
X639901D03*
X635945Y80118D03*
X643937D03*
G54D16*
G01X-245081Y-422119D02*
G02I-12000J0D01*
G01X-250231D02*
G02I-6850J0D01*
G01X-241081D02*
X-273081D01*
G01X-257081Y-438119D02*
Y-406119D01*
G01X-241081Y-438119D02*
Y-518119D01*
G01D02*
X1034819D01*
G01X-241081Y-473619D02*
X1034819D01*
G01X-241081Y-438119D02*
X1034819D01*
G01X9970Y337795D02*
X19272D01*
G01X9970Y396850D02*
X19272D01*
G01Y328493D02*
Y337795D01*
G01D02*
Y347097D01*
G01Y337795D02*
X28574D01*
G01X19272Y387548D02*
Y396850D01*
G01D02*
Y406152D01*
G01X63054Y669720D02*
Y665970D01*
X60304Y663220D01*
G01X55304Y669720D02*
X59554D01*
G01D02*
Y671171D01*
X61603Y673220D01*
X86304D01*
X89804Y669720D01*
G01X60586Y690003D02*
Y693503D01*
G01D02*
Y697938D01*
X58804Y699720D01*
G01X64086Y693503D02*
Y690003D01*
G01Y693503D02*
Y698502D01*
X64304Y698720D01*
G01X58804Y710220D02*
Y699720D01*
G01X76804Y710220D02*
X58804D01*
G01X93347Y765754D02*
X94029Y766436D01*
Y777044D01*
X65022Y806051D01*
Y822004D01*
G01X55022Y826720D02*
X56555Y828253D01*
X65023D01*
X66022Y827254D01*
G01X65022Y822004D02*
Y826254D01*
X66022Y827254D01*
G01X76804Y710220D02*
Y723536D01*
X77272Y724004D01*
G01X76804Y710220D02*
X77522Y709502D01*
Y709052D01*
X92354Y694220D01*
X94869D01*
X95086Y694003D01*
G01X81022Y730004D02*
Y710502D01*
X81304Y710220D01*
G01X77522Y730004D02*
Y724254D01*
X77272Y724004D01*
G01X74522Y752504D02*
Y757934D01*
X75432Y758844D01*
G01X78022Y752504D02*
X78772Y753254D01*
Y760004D01*
X76272Y762504D01*
G01X77500Y832000D02*
Y832500D01*
X75000Y835000D01*
Y840524D01*
X70909Y844615D01*
Y847325D01*
G01X83838Y853252D02*
Y848133D01*
G01X73554Y853220D02*
Y850970D01*
X76804Y847720D01*
G01X70054Y853220D02*
Y848180D01*
X70909Y847325D01*
G01X98838Y328493D02*
Y337795D01*
G01D02*
Y347097D01*
G01X89536Y337795D02*
X98838D01*
G01D02*
X108140D01*
G01X98054Y669720D02*
Y666470D01*
X95304Y663720D01*
G01X94554Y669720D02*
X89804D01*
G01X130000Y666500D02*
Y667000D01*
X110780Y686220D01*
X95304D01*
G01D02*
X95086Y686438D01*
Y690503D01*
G01D02*
Y694003D01*
G01X98586Y690503D02*
Y694003D01*
G01D02*
Y697804D01*
X97737Y698653D01*
G01X93347Y765754D02*
X96601D01*
X117000Y745355D01*
Y737000D01*
X143500Y710500D01*
G01X123054Y800720D02*
Y806470D01*
X93804Y835720D01*
X92304D01*
G01X87338Y853252D02*
Y848697D01*
X87928Y848107D01*
G01X119554Y800720D02*
X117804D01*
X115804Y798720D01*
G01X119554Y796720D02*
X117804D01*
X115804Y798720D01*
G01X110234Y1009860D02*
Y997166D01*
X112900Y994500D01*
Y988500D01*
G01X128000Y544050D02*
X148385D01*
X154625Y550290D01*
G01X123054Y796720D02*
X127304D01*
X129304Y798720D01*
G01D02*
X127304Y800720D01*
X123054D01*
G01X145500Y283500D02*
X150371Y288371D01*
X240741D01*
X265200Y263912D01*
Y210800D01*
X293000Y183000D01*
Y133000D01*
X314000Y112000D01*
Y102500D01*
G01X153937Y235196D02*
Y238898D01*
G01Y243070D02*
Y246772D01*
G01D02*
Y250474D01*
G01X150235Y246772D02*
X153937D01*
G01D02*
X157639D01*
G01X153937Y238898D02*
Y242600D01*
G01X150235Y238898D02*
X153937D01*
G01D02*
X157639D01*
G01X153937Y256849D02*
Y260551D01*
G01D02*
Y264253D01*
G01X150235Y260551D02*
X153937D01*
G01D02*
X157639D01*
G01X190118Y734957D02*
Y739409D01*
G01D02*
Y743861D01*
G01Y739409D02*
X194570D01*
G01X195666D02*
X200118D01*
G01X199000Y891500D02*
X201915Y888585D01*
X209085D01*
X212000Y891500D01*
G01X215666Y739409D02*
X220118D01*
G01X210118Y734957D02*
Y739409D01*
G01D02*
Y743861D01*
G01X205666Y739409D02*
X210118D01*
G01D02*
X214570D01*
G01X200118Y734957D02*
Y739409D01*
G01D02*
Y743861D01*
G01Y739409D02*
X204570D01*
G01X212000Y891500D02*
Y807500D01*
X218000Y801500D01*
G01X224015Y234961D02*
Y238663D01*
G01X220313Y234961D02*
X224015D01*
G01D02*
X227717D01*
G01X224015Y243070D02*
Y246772D01*
G01D02*
Y250474D01*
G01X220313Y246772D02*
X224015D01*
G01D02*
X227717D01*
G01X224015Y256849D02*
Y260551D01*
G01D02*
Y264253D01*
G01X220313Y260551D02*
X224015D01*
G01D02*
X227717D01*
G01X220118Y734957D02*
Y739409D01*
G01D02*
Y743861D01*
G01Y739409D02*
X224570D01*
G01X230118Y734957D02*
Y739409D01*
G01D02*
Y743861D01*
G01X225666Y739409D02*
X230118D01*
G01D02*
X234570D01*
G01X247319Y-438119D02*
Y-518119D01*
G01X240118Y734957D02*
Y739409D01*
G01D02*
Y743861D01*
G01X235666Y739409D02*
X240118D01*
G01D02*
X244570D01*
G01X245666D02*
X250118D01*
G01X260118Y729409D02*
Y733861D01*
G01X255666Y729409D02*
X260118D01*
G01D02*
X264570D01*
G01X260118Y734957D02*
Y739409D01*
G01D02*
Y743861D01*
G01X255666Y739409D02*
X260118D01*
G01D02*
X264570D01*
G01X250118Y734957D02*
Y739409D01*
G01D02*
Y743861D01*
G01Y739409D02*
X254570D01*
G01X270118Y729409D02*
Y733861D01*
G01X265666Y729409D02*
X270118D01*
G01D02*
X274570D01*
G01X270118Y734957D02*
Y739409D01*
G01D02*
Y743861D01*
G01X265666Y739409D02*
X270118D01*
G01D02*
X274570D01*
G01X273678Y962250D02*
Y958000D01*
G01X269678Y962250D02*
Y957000D01*
X268178Y955500D01*
G01X283463Y1009860D02*
Y997715D01*
X285678Y995500D01*
G01X295273Y1009860D02*
Y997595D01*
X293178Y995500D01*
G01X314500Y71000D02*
X313000D01*
X309500Y74500D01*
Y75000D01*
G01X307250Y84125D02*
X302675D01*
X302600Y84200D01*
X299300D01*
G01X309500Y78500D02*
Y75000D01*
G01X317000Y81750D02*
X315750D01*
X315500Y81500D01*
X311500D01*
G01X317500Y101000D02*
X314000Y97500D01*
X313500D01*
G01X309250Y98500D02*
X311000D01*
X312000Y97500D01*
X313500D01*
G01X313000Y92750D02*
Y97000D01*
X313500Y97500D01*
G01X307953Y243052D02*
X310003Y245102D01*
X314453D01*
G01X307500Y294500D02*
Y299000D01*
G01X312773Y529878D02*
Y546838D01*
X315725Y549790D01*
G01X299213Y1009860D02*
Y997465D01*
X301178Y995500D01*
G01X311023Y1009860D02*
Y996845D01*
X309678Y995500D01*
G01X319500Y71000D02*
X314500D01*
G01X334000Y80750D02*
X333250Y80000D01*
X330250D01*
G01X326000Y85250D02*
Y88500D01*
X327000Y89500D01*
G01X328000Y93000D02*
Y90500D01*
X327000Y89500D01*
G01X321500Y81750D02*
X317000D01*
G01X314500Y77000D02*
X319500D01*
G01X326000Y75300D02*
Y81750D01*
G01D02*
X321500D01*
G01X319500Y77000D02*
X321200Y75300D01*
X326000D01*
G01D02*
X331700D01*
X332500Y74500D01*
G01X373500Y235200D02*
X340129D01*
X323729Y218800D01*
X322229D01*
G01X382130Y229780D02*
X343709D01*
X326929Y213000D01*
X316129D01*
G01X397900Y231800D02*
X397200Y232500D01*
X393000D01*
X387000Y238500D01*
X335929D01*
X322265Y224836D01*
X318736D01*
G01D02*
X316400Y222500D01*
G01X330708Y1009860D02*
Y997470D01*
X332678Y995500D01*
G01X326773Y1009860D02*
Y997595D01*
X324678Y995500D01*
G01X314958Y1009860D02*
Y997720D01*
X317178Y995500D01*
G01X332500Y74500D02*
X333500Y73500D01*
X337000D01*
G01X352500Y113000D02*
X352290Y112790D01*
X346000D01*
G01D02*
X341000D01*
G01X346330Y179800D02*
Y182599D01*
X345929Y183000D01*
G01X337179Y189000D02*
X337290Y189111D01*
Y193000D01*
G01X340679Y201500D02*
Y204900D01*
G01X337290Y193000D02*
Y197500D01*
G01D02*
X337179Y197611D01*
Y201500D01*
G01D02*
Y206750D01*
X341179Y210750D01*
X343929D01*
G01D02*
Y215500D01*
G01Y210750D02*
X344040D01*
G01X348540D02*
X344040D01*
G01X343250Y287625D02*
Y287750D01*
X348000Y292500D01*
G01X343250Y396000D02*
X340000D01*
X338500Y397500D01*
G01X347213Y546700D02*
X348305Y545608D01*
Y542500D01*
G01X346458Y1009860D02*
Y998220D01*
X348678Y996000D01*
G01X342518Y1009860D02*
Y997340D01*
X341178Y996000D01*
G01X360819Y207290D02*
X364748Y202361D01*
X368307D01*
G01X357040Y210750D02*
X353040D01*
G01D02*
X348540D01*
G01X357040D02*
X360779D01*
X360819Y210790D01*
G01D02*
X361839Y211810D01*
X365158D01*
G01X356929Y215750D02*
Y210861D01*
X357040Y210750D01*
G01X351000Y392750D02*
X353805D01*
X355055Y394000D01*
G01X348305Y542500D02*
Y538500D01*
G01X351805D02*
Y542500D01*
G01D02*
Y546870D01*
X351815Y546880D01*
G01X358268Y1009860D02*
Y995500D01*
G01X371239Y188420D02*
X369671D01*
X368336Y189755D01*
G01X373200Y183290D02*
X371925Y183250D01*
X369315Y185860D01*
X365932D01*
X365187Y186605D01*
G01X364909Y190169D02*
Y186883D01*
X365187Y186605D01*
G01X371299Y195990D02*
X368379D01*
X368307Y196062D01*
G01X364909Y193669D02*
X367302Y196062D01*
X368307D01*
G01Y205511D02*
X365283Y208535D01*
Y211685D01*
X365158Y211810D01*
G01X371299Y199490D02*
X368586D01*
X368307Y199211D01*
G01X365179Y199389D02*
X368129D01*
X368307Y199211D01*
G01X371239Y191920D02*
X370255Y192904D01*
X368336D01*
G01X377439Y215390D02*
Y212127D01*
X377756Y211810D01*
G01X376929Y208750D02*
Y210983D01*
X377756Y211810D01*
G01X365429Y215500D02*
Y212081D01*
X365158Y211810D01*
G01X371429Y207250D02*
Y211782D01*
X371457Y211810D01*
G01X369739Y215420D02*
Y214690D01*
X371457Y212972D01*
Y211810D01*
G01X388000Y233500D02*
X386300Y235200D01*
X373500D01*
G01X377953Y1009860D02*
Y995725D01*
G01X384819Y-438119D02*
Y-518119D01*
G01X397779Y165000D02*
Y166355D01*
X397427Y166707D01*
Y166941D01*
X396653Y167715D01*
G01X397679Y170500D02*
Y169750D01*
X396653Y168724D01*
Y167715D01*
G01X387179Y174000D02*
Y170500D01*
G01X396654Y186614D02*
X397441Y185827D01*
Y185619D01*
X397679Y185381D01*
Y183500D01*
G01X396653Y180314D02*
X397440Y179527D01*
Y179320D01*
X397679Y179081D01*
Y177000D01*
G01X384032Y174003D02*
X384035Y174000D01*
X387179D01*
G01X397679Y190000D02*
Y187847D01*
X397441Y187609D01*
Y187401D01*
X396654Y186614D01*
G01X396653Y174015D02*
X397390Y173278D01*
Y173044D01*
X397679Y172755D01*
Y170500D01*
G01Y177000D02*
Y175323D01*
X397390Y175034D01*
Y174752D01*
X396653Y174015D01*
G01X397679Y183500D02*
Y181549D01*
X397440Y181310D01*
Y181101D01*
X396653Y180314D01*
G01Y192912D02*
X397391Y192174D01*
Y191943D01*
X397679Y191655D01*
Y190000D01*
G01X395809Y215180D02*
X396429Y214560D01*
Y212035D01*
X396654Y211810D01*
G01X388619Y215400D02*
Y216374D01*
X390354Y218109D01*
G01X380939Y215390D02*
Y211843D01*
X380906Y211810D01*
G01X384055D02*
X385119Y212874D01*
Y215400D01*
G01X385429Y219750D02*
Y215710D01*
X385119Y215400D01*
G01X388149Y229780D02*
X382130D01*
G01X396500Y329300D02*
X398754Y331554D01*
X402019D01*
X404519Y334054D01*
X404920D01*
G01X386755Y441000D02*
Y447300D01*
G01X389763Y1009860D02*
Y996085D01*
G01X412290Y139000D02*
Y142407D01*
X412403Y142520D01*
G01X409251Y174015D02*
X408679Y173443D01*
Y170500D01*
G01X408779Y165000D02*
Y167243D01*
X409251Y167715D01*
G01X408679Y170500D02*
Y168287D01*
X409251Y167715D01*
G01Y186613D02*
X408679Y186041D01*
Y183500D01*
G01X409288Y180315D02*
X408679Y179706D01*
Y177000D01*
G01Y190000D02*
Y187185D01*
X409251Y186613D01*
G01X408679Y183500D02*
Y180924D01*
X409288Y180315D01*
G01X408679Y177000D02*
Y174587D01*
X409251Y174015D01*
G01Y192912D02*
X408679Y192340D01*
Y190000D01*
G01X403109Y219530D02*
X401429Y221210D01*
Y221259D01*
X399803D01*
G01X412379Y214680D02*
Y211833D01*
X412402Y211810D01*
G01X399803D02*
X399309Y212304D01*
Y215180D01*
G01X406929Y233750D02*
Y235500D01*
X407429Y236000D01*
Y238146D01*
X415683Y246400D01*
X420429D01*
G01X423290Y139000D02*
Y140177D01*
X425001Y141888D01*
Y142520D01*
G01X415790Y139000D02*
Y142282D01*
X415552Y142520D01*
G01X427290Y139000D02*
X428151Y139861D01*
Y142520D01*
G01X419790Y139000D02*
Y140213D01*
X421851Y142274D01*
Y142520D01*
G01X415575Y167703D02*
X416179Y168307D01*
Y170500D01*
G01X416279Y165000D02*
Y166999D01*
X415575Y167703D01*
G01X423679Y170500D02*
Y172202D01*
X421876Y174005D01*
G01X423779Y165000D02*
Y165802D01*
X421876Y167705D01*
G01X416179Y170500D02*
Y173387D01*
X415551Y174015D01*
G01X421876Y174005D02*
X423679Y175808D01*
Y177000D01*
G01X421876Y186603D02*
X423679Y188406D01*
Y190000D01*
G01X415551Y186614D02*
X416179Y185986D01*
Y183500D01*
G01X415587Y180315D02*
X416179Y179723D01*
Y177000D01*
G01X421876Y186603D02*
X423679Y184800D01*
Y183500D01*
G01Y177000D02*
Y178501D01*
X421876Y180304D01*
G01X416179Y190000D02*
X415551Y189372D01*
Y186614D01*
G01X416179Y177000D02*
Y174643D01*
X415551Y174015D01*
G01X416179Y183500D02*
Y180907D01*
X415587Y180315D01*
G01X423679Y183500D02*
Y182107D01*
X421876Y180304D01*
G01X415551Y192912D02*
X416179Y192284D01*
Y190000D01*
G01X424979Y205200D02*
Y202381D01*
X424999Y202361D01*
G01X426429Y196000D02*
X425429Y195000D01*
Y193342D01*
X424999Y192912D01*
G01X424919Y208670D02*
Y211728D01*
X425001Y211810D01*
G01X419989Y214650D02*
X418989Y212098D01*
X418701Y211810D01*
G01X415551D02*
Y213959D01*
X415879Y214680D01*
G01X423489Y214650D02*
X422489Y212449D01*
X421850Y211810D01*
G01X428419Y208670D02*
Y208590D01*
X428479Y208530D01*
Y205200D01*
G01X428150Y211810D02*
X428419Y211541D01*
Y208670D01*
G01X426750Y241000D02*
Y237250D01*
X421000Y231500D01*
G01X426750Y245000D02*
Y245750D01*
X431500Y250500D01*
X435000D01*
X439000Y254500D01*
G01X419455Y293000D02*
X420300Y292155D01*
Y284245D01*
X419600Y283545D01*
Y282900D01*
G01X435055Y284250D02*
X433705Y282900D01*
X419600D01*
G01X438055Y319250D02*
Y317000D01*
X435555Y314500D01*
X428750D01*
G01X418273Y326283D02*
X418773Y326783D01*
Y328222D01*
X420668Y330117D01*
G01X430523Y323533D02*
X426523D01*
G01X439029Y108000D02*
X431290D01*
X430540Y108750D01*
G01X430790Y139000D02*
Y142010D01*
X431300Y142520D01*
G01X438290Y139000D02*
Y141829D01*
X437599Y142520D01*
G01X434790Y139000D02*
Y142180D01*
X434450Y142520D01*
G01X435079Y151710D02*
Y154488D01*
X434449Y155118D01*
G01X438579Y151710D02*
Y154137D01*
X437598Y155118D01*
G01X437133Y145701D02*
Y148353D01*
X437598Y148818D01*
G01X434269Y164850D02*
Y167536D01*
X434449Y167716D01*
G01X434179Y170860D02*
Y173745D01*
X434449Y174015D01*
G01X434129Y158620D02*
Y161097D01*
X434449Y161417D01*
G01X437679Y170860D02*
X437598Y170779D01*
Y167716D01*
G01X437769Y164850D02*
Y167545D01*
X437598Y167716D01*
G01Y174015D02*
X437679Y173934D01*
Y170860D01*
G01X437629Y158620D02*
X437598Y158651D01*
Y161417D01*
G01X434379Y183800D02*
Y186544D01*
X434448Y186613D01*
G01X434179Y177400D02*
Y180044D01*
X434449Y180314D01*
G01X437679Y177400D02*
Y180233D01*
X437598Y180314D01*
G01X437879Y183800D02*
Y186333D01*
X437598Y186614D01*
G01X434179Y189750D02*
Y192643D01*
X434449Y192913D01*
G01X434499Y202480D02*
X434414Y202565D01*
Y205514D01*
G01X434679Y196000D02*
Y198982D01*
X434449Y199212D01*
G01X437999Y202480D02*
Y205110D01*
X437598Y205511D01*
G01X437679Y189750D02*
Y192832D01*
X437598Y192913D01*
G01X438179Y196000D02*
Y198631D01*
X437598Y199212D01*
G01X434489Y208870D02*
X434449Y208910D01*
Y211810D01*
G01X437989Y208870D02*
Y211419D01*
X437598Y211810D01*
G01X553555Y321000D02*
X552847D01*
X549055Y317208D01*
Y314500D01*
X545055Y310500D01*
Y298755D01*
X533800Y287500D01*
X495522D01*
X493022Y290000D01*
X468500D01*
X465000Y293500D01*
X456000D01*
X446955Y284455D01*
Y282581D01*
X445374Y281000D01*
X442900D01*
X439800Y284100D01*
G01D02*
X439650Y284250D01*
X435055D01*
G01X444055Y298750D02*
Y300300D01*
X458355Y314600D01*
G01X434448Y320783D02*
X435981Y319250D01*
X438055D01*
G01X444305Y372500D02*
Y369502D01*
X444290Y369487D01*
G01X433073Y1009860D02*
Y998605D01*
X435678Y996000D01*
G01X444883Y1009860D02*
Y997705D01*
X443178Y996000D01*
G01X459179Y118000D02*
Y119321D01*
X457500Y121000D01*
G01X449679Y113500D02*
X450929Y114750D01*
Y118000D01*
G01D02*
X446790D01*
G01X455679D02*
X450929D01*
G01X451679Y171500D02*
X457429D01*
G01X461929Y183750D02*
X459679D01*
X458429Y185000D01*
G01X461929Y180250D02*
X455829D01*
X455054Y179475D01*
G01X451679Y180000D02*
Y175500D01*
G01Y180000D02*
X454404D01*
X454929Y179475D01*
X455054D01*
G01X451679Y184500D02*
Y180000D01*
G01X458355Y314600D02*
X459213Y313742D01*
Y311087D01*
X462462Y307838D01*
X464200D01*
G01X460305Y372500D02*
Y369752D01*
X460040Y369487D01*
G01X447805Y372500D02*
Y369909D01*
X448227Y369487D01*
G01X456805Y372500D02*
Y370189D01*
X456103Y369487D01*
G01X451055Y381750D02*
X448677D01*
X448227Y381300D01*
G01X451055Y385750D02*
X448740D01*
X448227Y385237D01*
G01X451055Y378250D02*
X449114D01*
X448227Y377363D01*
G01X451055Y389250D02*
X448303D01*
X448227Y389174D01*
G01X450678Y808750D02*
Y807700D01*
X452978Y805400D01*
G01X455778Y875750D02*
Y877850D01*
X457578Y879650D01*
Y879700D01*
G01X460628Y1009860D02*
Y997950D01*
X458678Y996000D01*
G01X448818Y1009860D02*
Y997360D01*
X450178Y996000D01*
G01X468179Y104000D02*
X469549Y105370D01*
X471190D01*
X471480Y105660D01*
G01D02*
X479000Y113180D01*
Y116500D01*
G01X471429Y126250D02*
Y122250D01*
X471179Y122000D01*
G01X471290Y118361D02*
X471179Y118472D01*
Y122000D01*
G01X471429Y129750D02*
Y133500D01*
G01X474179Y149000D02*
X474429D01*
X475929Y147500D01*
X477291D01*
G01X474179Y153500D02*
X477800D01*
X477900Y153600D01*
G01X464287Y302717D02*
Y302213D01*
X468700Y297800D01*
X469155D01*
G01X467405Y308700D02*
X465262D01*
X464400Y307838D01*
X464200D01*
G01X467805Y372500D02*
Y369596D01*
X467914Y369487D01*
G01X464305Y372500D02*
Y369815D01*
X463977Y369487D01*
G01X476378Y1009860D02*
Y997700D01*
X474178Y995500D01*
G01X464568Y1009860D02*
Y997610D01*
X466178Y996000D01*
G01X513200Y121450D02*
X512379D01*
X510129Y119200D01*
X482129D01*
X479429Y116500D01*
X479000D01*
G01X479750Y186231D02*
X479781Y186262D01*
Y190291D01*
G01X480500Y181800D02*
X479673Y182627D01*
Y186154D01*
X479750Y186231D01*
G01X479773Y334283D02*
Y337943D01*
X479725Y337991D01*
G01X489555Y431250D02*
X492555D01*
G01X498500Y867500D02*
X494078D01*
G01X492128Y1009860D02*
Y997950D01*
X489678Y995500D01*
G01X480313Y1009860D02*
Y997365D01*
X482178Y995500D01*
G01X499819Y-438119D02*
Y-518119D01*
G01X507055Y408750D02*
X503456D01*
X503347Y408859D01*
G01X507055Y412250D02*
X504305D01*
G01X507873Y1009860D02*
Y997695D01*
X505678Y995500D01*
G01X496063Y1009860D02*
Y997615D01*
X498178Y995500D01*
G01X524179Y124500D02*
Y122722D01*
X520991Y119534D01*
Y114709D01*
X521700Y114000D01*
G01X517679Y121625D02*
Y125750D01*
G01X525679Y141000D02*
Y136250D01*
G01X514679Y151000D02*
Y154821D01*
X513000Y156500D01*
G01X523623Y1009860D02*
Y997945D01*
X521178Y995500D01*
G01X527558Y1009860D02*
Y998025D01*
X530083Y995500D01*
G01X511813Y1009860D02*
Y997365D01*
X513678Y995500D01*
G01X538875Y142250D02*
Y138000D01*
G01X539368Y1009860D02*
Y998690D01*
X536678Y996000D01*
G01X559750Y264500D02*
X561000D01*
X580500Y284000D01*
Y291568D01*
X583432Y294500D01*
X589816D01*
X592500Y297184D01*
Y310000D01*
X596500Y314000D01*
Y510500D01*
X626500Y540500D01*
Y557350D01*
G01X563555Y333000D02*
Y328983D01*
X561347Y326775D01*
X559330D01*
X553555Y321000D01*
G01X548555Y345250D02*
Y346500D01*
X552255Y350200D01*
X563174D01*
X564755Y348619D01*
Y344700D01*
X563143Y343088D01*
Y333412D01*
X563555Y333000D01*
G01X552555Y345250D02*
X556555D01*
G01D02*
X559805D01*
X562055Y347500D01*
G01X562993Y1009860D02*
Y998315D01*
X560678Y996000D01*
G01X566928Y1009860D02*
Y998250D01*
X569178Y996000D01*
G01X578738Y1009860D02*
Y998060D01*
X576678Y996000D01*
G01X585315Y38832D02*
Y44134D01*
G01D02*
Y49436D01*
G01X580013Y44134D02*
X585315D01*
G01D02*
X590617D01*
G01X591903Y80118D02*
X595905D01*
G01X582678Y1009860D02*
Y996500D01*
X584678Y994500D01*
G01X599941Y66116D02*
Y70118D01*
G01D02*
Y74120D01*
G01X595939Y70118D02*
X599941D01*
G01X595905Y76116D02*
Y80118D01*
G01D02*
Y84120D01*
G01X594488Y1007910D02*
Y987512D01*
X598178Y983822D01*
G01D02*
Y983500D01*
G01X623500Y576500D02*
Y560350D01*
X626500Y557350D01*
G01X628524Y591976D02*
Y582524D01*
X623500Y577500D01*
Y576500D01*
G01X642800Y433587D02*
X643200Y433987D01*
Y445800D01*
X641500Y447500D01*
Y449500D01*
G01X646500Y452250D02*
X644250D01*
X641500Y449500D01*
G01X632500Y530000D02*
Y456000D01*
X636500Y452000D01*
Y444800D01*
G01X641625Y458750D02*
Y465375D01*
G01X654527Y38832D02*
Y44134D01*
G01D02*
Y49436D01*
G01X649225Y44134D02*
X654527D01*
G01D02*
X659829D01*
G01X647125Y434750D02*
Y429375D01*
G01X656162Y465964D02*
Y472338D01*
G01X645500Y475750D02*
Y481000D01*
G01D02*
Y503000D01*
X683100Y540600D01*
X751484D01*
G01X663360Y483321D02*
X656381Y490300D01*
X654300D01*
G01X667319Y-438119D02*
Y-518119D01*
G01X678400Y398850D02*
X673850D01*
X670000Y395000D01*
G01X678500Y410250D02*
X674250D01*
X670500Y414000D01*
G01X665000Y446000D02*
Y441900D01*
X664900Y441800D01*
G01X669025Y441725D02*
X664975D01*
X664900Y441800D01*
G01X680700Y446000D02*
X675411D01*
G01D02*
X671000D01*
G01X668800Y465993D02*
X670798D01*
X673000Y466000D01*
G01X663762Y465964D02*
X668464D01*
X668493Y465993D01*
X668800D01*
G01X673000Y466000D02*
Y468000D01*
X669462Y471538D01*
Y472500D01*
G01X673010Y474436D02*
X664125Y483321D01*
X663360D01*
G01X687500Y440500D02*
X688300Y441300D01*
Y446000D01*
G01D02*
X688500Y445800D01*
X693100D01*
G01X679000Y466000D02*
X679900Y466900D01*
Y470200D01*
G01X677500Y472500D02*
X677600D01*
X679900Y470200D01*
G01X706966Y122784D02*
Y126284D01*
G01X706748Y117000D02*
X706966Y117218D01*
Y122784D01*
G01X706748Y117000D02*
X703280D01*
X701949Y118331D01*
G01X697248Y128000D02*
X699848Y125400D01*
X701748D01*
G01X706966Y126284D02*
X704232D01*
X703348Y125400D01*
X701748D01*
G01X718948Y107500D02*
Y110016D01*
X721716Y112784D01*
G01X719683Y1009860D02*
Y1000317D01*
X723000Y997000D01*
G01D02*
Y996500D01*
G01X726548Y107500D02*
Y103700D01*
X730748Y99500D01*
G01X731716Y109534D02*
X735216D01*
G01D02*
X740000D01*
G01X823500Y556500D02*
Y532136D01*
X776364Y485000D01*
X773805D01*
X767500Y478695D01*
Y462181D01*
X756619Y451300D01*
X736700D01*
X732500Y455500D01*
G01X728500Y482500D02*
Y472000D01*
X736000Y464500D01*
G01D02*
X751000D01*
X758500Y457000D01*
G01X774500Y489500D02*
X771500D01*
X764500Y482500D01*
X728500D01*
G01X739368Y1009860D02*
Y996610D01*
G01X727558Y1009860D02*
Y996500D01*
G01X751484Y540600D02*
X760500Y531584D01*
Y489500D01*
G01X787000Y400500D02*
X798000D01*
G01X787000Y414750D02*
X782600D01*
G01D02*
Y411000D01*
G01X776750Y968500D02*
Y964750D01*
G01X803500Y655000D02*
X823500Y635000D01*
Y556500D01*
G01X837319Y-438119D02*
Y-518119D01*
G01X829500Y385500D02*
X829800Y385800D01*
Y408300D01*
X852300Y430800D01*
X906714D01*
X929430Y453516D01*
Y461510D01*
X945720Y477800D01*
Y478280D01*
G01X867914Y286803D02*
Y290355D01*
G01X863974Y294678D02*
Y298230D01*
G01D02*
Y301782D01*
G01X860422Y298230D02*
X863974D01*
G01D02*
X867526D01*
G01X867914Y290355D02*
Y293907D01*
G01X864362Y290355D02*
X867914D01*
G01D02*
X871466D01*
G01X863974Y304518D02*
Y308070D01*
G01D02*
Y311622D01*
G01X860422Y308070D02*
X863974D01*
G01D02*
X867526D01*
G01X867914Y312393D02*
Y315945D01*
G01D02*
Y319497D01*
G01X864362Y315945D02*
X867914D01*
G01D02*
X871466D01*
G01X871849Y304518D02*
Y308070D01*
G01D02*
Y311622D01*
G01X868297Y308070D02*
X871849D01*
G01D02*
X875401D01*
G01X885000Y438700D02*
X875800D01*
X870500Y444000D01*
G01X877000Y479500D02*
Y474801D01*
X870500Y468301D01*
Y448000D01*
G01X887950Y359730D02*
X929150D01*
X932420Y363000D01*
X963500D01*
X965000Y364500D01*
G01X1055500Y360000D02*
X1055000Y359500D01*
X934500D01*
X931230Y356230D01*
X884670D01*
X880740Y360160D01*
X874910D01*
G01X887940Y380200D02*
X887948Y380208D01*
Y399052D01*
X882500Y404500D01*
X878000D01*
G01X885000Y438700D02*
X907990D01*
X918420Y449130D01*
G01X945720Y478280D02*
X949465Y482025D01*
X1164475D01*
X1165500Y481000D01*
X1195243D01*
X1220300Y506057D01*
Y507229D01*
X1224518Y511447D01*
X1224575D01*
X1238628Y525500D01*
X1252077D01*
X1257725Y531148D01*
Y555125D01*
X1258000Y555400D01*
G01X1012000Y50500D02*
Y43000D01*
G01X1033500Y118000D02*
X1031500D01*
X1022000Y127500D01*
Y140500D01*
X1020500Y142000D01*
G01X1034819Y-438119D02*
Y-518119D01*
G01X1066819Y-422119D02*
X1034819D01*
G01X1035750Y145500D02*
X1029000Y152250D01*
Y163500D01*
X1028000Y164500D01*
G01X1051034Y173534D02*
X1037034D01*
X1028000Y164500D01*
G01X1050819Y-438119D02*
Y-406119D01*
G01X1062819Y-422119D02*
G02I-12000J0D01*
G01X1057669D02*
G02I-6850J0D01*
G01X1052984Y43267D02*
X1057086D01*
G01X1045000Y141500D02*
Y138062D01*
X1045031Y138031D01*
G01X1050200Y140500D02*
X1049200Y141500D01*
X1045000D01*
G01X1060900Y173534D02*
X1051034D01*
G01X1080300Y191000D02*
X1080000D01*
X1077500Y188500D01*
X1053500D01*
X1052500Y187500D01*
G01X1057086Y43267D02*
Y47369D01*
G01Y43267D02*
X1061188D01*
G01X1063750Y120500D02*
X1066500D01*
X1068500Y118500D01*
G01X1063750Y124500D02*
X1069000D01*
G01X1057800Y140500D02*
X1063000D01*
G01D02*
X1067500D01*
G01X1084646Y39165D02*
Y43267D01*
G01D02*
Y47369D01*
G01X1080544Y43267D02*
X1084646D01*
G01D02*
X1088748D01*
G01X1072000Y136000D02*
X1073500Y137500D01*
Y140500D01*
G01X1084500Y202500D02*
X1083000Y201000D01*
Y194000D01*
X1080300Y191300D01*
Y191000D01*
G01X1077750Y640000D02*
X1075500D01*
X1073000Y637500D01*
G01X1077750Y675500D02*
X1075500D01*
X1074000Y677000D01*
G01X1077750Y671500D02*
X1074000D01*
X1073500Y672000D01*
G01X1101500Y461500D02*
X1170000D01*
X1170500Y461000D01*
G01X1087738Y650584D02*
X1087500Y650346D01*
Y648900D01*
X1088400Y648000D01*
Y647484D01*
G01X1124800Y804000D02*
X1124796Y803996D01*
G01X1131300Y804000D02*
X1131095Y803795D01*
G01X1124796Y803996D02*
Y800150D01*
G01X1131095Y803795D02*
Y799965D01*
G01X1124800Y810000D02*
X1122667D01*
X1121167Y808500D01*
X1121000D01*
G01X1131300Y810000D02*
X1135000D01*
G01X1149268Y675934D02*
X1151014D01*
X1152090Y677010D01*
G01X1141850Y684800D02*
X1141282Y684232D01*
Y684210D01*
X1139856Y682784D01*
X1135659D01*
X1135589Y682854D01*
G01X1140718Y688284D02*
Y691214D01*
X1139858Y692074D01*
G01X1139000Y700500D02*
X1137786Y701714D01*
X1135589D01*
G01X1142000Y805500D02*
X1141950Y805160D01*
X1142010Y805220D01*
Y809500D01*
G01X1162000Y644750D02*
Y643500D01*
X1159700Y641200D01*
X1159500D01*
X1159100Y640800D01*
G01X1163250Y704500D02*
X1163968Y705218D01*
Y708000D01*
G01X1165300Y804750D02*
Y809610D01*
G01X1160300Y804750D02*
Y809610D01*
G01X1154300Y806250D02*
Y809610D01*
G01X1173500Y422500D02*
X1188000D01*
X1189000Y421500D01*
G01X1176250Y701300D02*
Y698810D01*
X1176496Y698564D01*
G01X1170300Y804750D02*
Y809610D01*
G01X1200370Y704500D02*
X1201670Y703200D01*
X1204390D01*
G01Y709200D02*
X1203191Y708001D01*
X1200371D01*
X1200370Y708000D01*
G01D02*
Y708130D01*
X1198000Y710500D01*
X1196000D01*
G01X1217000Y630750D02*
X1219250D01*
X1221500Y633000D01*
G01X1217500Y705200D02*
X1211000D01*
G01X1216000Y702500D02*
X1217500Y704000D01*
Y705200D01*
G01X1211000D02*
X1209000Y703200D01*
X1204390D01*
G01X1227177Y205800D02*
X1233700D01*
X1235500Y204000D01*
X1239500D01*
G01X1225750Y718500D02*
Y714750D01*
X1225500Y714500D01*
G01X1225750Y722500D02*
X1226000D01*
X1229000Y725500D01*
Y726500D01*
G01X1248250Y719500D02*
Y722500D01*
X1249000Y723250D01*
G01X1268500Y427000D02*
X1268000Y426500D01*
X1265000D01*
G01X1260500Y637750D02*
X1259750D01*
X1257500Y635500D01*
G01X1261250Y667500D02*
Y667750D01*
X1262300Y668800D01*
Y670700D01*
G01X1253750Y671000D02*
X1257124D01*
X1258562Y672438D01*
G01X1259250Y719500D02*
Y723750D01*
X1259500Y724000D01*
G01X1259250Y715500D02*
X1261500D01*
X1263000Y717000D01*
G01X1275300Y433000D02*
X1280500D01*
G01D02*
X1284500D01*
G01X1267700D02*
X1268500Y432200D01*
Y427000D01*
G01X1272000Y463500D02*
Y466100D01*
X1272500Y466600D01*
G01X1281000Y690750D02*
Y693400D01*
X1279600Y694800D01*
G01X1281000Y698250D02*
X1316250D01*
X1318000Y696500D01*
G01X1281000Y709250D02*
X1283500D01*
X1284490Y710240D01*
Y710936D01*
G01X1273000Y727750D02*
Y730000D01*
X1275000Y732000D01*
G01X1277000Y727750D02*
Y730000D01*
X1275000Y732000D01*
G01X1281000Y716250D02*
X1289250D01*
X1289500Y716500D01*
G01X1281000Y727750D02*
X1284032D01*
X1286760Y730478D01*
X1292500D01*
G01Y405750D02*
Y402000D01*
G01Y416750D02*
X1290250D01*
X1289000Y415500D01*
G01X1290500Y433000D02*
Y429500D01*
X1289000Y428000D01*
X1287500D01*
G01X1312500Y607750D02*
X1306837D01*
X1306423Y608164D01*
G01X1312500Y611250D02*
X1309662D01*
X1308500Y612412D01*
X1305217D01*
G01X1306500Y645250D02*
X1311466D01*
X1312000Y645784D01*
G01X1306500Y648750D02*
X1309250D01*
X1311000Y650500D01*
Y651900D01*
G01X1323500Y452500D02*
Y454993D01*
X1330507Y462000D01*
X1373700D01*
X1374500Y462800D01*
G01X1338526Y17754D02*
Y21656D01*
G01X1334624D02*
X1338526D01*
G01X1345500Y394500D02*
X1348500D01*
X1353000Y390000D01*
G01X1344250Y399500D02*
X1349000D01*
G01X1350084Y284418D02*
Y296500D01*
G01X1358584Y284418D02*
X1358500Y284502D01*
Y288916D01*
G01X1349000Y399500D02*
X1350500D01*
X1353000Y402000D01*
G01X1384500Y319250D02*
X1379500D01*
G01D02*
Y314000D01*
G01Y322750D02*
Y324000D01*
X1375500Y328000D01*
G01X1368000Y454400D02*
Y450500D01*
G01X1392657Y55837D02*
Y60039D01*
G01D02*
Y64241D01*
G01X1388455Y60039D02*
X1392657D01*
G01Y92058D02*
Y96260D01*
G01D02*
Y100462D01*
G01X1388455Y96260D02*
X1392657D01*
X50000Y659500D03*
X58804Y699720D03*
X109000Y844220D03*
X111000Y981500D03*
X112900Y988500D03*
X124500Y515500D03*
X128000Y544050D03*
X121200Y584278D03*
X166200Y506500D03*
X172000Y486400D03*
X182000Y577500D03*
X176938Y680465D03*
X182500Y677500D03*
X242500Y565500D03*
X234000Y562000D03*
X236500Y574000D03*
X238500Y705000D03*
X253500Y707250D03*
X311500Y153000D03*
X299000Y148000D03*
X307129Y143000D03*
X305029Y147700D03*
X304300Y160200D03*
X304100Y167000D03*
X311300D03*
X312500Y159100D03*
X306155Y497700D03*
X305155Y504900D03*
X330250Y80000D03*
X330900Y134500D03*
X319014Y152977D03*
X328700Y154400D03*
X328629Y146800D03*
X330400Y141600D03*
X331040Y152601D03*
X330929Y148600D03*
X318200Y159100D03*
X320238Y497183D03*
X320338Y507683D03*
X316273Y520282D03*
X347000Y120040D03*
X340000D03*
X338000Y127500D03*
X337400Y134500D03*
X334000Y147600D03*
X344055Y529000D03*
X340055Y524000D03*
X342971Y525750D03*
X339000Y878500D03*
X336000Y871500D03*
X339000Y894000D03*
Y885500D03*
X337300Y949500D03*
X357394Y131496D03*
X353740Y133300D03*
X362009Y142520D03*
Y148819D03*
Y155119D03*
X352040Y143000D03*
X349829Y153400D03*
X362036Y170876D03*
X362034Y161406D03*
X355084Y172441D03*
X351929Y162200D03*
X353085Y187485D03*
X355040Y180000D03*
X362017Y183492D03*
X362036Y177155D03*
X358858Y177128D03*
X358848Y174010D03*
X354540Y199000D03*
X358879Y192929D03*
X351320Y194520D03*
X361987Y189747D03*
X358850Y196050D03*
X355090Y195660D03*
X355139Y190099D03*
X351731Y190274D03*
X361155Y496203D03*
X356555Y513000D03*
X357055Y507000D03*
X356055Y502000D03*
X368307Y133071D03*
X374606Y136221D03*
X368296Y136246D03*
X371456Y136221D03*
X368305Y139401D03*
X371482Y133058D03*
X365133Y129133D03*
X374600Y139390D03*
X377750Y139400D03*
X371458Y142520D03*
X377765Y155146D03*
X374589Y155110D03*
X371455Y148854D03*
X377787Y148812D03*
X368333Y155107D03*
X365140Y155100D03*
X377757Y145670D03*
X368333Y148827D03*
X368329Y151956D03*
X371493Y145667D03*
X368314Y142505D03*
Y145680D03*
X371457Y155080D03*
X377759Y152000D03*
X365146Y151942D03*
X365182Y142532D03*
X374607Y142520D03*
X377757D03*
X365186Y170876D03*
X377732Y167703D03*
X377718Y161417D03*
X371470Y167741D03*
X371489Y161411D03*
X368309Y170830D03*
X368334Y167706D03*
X365158Y164554D03*
X368325Y164585D03*
X368326Y161400D03*
X368271Y158268D03*
X374582Y161404D03*
X374577Y164559D03*
X377750Y170846D03*
X374570Y158267D03*
X365176Y161400D03*
X365186Y177175D03*
X368320Y183460D03*
X377741Y177188D03*
X377731Y180302D03*
X371457Y173978D03*
X365187Y186605D03*
X368308Y177202D03*
X374560Y177210D03*
X371485Y177175D03*
X368336Y189755D03*
X368307Y196062D03*
Y202361D03*
X377755D03*
Y199211D03*
Y196062D03*
Y192912D03*
Y189763D03*
X368307Y205511D03*
Y199211D03*
X368336Y192904D03*
X374606Y189763D03*
Y192912D03*
X374607Y218110D03*
X374606Y211810D03*
X377756D03*
X365158D03*
X371457D03*
X367665Y363430D03*
X368055Y380500D03*
X368555Y385000D03*
Y376500D03*
X371781Y387924D03*
X368555Y389000D03*
X368165Y393402D03*
X370500Y518000D03*
X379500Y963500D03*
X390354Y136221D03*
X380906Y136220D03*
X390355Y139371D03*
X380920Y139370D03*
X387173Y139376D03*
X392240Y129000D03*
X383680Y129030D03*
X396683Y139362D03*
X393510Y139340D03*
X384019Y139371D03*
X384055Y155117D03*
X396653D03*
X380907Y142520D03*
X387206Y145670D03*
X390355Y142520D03*
X393505Y145670D03*
X384093Y151968D03*
X393519Y151990D03*
X384056Y145670D03*
X390355D03*
X396655D03*
X387206Y142520D03*
X384056D03*
X390339Y151990D03*
X396639D03*
X380888Y148799D03*
X396655Y142520D03*
X393505D03*
X384055Y158266D03*
X396653D03*
X390354Y167715D03*
X396653D03*
X384032Y167703D03*
X380944Y161417D03*
X387219Y158290D03*
X387205Y167715D03*
X384041Y170888D03*
X380928Y167701D03*
X393528Y167702D03*
X390392Y186614D03*
X384055Y186613D03*
X396654Y186614D03*
X396653Y174015D03*
Y180314D03*
X387204Y177164D03*
X384032Y174003D03*
X384030Y177120D03*
X393542Y186614D03*
X393490Y174039D03*
X393541Y180315D03*
X384055Y202361D03*
X393503Y205510D03*
X396654Y202362D03*
X396653Y205511D03*
Y199211D03*
X384055Y192912D03*
Y196062D03*
X396653Y192912D03*
X384036Y189747D03*
X393519Y192900D03*
X387209Y192930D03*
X393503Y211809D03*
X380906Y211810D03*
X396654D03*
X396653Y208660D03*
X393503D03*
X390354Y218109D03*
Y221259D03*
X384055Y211810D03*
X393504Y218109D03*
X390354Y224408D03*
X389500Y319150D03*
X392589Y317729D03*
X394055Y335000D03*
X391325Y324520D03*
X386755Y326100D03*
X384160Y328812D03*
X391555Y338350D03*
X393061Y346800D03*
X393755Y350500D03*
X390230Y349327D03*
X396055Y338000D03*
X395855Y366890D03*
X392991Y365797D03*
X391628Y358852D03*
X394915Y359725D03*
X387515Y365500D03*
X387265Y384370D03*
X394935Y385150D03*
X382803Y385207D03*
X391215Y384900D03*
X396490Y388597D03*
X388500Y400575D03*
X390543Y391950D03*
X387000Y404275D03*
X396500Y910500D03*
X388750Y951750D03*
X387061Y986061D03*
X389500Y992000D03*
X402950Y133050D03*
X399835Y139375D03*
X412429Y136210D03*
X399783Y136237D03*
X402953Y139370D03*
X402800Y129180D03*
X406103Y139371D03*
X412415Y148794D03*
X399779Y142531D03*
X399804Y145670D03*
X412403Y142520D03*
X406102Y155117D03*
X412402Y155118D03*
X412401Y151967D03*
X399819Y151950D03*
X406125Y148804D03*
X406110Y145660D03*
X402954Y145670D03*
Y142520D03*
X406103D03*
X402938Y151950D03*
X402952Y167715D03*
X409251D03*
X412401Y158267D03*
X406102D03*
X399827Y167702D03*
X406140Y167716D03*
X406127Y161404D03*
X412427D03*
X412426Y167703D03*
X402977Y174003D03*
X402952Y186613D03*
X409251D03*
X409288Y180315D03*
X402952Y180314D03*
X409251Y174015D03*
X399841Y186614D03*
X399840Y180315D03*
X399790Y174039D03*
X406126Y174003D03*
X406139Y180315D03*
X406101Y186613D03*
X412426Y174003D03*
X412439Y186614D03*
X412400Y180314D03*
X412401Y205510D03*
X402952Y192912D03*
X409251D03*
X406128Y192901D03*
X399791Y192938D03*
X412428Y192901D03*
X402953Y211810D03*
X412402D03*
X399803Y218109D03*
Y221259D03*
Y208660D03*
Y211810D03*
X406102D03*
X406099Y214950D03*
X409249Y214965D03*
X412767Y233162D03*
X400000Y237500D03*
X409500Y271500D03*
X404920Y330117D03*
X412794D03*
X404920Y334054D03*
X412794D03*
X408857D03*
X400983D03*
X397983Y333998D03*
X408857Y330117D03*
X400523Y325283D03*
X412815Y349860D03*
X408857Y341928D03*
X412794D03*
X397555Y345146D03*
X398055Y350296D03*
X398555Y339283D03*
X408857Y345865D03*
X404965Y342120D03*
X412794Y337991D03*
X400055Y343146D03*
X408857Y365550D03*
Y357676D03*
X412794Y365550D03*
Y357676D03*
X397117Y364138D03*
X412794Y353739D03*
X404920Y369487D03*
X412794Y361613D03*
X408925Y361680D03*
X400395Y362450D03*
X400885Y354120D03*
X404935Y353840D03*
X412794Y369487D03*
X408857D03*
Y353739D03*
Y385237D03*
Y377363D03*
X412794D03*
Y385237D03*
Y381300D03*
X399923Y372000D03*
X408857Y400985D03*
Y393111D03*
X412794Y400985D03*
Y393111D03*
X408857Y389174D03*
X400983Y400985D03*
X404920Y397048D03*
Y400985D03*
Y389174D03*
X412794Y397048D03*
Y389174D03*
X408857Y397048D03*
X400983D03*
X404920Y393111D03*
X408857Y416733D03*
Y408859D03*
X412794Y416733D03*
Y408859D03*
X400983Y404922D03*
X412794Y412796D03*
X404920Y404922D03*
X408857D03*
Y412796D03*
X412794Y404922D03*
X404920Y416733D03*
X400983D03*
X408857Y424607D03*
X412794D03*
X408857Y420670D03*
X412794D03*
X404555Y430500D03*
X404920Y420670D03*
X406555Y428300D03*
X399555Y438500D03*
X428375Y119735D03*
X418940Y125000D03*
X415552Y136221D03*
X421590Y128500D03*
X418702Y136221D03*
X413540Y128500D03*
X425000Y136220D03*
X428116Y136218D03*
X421851Y136221D03*
X423686Y126215D03*
X415549Y151990D03*
X418702Y142520D03*
X425001D03*
X421851D03*
X415552D03*
X428151D03*
X418700Y148818D03*
X428149D03*
X415551D03*
X424999D03*
X421850D03*
X428149Y164565D03*
Y170865D03*
X421876Y167705D03*
X415575Y167703D03*
X424999Y161416D03*
X428149D03*
X418726Y167703D03*
X428149Y183463D03*
Y177164D03*
X421876Y174005D03*
Y180304D03*
Y186603D03*
X415551Y186614D03*
X415587Y180315D03*
X415551Y174015D03*
X418726Y174003D03*
Y180303D03*
X418701Y186614D03*
X424999Y199211D03*
X428149D03*
X424999Y202361D03*
X428149D03*
X421876Y192902D03*
X428149Y192912D03*
X415551D03*
X424999D03*
X418727Y192902D03*
X418701Y211810D03*
X425001D03*
X428150D03*
X415551D03*
X421850D03*
X428172Y221320D03*
X424979Y218127D03*
X428047Y218049D03*
X415551Y218109D03*
X418729Y218100D03*
X421850Y218109D03*
X418729Y221268D03*
X420500Y234500D03*
X422630Y227232D03*
X426147Y230982D03*
X420714Y225190D03*
X429444Y230192D03*
X419000Y227405D03*
X427965Y318293D03*
X419913Y318051D03*
X417650Y316400D03*
X416482Y319022D03*
X424555Y318000D03*
X420668Y330117D03*
X428542D03*
X420668Y334054D03*
X428542D03*
X424023Y320783D03*
X424605Y334054D03*
Y330117D03*
X416731D03*
X416950Y321783D03*
X416731Y334054D03*
X424605Y345865D03*
X420668Y337991D03*
X428542Y345865D03*
X416615Y349930D03*
X428542Y349802D03*
Y341928D03*
X424605Y337991D03*
X428542D03*
X420668Y341928D03*
X424605Y349802D03*
X420668D03*
X416731Y337991D03*
X420668Y345865D03*
X416731Y341928D03*
X424605D03*
Y369487D03*
Y361613D03*
Y353739D03*
X428542Y361613D03*
Y369487D03*
Y353739D03*
X416731D03*
X420668Y357676D03*
X428542Y365550D03*
X416731Y369487D03*
X420668Y353739D03*
X416731Y365550D03*
X424605D03*
X420668D03*
X416731Y361613D03*
X420668Y369487D03*
X424605Y357676D03*
X420668Y361613D03*
X416555Y357500D03*
X428542Y357676D03*
X424605Y385237D03*
X428542D03*
Y381300D03*
X428500Y377000D03*
X416731Y381300D03*
Y377363D03*
X428445Y373550D03*
X420668Y377363D03*
Y385237D03*
X416731D03*
X424605Y381300D03*
X420668D03*
X428542Y400985D03*
X424605D03*
Y393111D03*
X428542Y397048D03*
X420668Y400985D03*
X416731Y389174D03*
X428555Y393000D03*
X420668Y389174D03*
X416731Y393111D03*
Y397048D03*
X420668Y393111D03*
X424605Y397048D03*
X428542Y389174D03*
X420668Y397048D03*
X416731Y400985D03*
X424605Y389174D03*
Y404922D03*
Y408859D03*
X420668Y404922D03*
X428542Y408859D03*
X420668D03*
X428542Y404922D03*
X428523Y416683D03*
X416731Y416733D03*
Y404922D03*
Y412796D03*
X424605D03*
X423555Y431500D03*
X416731Y420670D03*
Y424607D03*
X419500Y914000D03*
X432540Y123000D03*
X435640D03*
X437599Y136221D03*
X434450D03*
X439540Y124500D03*
X431407Y136285D03*
X440931Y129061D03*
X431348Y125911D03*
X442323Y126000D03*
X437945Y127159D03*
X434449Y155118D03*
X431300Y142520D03*
X437599D03*
X437598Y148818D03*
Y155118D03*
X434450Y142520D03*
X440765Y145670D03*
X443928Y148811D03*
X443891Y151999D03*
X443890Y142565D03*
X443909Y145650D03*
X443936Y155118D03*
X431299Y164565D03*
Y170865D03*
X434449Y167716D03*
Y161417D03*
X431299Y161416D03*
X437598Y167716D03*
Y161417D03*
X443899Y161430D03*
X443882Y167737D03*
X443899Y164530D03*
X443871Y158278D03*
X431299Y183463D03*
X434449Y180314D03*
Y174015D03*
X431299Y177164D03*
X434448Y186613D03*
X431299D03*
X437598Y174015D03*
Y180314D03*
Y186614D03*
X443910Y174041D03*
X443879Y180320D03*
X443887Y177138D03*
X440769Y183480D03*
X443919D03*
X434414Y205514D03*
X434449Y199212D03*
Y192913D03*
X437598Y205511D03*
Y199212D03*
Y192913D03*
X443897Y205512D03*
Y192914D03*
X443898Y199212D03*
X443897Y202363D03*
Y196063D03*
X434449Y211810D03*
X437598D03*
X443897Y211811D03*
Y208662D03*
X431336Y218111D03*
X434448Y218109D03*
X437598D03*
X436529Y229500D03*
X434334Y226789D03*
X443113Y226339D03*
X439980Y232126D03*
X441379Y229700D03*
X432307Y224857D03*
X437112Y232239D03*
X445892Y225995D03*
X436500Y241000D03*
X438500Y250000D03*
X431023Y317283D03*
X430513Y320841D03*
X436416Y330117D03*
X444290D03*
X440353D03*
X434448Y320783D03*
X440353Y334054D03*
X432523Y330283D03*
X444555Y334000D03*
X441335Y321000D03*
X436416Y334054D03*
X440353Y349802D03*
X444290D03*
X440353Y341928D03*
X436416Y345865D03*
X432585Y345850D03*
X444290Y341928D03*
X432365Y341880D03*
X444290Y337991D03*
X432605Y337880D03*
X444290Y345865D03*
X440353D03*
X440555Y338000D03*
X440353Y369487D03*
X444290Y365550D03*
X440353Y353739D03*
X444290Y357676D03*
X432479Y369487D03*
Y361613D03*
X444290Y369487D03*
X436416D03*
X440353Y357676D03*
X444290Y353739D03*
X440353Y365550D03*
X436416Y353739D03*
Y361613D03*
X444290Y385237D03*
Y377363D03*
X440353Y381300D03*
X432479Y385237D03*
X436416Y377363D03*
X432479D03*
Y381300D03*
X444290D03*
X440353Y377363D03*
X436416Y381300D03*
X440353Y400985D03*
Y389174D03*
X432479Y400985D03*
Y397048D03*
Y393111D03*
Y389174D03*
X444290Y397048D03*
X440353D03*
X436416D03*
X444290Y400985D03*
X436416D03*
X444290Y389174D03*
X436416D03*
X432479Y408859D03*
Y404922D03*
X436416D03*
Y408859D03*
X444290Y404922D03*
Y408859D03*
X440353D03*
Y404922D03*
X444323Y416883D03*
X436523Y416683D03*
X440353Y412796D03*
X432479D03*
X442535Y426770D03*
X434723Y426283D03*
X448669Y126510D03*
X450209Y129230D03*
X447389Y129580D03*
X454676Y137495D03*
X456429Y135000D03*
X457929Y132500D03*
X451679Y148250D03*
X461685Y150386D03*
X455731Y154302D03*
X460300Y141100D03*
X454929Y146500D03*
X453929Y140334D03*
X459069Y151980D03*
X451329Y165570D03*
X453599Y156693D03*
X458429Y185000D03*
X450196Y189764D03*
X454329Y199800D03*
X452929Y203900D03*
X452329Y194300D03*
X447063Y199234D03*
X447047Y189764D03*
X451292Y197637D03*
X456479Y202400D03*
X455929Y192800D03*
X456229Y196700D03*
X453829Y215600D03*
X453729Y219300D03*
X452393Y210236D03*
X458029Y213469D03*
X457798Y217769D03*
X457729Y206800D03*
X448840Y225775D03*
X455429Y227500D03*
X451929Y229800D03*
X456929Y224507D03*
X456103Y330117D03*
X460040D03*
X448227D03*
X452223Y333983D03*
X448227Y334054D03*
X460040D03*
X456103D03*
X460040Y349802D03*
Y341928D03*
X448227Y349802D03*
Y341928D03*
X456103D03*
X460040Y337991D03*
X455825Y349840D03*
X448000Y346000D03*
X456055Y338000D03*
X452055D03*
X452165Y349470D03*
X456103Y365550D03*
Y357676D03*
X460040Y369487D03*
Y361613D03*
X448227Y369487D03*
Y361613D03*
Y353739D03*
X456103Y369487D03*
Y353739D03*
Y361613D03*
X460040Y357676D03*
Y365550D03*
X448227D03*
Y357676D03*
X456103Y385237D03*
Y377363D03*
X460040Y381300D03*
X448227D03*
X460040Y385237D03*
X456103Y381300D03*
X460040Y377363D03*
X448227Y385237D03*
Y377363D03*
X460040Y389174D03*
X448227D03*
X456103Y400985D03*
X460040D03*
X456103Y393111D03*
X460040D03*
Y397048D03*
X448227Y400985D03*
Y393111D03*
X456103Y397048D03*
X448227D03*
X456103Y389174D03*
X456223Y404883D03*
Y408783D03*
X456103Y412796D03*
X460023Y408883D03*
X452123Y416783D03*
X460040Y412796D03*
X448227D03*
X452223Y404883D03*
X448227Y408859D03*
X452223Y408783D03*
X448227Y404922D03*
X450725Y425460D03*
X471480Y105660D03*
X466464Y151000D03*
X466500Y144500D03*
X463969Y147610D03*
X469429Y172500D03*
Y165590D03*
X473131Y169131D03*
X477429Y162500D03*
X469429Y179500D03*
X465679Y192600D03*
X464570Y215750D03*
X467300Y320100D03*
X471851Y322243D03*
Y326180D03*
X463977Y330117D03*
X467914D03*
X463977Y334054D03*
X467914D03*
X475788Y330117D03*
Y349802D03*
Y341928D03*
X467914Y349802D03*
X463977Y341928D03*
X471851Y337991D03*
X467914D03*
X463977D03*
X471851Y349802D03*
X467914Y345865D03*
X475788Y369487D03*
Y361613D03*
Y357676D03*
X467914Y369487D03*
Y361613D03*
Y365550D03*
Y357676D03*
Y353739D03*
X463977Y365550D03*
Y357676D03*
X471851Y361613D03*
Y369487D03*
Y353739D03*
Y357676D03*
X463977Y369487D03*
Y361613D03*
Y385237D03*
X475788Y381300D03*
Y377363D03*
X467914Y385237D03*
Y377363D03*
Y381300D03*
X463977Y377363D03*
X471851D03*
Y381300D03*
X463977D03*
X475788Y400985D03*
Y397048D03*
Y393111D03*
X471851D03*
Y397048D03*
X475788Y389174D03*
X467914Y400985D03*
Y397048D03*
Y393111D03*
Y389174D03*
X463977Y393111D03*
Y397048D03*
Y400985D03*
X471851D03*
Y389174D03*
X463977D03*
Y408859D03*
Y404922D03*
X467914Y408859D03*
Y404922D03*
X471851Y412796D03*
X475788D03*
X471851Y416733D03*
X467914Y412796D03*
X475788Y424607D03*
X480500Y181800D03*
X493855Y312700D03*
X488155Y315700D03*
X490455Y319200D03*
X481255Y320000D03*
X483955Y318600D03*
X491536Y334054D03*
X479725Y330117D03*
X479655Y322500D03*
X487500Y333833D03*
X483662Y334054D03*
X487599Y330117D03*
X483662Y326180D03*
X484000Y322000D03*
X487599Y326180D03*
X487155Y321900D03*
X483662Y330117D03*
X491536Y341928D03*
X479725Y337991D03*
X487599D03*
X483662D03*
Y341928D03*
X487599D03*
X483662Y345865D03*
X487599Y349802D03*
X483662D03*
X487599Y345865D03*
X479725Y341928D03*
Y349802D03*
X487603Y369483D03*
X483662Y357676D03*
X487599D03*
X483663Y365463D03*
X483662Y361613D03*
Y353739D03*
X487599D03*
X483683Y369403D03*
X479725Y369487D03*
Y361613D03*
X487643Y361523D03*
X491500Y353500D03*
X491536Y369487D03*
Y361613D03*
X479725Y365550D03*
Y357676D03*
X491536Y385237D03*
Y377363D03*
X479725Y381300D03*
X491536D03*
X479725Y385237D03*
Y377363D03*
X491536Y400985D03*
Y393111D03*
X479725Y397048D03*
Y389174D03*
X491536Y397048D03*
Y389174D03*
X479725Y400985D03*
Y393111D03*
X491536Y416733D03*
Y408859D03*
X487599Y416733D03*
X483662Y408859D03*
X487599Y404922D03*
X479725Y412796D03*
X491536D03*
Y404922D03*
X483662Y412796D03*
Y404922D03*
X479725Y416733D03*
X491536Y420670D03*
Y424607D03*
X483662D03*
X487599D03*
Y420670D03*
X505678Y310921D03*
X506000Y317500D03*
X498855Y311100D03*
X498955Y316900D03*
X505523Y332086D03*
X499410Y322243D03*
X495473Y334054D03*
X511500Y348000D03*
X511455Y338700D03*
X495473Y341928D03*
X505523Y363582D03*
X507955Y356100D03*
X505523Y371456D03*
X503347Y381300D03*
X495473Y385237D03*
Y377363D03*
X503347Y397048D03*
Y389174D03*
X495473Y400985D03*
Y393111D03*
X499410Y416733D03*
Y412796D03*
Y408859D03*
X503347D03*
Y404922D03*
X495473Y416733D03*
Y412796D03*
Y408859D03*
X499410Y420670D03*
Y424607D03*
X503347Y420670D03*
X495473Y424607D03*
Y420670D03*
X513407Y311502D03*
X513500Y315800D03*
X522345Y311699D03*
X522365Y316365D03*
X521800Y322000D03*
X527667Y322182D03*
X523500Y347500D03*
Y352000D03*
Y342000D03*
X523100Y364300D03*
X526800Y359600D03*
X519500Y365500D03*
X523500Y357500D03*
X538875Y138000D03*
X533441Y211775D03*
X542000Y249000D03*
X528600Y316700D03*
X539300Y317600D03*
X534000Y317500D03*
X539200Y324100D03*
X530000Y342000D03*
X529400Y352800D03*
X530100Y347200D03*
X546500Y147500D03*
X559750Y264500D03*
X547500Y360168D03*
X568500Y147500D03*
X563250Y262500D03*
X579221Y237250D03*
X580828Y260028D03*
X604500Y205000D03*
Y200500D03*
X603500Y218500D03*
Y214000D03*
X605000Y209500D03*
X594500Y236000D03*
X604500Y227500D03*
Y223000D03*
X599000Y804000D03*
X622500Y696500D03*
X625000Y706000D03*
X632500Y530000D03*
X691400Y231100D03*
X710100Y182700D03*
X720500Y478750D03*
X723000Y996500D03*
X731498D03*
X739368Y996610D03*
X727558Y996500D03*
X756000Y180000D03*
X780000Y250000D03*
X862500Y65000D03*
X866112Y85626D03*
X865000Y488500D03*
X874000Y56000D03*
X873500Y61500D03*
X884500Y323500D03*
X881000Y736500D03*
X902000Y63000D03*
X935000Y51500D03*
X937000Y63000D03*
X945000Y141500D03*
X947500Y153000D03*
X959900Y180700D03*
X974500Y188500D03*
X975007Y194300D03*
X1002500Y653000D03*
X1001100Y776500D03*
X1015000Y477500D03*
X1011500Y667500D03*
X1022000Y492500D03*
X1022500Y637500D03*
X1027504Y853366D03*
X1045000Y266600D03*
X1041410Y695394D03*
Y690694D03*
Y699834D03*
X1055000Y214500D03*
X1055500Y360000D03*
X1062940Y629945D03*
X1065978Y664568D03*
X1063056Y681554D03*
X1062700Y672600D03*
X1054080Y680630D03*
X1061696Y761294D03*
X1061356Y753354D03*
X1084500Y223500D03*
X1074000Y660500D03*
X1074500Y665500D03*
X1102000Y250000D03*
X1102500Y264500D03*
X1089500Y405000D03*
X1088000Y461000D03*
X1088400Y647484D03*
X1103300Y492000D03*
X1113500Y614250D03*
X1113000Y630500D03*
X1105000D03*
X1114500Y645000D03*
X1118630Y714820D03*
X1110790Y738850D03*
X1116550Y783600D03*
X1119060Y791083D03*
X1132500Y333000D03*
X1126500Y614500D03*
X1132423Y663902D03*
X1135553Y663957D03*
X1132440Y676555D03*
X1129272Y673350D03*
X1129271Y670275D03*
X1126102Y676518D03*
X1122985Y670262D03*
X1122938Y676540D03*
X1132402Y673405D03*
X1132398Y667102D03*
X1129290Y676555D03*
X1126121Y679722D03*
X1132421Y679648D03*
X1132395Y670225D03*
X1126117Y685952D03*
X1129273Y689170D03*
X1126122Y689171D03*
X1129290Y692303D03*
X1126116Y692279D03*
X1132423Y695469D03*
X1132440Y692265D03*
Y686004D03*
X1132434Y682860D03*
X1129278Y682804D03*
X1119265Y683864D03*
X1135551Y685967D03*
X1129289Y686005D03*
X1126157Y695435D03*
X1129238Y704878D03*
X1132440Y701714D03*
X1129270D03*
X1126121Y711218D03*
X1129285Y708056D03*
X1126114Y701703D03*
X1126093Y704874D03*
X1132406Y704904D03*
X1132440Y698564D03*
X1129290D03*
X1126155Y708029D03*
X1132445Y714345D03*
X1129260Y714350D03*
X1135570Y711218D03*
X1126121Y714368D03*
X1132417Y711189D03*
X1129277Y711210D03*
X1128959Y729952D03*
X1126969Y727981D03*
X1132398Y720624D03*
X1132459Y717481D03*
X1127183Y740805D03*
X1126671Y744629D03*
X1126885Y736721D03*
X1123393Y743726D03*
X1124497Y734140D03*
X1124326Y738960D03*
X1126955Y731909D03*
X1124978Y747578D03*
X1130900Y766700D03*
X1124460Y768140D03*
X1125900Y764200D03*
X1129501Y776929D03*
X1134245Y769145D03*
X1127945Y769970D03*
X1121215Y769936D03*
X1120400Y781600D03*
X1126360Y792640D03*
X1127160Y788837D03*
X1129497Y792673D03*
X1130610Y788820D03*
X1134145Y788450D03*
X1132684Y792636D03*
X1124360Y788390D03*
X1132600Y784822D03*
X1120529Y786350D03*
X1123254Y792663D03*
X1131095Y799965D03*
X1124796Y800150D03*
X1135000Y810000D03*
X1134244Y799984D03*
X1121000Y808500D03*
X1127945Y799935D03*
X1121646Y799924D03*
X1123500Y832470D03*
X1135500Y835000D03*
X1144425Y325500D03*
X1143000Y629000D03*
X1138757Y663937D03*
X1151337Y660807D03*
X1151354Y663936D03*
X1148150Y663956D03*
X1141900Y663944D03*
X1148188Y667106D03*
Y670256D03*
X1151282Y667088D03*
X1141600Y673590D03*
X1141868Y680064D03*
X1151337Y670256D03*
X1141954Y676581D03*
X1135589Y673368D03*
X1144983Y667085D03*
X1145020Y670200D03*
X1136150Y676500D03*
X1135685Y679613D03*
X1135598Y667080D03*
X1135595Y670225D03*
X1141868Y670273D03*
X1138708Y667113D03*
X1139245Y675106D03*
X1135589Y682854D03*
Y695415D03*
X1151300Y682854D03*
Y692303D03*
Y689153D03*
Y686004D03*
Y695452D03*
X1148150D03*
Y692303D03*
Y689153D03*
Y686004D03*
Y682854D03*
X1139858Y692074D03*
X1139000Y685667D03*
X1144880Y707720D03*
X1145000Y711200D03*
X1138729Y714360D03*
X1151307Y714306D03*
X1141765Y711030D03*
X1145053Y714327D03*
X1148169Y711219D03*
X1141840Y714339D03*
X1138320Y710066D03*
X1151300Y698602D03*
X1148150D03*
X1135589Y701714D03*
X1151352Y711178D03*
X1140710Y707750D03*
X1138400Y705300D03*
X1136304Y707482D03*
X1151318Y717518D03*
X1148135Y720634D03*
X1138685Y720633D03*
X1141870Y717518D03*
X1148167Y717517D03*
X1138730Y717480D03*
X1141904Y720633D03*
X1150734Y736950D03*
X1149470Y734451D03*
X1137030Y745300D03*
X1146370Y769310D03*
X1142095Y773774D03*
X1151564Y776924D03*
X1146200Y766300D03*
X1142323Y780250D03*
X1138961Y776940D03*
X1145265Y776945D03*
X1151592Y773748D03*
X1150310Y783840D03*
X1142120Y795830D03*
X1145270D03*
X1138970D03*
X1145270Y792670D03*
X1141700Y785113D03*
X1138545Y787952D03*
X1145740Y789140D03*
X1138931Y792658D03*
X1142086Y789513D03*
X1136236Y782142D03*
X1151590Y792660D03*
X1143470Y782805D03*
X1140650Y782496D03*
X1151565Y787951D03*
X1142110Y792660D03*
X1149400Y800000D03*
X1142010Y809500D03*
X1141100Y831600D03*
X1159100Y640800D03*
X1157599Y663956D03*
X1167098Y663932D03*
X1160748Y660807D03*
Y657657D03*
X1160741Y663949D03*
X1163946Y663946D03*
X1157613Y673418D03*
X1167692Y674996D03*
X1160768Y676535D03*
X1154470Y673363D03*
X1152090Y677010D03*
X1154218Y679964D03*
X1154496Y667096D03*
X1163917Y670275D03*
X1160741Y667099D03*
X1163914Y673352D03*
X1167034Y667092D03*
X1157655Y667087D03*
X1160770Y673421D03*
X1163944Y667076D03*
X1154487Y670256D03*
X1160748Y682854D03*
X1157599Y686004D03*
X1154449D03*
Y682854D03*
Y689153D03*
X1160748Y695452D03*
X1157599D03*
Y692303D03*
X1154449Y695452D03*
Y692303D03*
X1163898Y695452D03*
X1160748Y692303D03*
X1163898D03*
X1157599Y689153D03*
X1160748D03*
X1163898D03*
X1160748Y686004D03*
X1163898D03*
X1157670Y707960D03*
X1167048Y714312D03*
X1163968Y708000D03*
X1154434Y714335D03*
X1157581Y714331D03*
X1163905Y711206D03*
X1157636Y711200D03*
X1163898Y698602D03*
X1160748D03*
X1157599D03*
X1154449D03*
X1167103Y711107D03*
X1167000Y727500D03*
X1157637Y717463D03*
X1157643Y720642D03*
X1152248Y730404D03*
X1154430Y717481D03*
X1152400Y727600D03*
X1167049Y717501D03*
X1167048Y720612D03*
X1163898Y717462D03*
Y720612D03*
X1157112Y731702D03*
X1164200Y744500D03*
X1157000Y734500D03*
X1166100Y731500D03*
X1152023Y733299D03*
X1163830Y747899D03*
X1158100Y769700D03*
X1162450Y769190D03*
X1167002Y767508D03*
X1167326Y776936D03*
X1167320Y770290D03*
X1157871Y773728D03*
X1161051Y792660D03*
X1164196Y795814D03*
X1153219Y781303D03*
X1161545Y788844D03*
X1162693Y780865D03*
X1158092Y787715D03*
X1154712Y792690D03*
X1165492Y780957D03*
X1154200Y788900D03*
X1154700Y795790D03*
X1161022Y785693D03*
X1165063Y787500D03*
X1167410Y785530D03*
X1167330Y795830D03*
X1163605Y783513D03*
X1167277Y792658D03*
X1157866Y795844D03*
X1154800Y799000D03*
X1165300Y809610D03*
X1160300D03*
X1154300D03*
X1155390Y818000D03*
X1157990Y827000D03*
X1173332Y663938D03*
X1176506Y663916D03*
X1176525Y679676D03*
X1170181Y670240D03*
X1176503Y670218D03*
X1182803Y670234D03*
X1176534Y673368D03*
X1179653Y670234D03*
X1173309Y673406D03*
X1179662Y673421D03*
X1176534Y676555D03*
X1179667Y679655D03*
X1182831Y679666D03*
X1182815Y676573D03*
X1170192Y667100D03*
X1176526Y667092D03*
X1173403Y670237D03*
X1173349Y667099D03*
X1182785Y685977D03*
X1176520Y685970D03*
X1179663Y685959D03*
X1173365Y695397D03*
X1169800Y682200D03*
X1173392Y685974D03*
X1173389Y689121D03*
X1176482Y682840D03*
X1176529Y692276D03*
X1179685Y692292D03*
X1176496Y695415D03*
X1179664Y695466D03*
X1182796Y695415D03*
X1179678Y689111D03*
X1182817Y689155D03*
X1173384Y692265D03*
X1182815Y701696D03*
X1182796Y708013D03*
X1182813Y698619D03*
X1176496Y698564D03*
X1179671Y698565D03*
X1170248Y714330D03*
X1173350Y698590D03*
X1179703Y714331D03*
X1173347Y714350D03*
X1176503Y714342D03*
X1176515Y704845D03*
X1179676Y711207D03*
X1179660Y704850D03*
X1171200Y706170D03*
X1179660Y708050D03*
X1176515Y708045D03*
X1173015Y708329D03*
X1176515Y711144D03*
X1173262Y711119D03*
X1182802Y714356D03*
X1169282Y729708D03*
X1173400Y717480D03*
X1176499Y720609D03*
X1170199Y717501D03*
X1173348Y720613D03*
X1176489Y717469D03*
X1171500Y733725D03*
X1175000Y734870D03*
X1171108Y777368D03*
X1170950Y795960D03*
X1170911Y784912D03*
X1170718Y782118D03*
X1170300Y809610D03*
X1185965Y676573D03*
X1190500Y674207D03*
X1185945Y695415D03*
X1190000Y699500D03*
X1196000Y710500D03*
X1190000Y705500D03*
X1201250Y627000D03*
X1203500Y698520D03*
X1218040Y719850D03*
X1249773Y551500D03*
X1249000Y723250D03*
X1258562Y672438D03*
X1259000Y699500D03*
X1257500Y710500D03*
X1259500Y724000D03*
X1279600Y694800D03*
X1276000Y694000D03*
X1272700Y694900D03*
X1277000Y712500D03*
X1272500D03*
X1275000Y732000D03*
X1287962Y710490D03*
X1289500Y716500D03*
X1292500Y730478D03*
X1305000Y596500D03*
X1306423Y608164D03*
X1305217Y612412D03*
X1305435Y603918D03*
X1306443Y618985D03*
X1307150Y691500D03*
X1307000Y729100D03*
X1310500Y737500D03*
X1307000Y732500D03*
X1300491Y732991D03*
X1319400Y522100D03*
X1318700Y533500D03*
X1322900Y524600D03*
X1322400Y533100D03*
X1318000Y696500D03*
X1319000Y708000D03*
X1354900Y522600D03*
X1351900Y524600D03*
X1352400Y533600D03*
X1355900Y536600D03*
X1381415Y581195D03*
X1379600Y584200D03*
X1378800Y594900D03*
X1380925Y598315D03*
X1377800Y603800D03*
X1378082Y614266D03*
X1381637Y611225D03*
X1381578Y607117D03*
X1377996Y610847D03*
X1380925Y602035D03*
X1377996Y607382D03*
X1385135Y581195D03*
X1387200Y584100D03*
X1384400Y598300D03*
Y601900D03*
G54D80*
G01X68522Y822004D02*
X73772D01*
G01X224000Y875000D02*
X222500Y876500D01*
Y883243D01*
X226000Y886743D01*
Y919500D01*
X225000Y920500D01*
G01X232000Y921000D02*
X229000Y918000D01*
Y885500D01*
X225500Y882000D01*
Y879500D01*
G01X399309Y215180D02*
X398109Y216380D01*
Y216762D01*
X393929Y220942D01*
Y221250D01*
G01X477291Y147500D02*
X474291Y144500D01*
X474250D01*
G01D02*
Y144250D01*
X477750Y140750D01*
Y140000D01*
G01X1138968Y695784D02*
X1137027D01*
X1136743Y695500D01*
X1136216D01*
X1136131Y695415D01*
X1135589D01*
G54D71*
X1350084Y281318D03*
G54D17*
X48700Y872500D03*
Y868500D03*
X340740Y193000D03*
X340629Y189000D03*
X340740Y197500D03*
X346700Y396000D03*
X362210Y179910D03*
X416700Y225000D03*
X441129Y113500D03*
X451629Y175500D03*
X470855Y308700D03*
X479700Y186231D03*
X479723Y334283D03*
X491478Y844000D03*
Y836000D03*
Y840000D03*
Y848500D03*
X527629Y124500D03*
X534700Y148500D03*
X780200Y973000D03*
X1039200Y141000D03*
X1081200Y667500D03*
Y679500D03*
Y675500D03*
Y671500D03*
Y683500D03*
X1069568Y681554D03*
X1081200Y695500D03*
Y687500D03*
Y691500D03*
Y699500D03*
Y711500D03*
Y707500D03*
Y703500D03*
Y723500D03*
Y719500D03*
Y715500D03*
Y727500D03*
X1082200Y736500D03*
X1089700Y630000D03*
X1091200Y655000D03*
X1091188Y650584D03*
X1171900Y679300D03*
X1225700Y727000D03*
Y718500D03*
Y735500D03*
Y731000D03*
X1261200Y651000D03*
Y657000D03*
Y661000D03*
X1253700Y671000D03*
X1261200Y667500D03*
X1253700Y687500D03*
Y683500D03*
G54D53*
X439029Y100000D03*
Y108000D03*
X447829Y104000D03*
X494329Y149500D03*
X485529Y145500D03*
Y153500D03*
G54D44*
X323060Y285250D03*
X317940D03*
Y291750D03*
X320500D03*
X323060D03*
G54D62*
X641625Y458750D03*
X654875Y434750D03*
X647125D03*
X651000Y442250D03*
X645500Y466250D03*
X649375Y458750D03*
G54D26*
X114174Y1009860D03*
X110234D03*
X133859D03*
X129919D03*
X125984D03*
X122049D03*
X118109D03*
X149604D03*
X145669D03*
X165354D03*
X161419D03*
X157479D03*
X153544D03*
X181104D03*
X177164D03*
X173229D03*
X169289D03*
X279528D03*
X275588D03*
X271653D03*
X267718D03*
X295273D03*
X291338D03*
X287403D03*
X283463D03*
X311023D03*
X307088D03*
X303148D03*
X299213D03*
X330708D03*
X326773D03*
X322833D03*
X318898D03*
X314958D03*
X346458D03*
X342518D03*
X338583D03*
X334643D03*
X362203D03*
X358268D03*
X354333D03*
X350393D03*
X377953D03*
X374018D03*
X370078D03*
X366143D03*
X393703D03*
X389763D03*
X385828D03*
X381888D03*
X409448D03*
X405513D03*
X401573D03*
X397638D03*
X429133D03*
X425198D03*
X421258D03*
X417323D03*
X413388D03*
X444883D03*
X440943D03*
X437008D03*
X433073D03*
X460628D03*
X456693D03*
X452758D03*
X448818D03*
X476378D03*
X472443D03*
X468503D03*
X464568D03*
X492128D03*
X488188D03*
X484253D03*
X480313D03*
X507873D03*
X503938D03*
X499998D03*
X496063D03*
X527558D03*
X523623D03*
X519683D03*
X515748D03*
X511813D03*
X543308D03*
X539368D03*
X535433D03*
X531498D03*
X559053D03*
X555118D03*
X574803D03*
X570868D03*
X566928D03*
X562993D03*
X590553D03*
X586613D03*
X582678D03*
X578738D03*
X723623D03*
X719683D03*
X739368D03*
X735433D03*
X731498D03*
X727558D03*
X755118D03*
X743308D03*
X770868D03*
X766928D03*
X762993D03*
X759053D03*
X790553D03*
X786613D03*
X782678D03*
X778738D03*
X774803D03*
G54D35*
X314500Y71200D03*
X307500Y288700D03*
X319500Y71200D03*
X332500Y68700D03*
X1031500Y63700D03*
X1036500D03*
X1041500D03*
X1046500D03*
X1051500D03*
X1124800Y804200D03*
X1131300D03*
X1142000Y799700D03*
X1212500Y197700D03*
X1204390Y703400D03*
G54D90*
G01X816734Y298230D02*
G02X817486Y291808I-27046J-6422D01*
G01X817461Y291783D01*
Y288145D01*
G02X816333Y285422I-3850J0D01*
G01X789188Y258277D01*
G02X786465Y257149I-2723J2722D01*
G01X779389D01*
G03X777621Y256417I0J-2500D01*
G01X624782Y103578D01*
G02X622059Y102450I-2723J2722D01*
G01X601864D01*
G03X600096Y101718I0J-2500D01*
G01X518006Y19628D01*
G02X515283Y18500I-2723J2722D01*
G01X459185D01*
G02X456462Y19628I0J3850D01*
G01X440824Y35266D01*
G03X439056Y35998I-1768J-1768D01*
G01X412115D01*
G02X409392Y37126I0J3850D01*
G01X365285Y81233D01*
G03X363517Y81965I-1768J-1768D01*
G01X356720D01*
G02X353997Y83093I0J3850D01*
G01X344778Y92312D01*
G02X343650Y95035I2722J2723D01*
G01Y99500D01*
G03X343049Y100951I-2052J0D01*
G01X342000Y102000D01*
G01X812794Y290355D02*
X812106Y291044D01*
G02X811091Y293493I2449J2450D01*
G02X814021Y294754I2167J-1001D01*
G02X816111Y292201I-994J-2946D01*
G01Y288147D01*
G02X815379Y286379I-2500J0D01*
G01X788232Y259232D01*
G02X786464Y258500I-1768J1768D01*
G01X779389D01*
G03X776666Y257372I0J-3850D01*
G01X623826Y104532D01*
G02X622058Y103800I-1768J1768D01*
G01X601863D01*
G03X599140Y102672I0J-3850D01*
G01X517050Y20582D01*
G02X515282Y19850I-1768J1768D01*
G01X459186D01*
G02X457418Y20582I0J2500D01*
G01X441780Y36220D01*
G03X439057Y37348I-2723J-2722D01*
G01X412116D01*
G02X410348Y38080I0J2500D01*
G01X366241Y82187D01*
G03X363518Y83315I-2723J-2722D01*
G01X356721D01*
G02X354953Y84047I0J2500D01*
G01X345732Y93268D01*
G02X345000Y95036I1768J1768D01*
G01Y99586D01*
G02X346000Y102000I3414J0D01*
G01X373540Y123400D02*
G02X374151Y121925I-1475J-1475D01*
G01Y118438D01*
G02X372796Y115167I-4626J0D01*
G03X371990Y113222I1946J-1946D01*
G01Y95641D01*
G03X373118Y92918I3850J0D01*
G01X415110Y50926D01*
G03X417833Y49798I2723J2722D01*
G01X445256D01*
G02X447024Y49066I0J-2500D01*
G01X462262Y33828D01*
G03X464985Y32700I2723J2722D01*
G01X509965D01*
G03X512688Y33828I0J3850D01*
G01X594378Y115518D01*
G02X596146Y116250I1768J-1768D01*
G01X615673D01*
G03X618396Y117378I0J3850D01*
G01X784055Y283037D01*
G03X785903Y287500I-4463J4462D01*
G01Y296615D01*
G03X785234Y298230I-2284J0D01*
G01X376040Y123400D02*
G03X375501Y122099I1301J-1301D01*
G01Y118437D01*
G02X373751Y114212I-5976J0D01*
G03X373340Y113221I991J-992D01*
G01Y95642D01*
G03X374072Y93874I2500J0D01*
G01X416066Y51880D01*
G03X417834Y51148I1768J1768D01*
G01X445257D01*
G02X447980Y50020I0J-3850D01*
G01X463218Y34782D01*
G03X464986Y34050I1768J1768D01*
G01X509964D01*
G03X511732Y34782I0J2500D01*
G01X593422Y116472D01*
G02X596145Y117600I2723J-2722D01*
G01X615672D01*
G03X617440Y118332I0J2500D01*
G01X783100Y283992D01*
G03X784553Y287500I-3508J3508D01*
G01Y291675D01*
G03X784002Y293005I-1881J0D01*
G03X781005I-1499J-1498D01*
G01X780616Y292616D01*
G03Y291038I789J-789D01*
G01X781299Y290355D01*
G01X367540Y123400D02*
G02X368115Y122012I-1388J-1388D01*
G01Y117966D01*
G02X367704Y116975I-1402J1D01*
G01X365893Y115164D01*
G03X365087Y113218I1946J-1946D01*
G01Y92785D01*
G03X366215Y90062I3850J0D01*
G01X412251Y44026D01*
G03X414974Y42898I2723J2722D01*
G01X442397D01*
G02X444165Y42166I0J-2500D01*
G01X459703Y26628D01*
G03X462426Y25500I2723J2722D01*
G01X512524D01*
G03X515247Y26628I0J3850D01*
G01X597237Y108618D01*
G02X599005Y109350I1768J-1768D01*
G01X619202D01*
G03X621923Y110478I-2J3850D01*
G01X775277Y263832D01*
G02X780872Y266150I5596J-5595D01*
G01X781999D01*
G03X784662Y267252I2J3764D01*
G01X798816Y281406D01*
G03X801754Y288500I-7094J7093D01*
G01Y291987D01*
G03X800819Y294246I-3194J1D01*
G01X799417Y295648D01*
G02Y297808I1080J1080D01*
G02X800436Y298230I1019J-1019D01*
G01X800984D01*
G01X370040Y123400D02*
G03X369465Y122012I1388J-1388D01*
G01Y117965D01*
G02X368659Y116020I-2752J1D01*
G01X366848Y114209D01*
G03X366437Y113218I991J-992D01*
G01Y92786D01*
G03X367169Y91018I2500J0D01*
G01X413207Y44980D01*
G03X414975Y44248I1768J1768D01*
G01X442398D01*
G02X445121Y43120I0J-3850D01*
G01X460659Y27582D01*
G03X462427Y26850I1768J1768D01*
G01X512523D01*
G03X514291Y27582I0J2500D01*
G01X596281Y109572D01*
G02X599004Y110700I2723J-2722D01*
G01X619201D01*
G03X620968Y111433I-1J2500D01*
G01X774322Y264787D01*
G02X780872Y267500I6550J-6550D01*
G01X782000D01*
G03X783707Y268207I0J2414D01*
G01X797861Y282361D01*
G03X800404Y288500I-6139J6139D01*
G01Y291987D01*
G03X799864Y293291I-1844J0D01*
G01X799050Y294105D01*
G03X798478Y294424I-848J-848D01*
G01X797348D01*
G03X795849Y293803I0J-2120D01*
G03Y291555I1124J-1124D01*
G01X797049Y290355D01*
G01X379540Y123400D02*
X380083Y122857D01*
G02X380229Y122504I-354J-353D01*
G01Y117500D01*
G02X380037Y117038I-654J1D01*
G01X379500Y116500D01*
G03X378890Y115027I1473J-1473D01*
G01Y98500D01*
G03X380018Y95777I3850J0D01*
G01X417969Y57826D01*
G03X420692Y56698I2723J2722D01*
G01X448766D01*
G02X450534Y55966I0J-2500D01*
G01X465772Y40728D01*
G03X468495Y39600I2723J2722D01*
G01X506965D01*
G03X509688Y40728I0J3850D01*
G01X591378Y122418D01*
G02X593146Y123150I1768J-1768D01*
G01X611356D01*
G03X614079Y124278I0J3850D01*
G01X769015Y279214D01*
G03X770143Y281937I-2722J2723D01*
G01Y292948D01*
G03X769500Y294500I-2195J0D01*
G01X769489Y294511D01*
G02Y298230I1860J1859D01*
G01X370040Y125600D02*
Y125607D01*
G02X371206Y128422I3981J0D01*
G01X376656Y133872D01*
G01X367540Y125600D02*
G02X368294Y127420I2574J0D01*
G01X375756Y134882D01*
G01X376040Y125600D02*
Y127848D01*
G02X376626Y129263I2001J0D01*
G01X378896Y131533D01*
G01X373540Y125600D02*
G02X375299Y129848I6007J1D01*
G01X375841Y130389D01*
X376067Y130615D01*
X377520Y132067D01*
G01X382040Y123400D02*
G03X381579Y122287I1113J-1113D01*
G01Y117499D01*
G02X380992Y116083I-2004J1D01*
G01X380456Y115545D01*
X380455D01*
G03X380241Y115027I518J-517D01*
G01X380240Y115028D01*
Y98501D01*
G03X380972Y96733I2500J0D01*
G01X418925Y58780D01*
G03X420693Y58048I1768J1768D01*
G01X448767D01*
G02X451490Y56920I0J-3850D01*
G01X466728Y41682D01*
G03X468496Y40950I1768J1768D01*
G01X506964D01*
G03X508732Y41682I0J2500D01*
G01X590422Y123372D01*
G02X593145Y124500I2723J-2722D01*
G01X611355D01*
G03X613123Y125232I0J2500D01*
G01X768061Y280170D01*
G03X768793Y281938I-1768J1768D01*
G01Y291086D01*
G03X768001Y292999I-2706J0D01*
G01X768000Y293000D01*
G03X765000I-1500J-1500D01*
G03Y290904I1048J-1048D01*
G01X765549Y290355D01*
G01X394040Y123400D02*
Y104219D01*
G03X394772Y102451I2500J0D01*
G01X424643Y72580D01*
G03X426411Y71848I1768J1768D01*
G01X457557D01*
G02X460280Y70720I0J-3850D01*
G01X475418Y55582D01*
G03X477186Y54850I1768J1768D01*
G01X501073D01*
G03X502841Y55582I0J2500D01*
G01X584431Y137172D01*
G02X587154Y138300I2723J-2722D01*
G01X605637D01*
G03X607405Y139032I0J2500D01*
G01X673506Y205133D01*
G03X674238Y206901I-1768J1768D01*
G01Y292000D01*
G03X673699Y293301I-1840J0D01*
G01X673309Y293691D01*
G03X671191I-1059J-1059D01*
G01X670802Y293302D01*
G03Y290617I1342J-1343D01*
G01X671064Y290355D01*
G01X391540Y123400D02*
X392160Y122781D01*
G02X392690Y121500I-1281J-1280D01*
G01Y104218D01*
G03X393818Y101495I3850J0D01*
G01X423687Y71626D01*
G03X426410Y70498I2723J2722D01*
G01X457556D01*
G02X459324Y69766I0J-2500D01*
G01X474462Y54628D01*
G03X477185Y53500I2723J2722D01*
G01X501074D01*
G03X503797Y54628I0J3850D01*
G01X585387Y136218D01*
G02X587155Y136950I1768J-1768D01*
G01X605638D01*
G03X608361Y138078I0J3850D01*
G01X674460Y204177D01*
G03X675588Y206900I-2722J2723D01*
G01Y292000D01*
G03X674736Y294171I-3190J1D01*
G02X674808Y298039I2043J1897D01*
G01X674999Y298230D01*
G01X385540Y123400D02*
X385644Y123296D01*
G02X385790Y122943I-354J-353D01*
G01Y101359D01*
G03X386918Y98636I3850J0D01*
G01X420828Y64726D01*
G03X423551Y63598I2723J2722D01*
G01X454456D01*
G02X456224Y62866I0J-2500D01*
G01X471462Y47628D01*
G03X474185Y46500I2723J2722D01*
G01X503833D01*
G03X506556Y47628I0J3850D01*
G01X588246Y129318D01*
G02X590014Y130050I1768J-1768D01*
G01X608497D01*
G03X611220Y131178I0J3850D01*
G01X753407Y273365D01*
G03X754535Y276088I-2722J2723D01*
G01Y293000D01*
G03X753853Y294648I-2330J1D01*
G01X753463Y295037D01*
G02Y297954I1459J1458D01*
G01X753739Y298230D01*
G01X388040Y123400D02*
G03X387140Y121227I2173J-2173D01*
G01Y101360D01*
G03X387872Y99592I2500J0D01*
G01X421784Y65680D01*
G03X423552Y64948I1768J1768D01*
G01X454457D01*
G02X457180Y63820I0J-3850D01*
G01X472418Y48582D01*
G03X474186Y47850I1768J1768D01*
G01X503832D01*
G03X505600Y48582I0J2500D01*
G01X587290Y130272D01*
G02X590013Y131400I2723J-2722D01*
G01X608496D01*
G03X610264Y132132I0J2500D01*
G01X752453Y274321D01*
G03X753185Y276089I-1768J1768D01*
G01Y290733D01*
G03X752420Y292580I-2612J0D01*
G01X752000Y293000D01*
G03X749500I-1250J-1250D01*
G03Y290659I1171J-1171D01*
G01X749804Y290355D01*
G01X388040Y125600D02*
X387621Y126019D01*
G02X387279Y126845I826J826D01*
G01Y135177D01*
G02X387482Y135667I693J0D01*
G01X388523Y136708D01*
Y137203D01*
X388780Y137460D01*
G01X385540Y125600D02*
G03X385929Y126539I-939J939D01*
G01Y135177D01*
G02X386527Y136622I2043J1D01*
G01X387173Y137268D01*
Y139376D01*
G01X382040Y125600D02*
G02X381929Y125868I268J268D01*
G01Y130383D01*
G02X382075Y130736I500J0D01*
G01X383473Y132134D01*
G03X384279Y134080I-1946J1946D01*
G01Y135494D01*
G02X384287Y135679I2112J1D01*
G01Y135680D01*
G02X384356Y136060I2104J-186D01*
G02X384465Y136361I2035J-567D01*
G02X384515Y136465I1928J-863D01*
G02X384540Y136513I1886J-952D01*
G02X384558Y136544I1836J-1045D01*
G02X384573Y136569I1819J-1074D01*
G02X384664Y136710I1819J-1074D01*
G02X384665Y136712I1890J-944D01*
G02X384701Y136762I1732J-1209D01*
G02X384713Y136777I1655J-1312D01*
G02X384855Y136944I1678J-1283D01*
G02X384898Y136988I1532J-1454D01*
G01X385219Y137309D01*
G01X394040Y125600D02*
Y126115D01*
G02X394327Y126808I980J0D01*
G01X394676Y127157D01*
G03X395265Y128578I-1420J1421D01*
G01Y130200D01*
G02X395108Y130579I379J379D01*
G01Y138000D01*
G01X391540Y125600D02*
X392566Y126626D01*
G03X392899Y127124I-1087J1087D01*
G02X393233Y127624I1420J-587D01*
G01X393721Y128112D01*
G03X393915Y128578I-464J467D01*
G01Y129694D01*
X393904Y129705D01*
G02X393758Y130058I354J353D01*
G01Y138741D01*
G03X393510Y139340I-847J0D01*
G01X379540Y125600D02*
G03X380579Y128108I-2508J2508D01*
G01Y130383D01*
G02X381119Y131691I1850J2D01*
G01X382518Y133089D01*
G03X382929Y134080I-991J992D01*
G01Y137400D01*
G02X383552Y138904I2127J0D01*
G01X384019Y139371D01*
G01X406040Y123400D02*
G03X405390Y121831I1569J-1569D01*
G01Y117846D01*
G03X406122Y116079I2499J0D01*
G01X406312Y115889D01*
G02X407840Y112201I-3689J-3689D01*
G01Y110358D01*
G03X408870Y107871I3517J0D01*
G01X430359Y86382D01*
G03X432127Y85650I1768J1768D01*
G01X469850D01*
G03X470840Y86061I-2J1402D01*
G01X480389Y95610D01*
G02X488694Y99050I8305J-8306D01*
G01X524200D01*
G03X525652Y99652I-1J2054D01*
G01X581972Y155972D01*
G02X584695Y157100I2723J-2722D01*
G01X603769D01*
G03X605537Y157832I0J2500D01*
G01X641602Y193897D01*
G03X642832Y196868I-2972J2970D01*
G01X642833Y196867D01*
Y292627D01*
G03X641460Y294000I-1373J0D01*
G01X641000D01*
G03X640147Y293646I1J-1207D01*
G01X639500Y293000D01*
G03Y290424I1288J-1288D01*
G01X639569Y290355D01*
G01X403540Y123400D02*
X403822Y123118D01*
X404001Y122693D01*
G02X404010Y122668I-465J-182D01*
G02X404040Y122499I-470J-171D01*
G01Y117845D01*
G03X405167Y115124I3849J0D01*
G01X405357Y114934D01*
G02X406490Y112200I-2734J-2735D01*
G01Y110358D01*
G03X407915Y106916I4867J-1D01*
G01X429403Y85428D01*
G03X432126Y84300I2723J2722D01*
G01X469850D01*
G03X471795Y85106I-1J2752D01*
G01X481344Y94655D01*
G02X488695Y97700I7351J-7351D01*
G01X524200D01*
G03X526607Y98697I0J3404D01*
G01X582928Y155018D01*
G02X584696Y155750I1768J-1768D01*
G01X603770D01*
G03X606493Y156878I0J3850D01*
G01X642557Y192942D01*
G03X644183Y196868I-3926J3926D01*
G01Y292627D01*
G03X643325Y294612I-2723J1D01*
G02X643273Y297999I1616J1719D01*
G01X643504Y298230D01*
G01X400040Y123467D02*
X399752Y123179D01*
G03X399540Y122668I510J-511D01*
G01Y116302D01*
G03X399796Y115684I874J0D01*
G01X400304Y115176D01*
G02X400940Y113641I-1535J-1535D01*
G01Y107078D01*
G03X401672Y105310I2500J0D01*
G01X427502Y79480D01*
G03X429270Y78748I1768J1768D01*
G01X464157D01*
G02X466880Y77620I0J-3850D01*
G01X481918Y62582D01*
G03X483686Y61850I1768J1768D01*
G01X498314D01*
G03X500082Y62582I0J2500D01*
G01X581572Y144072D01*
G02X584295Y145200I2723J-2722D01*
G01X602005D01*
G03X603773Y145932I0J2500D01*
G01X656920Y199079D01*
G03X658626Y203197I-4117J4118D01*
G01Y291989D01*
G03X658000Y293500I-2137J0D01*
G03X655500I-1250J-1250D01*
G01X655000Y293000D01*
G03Y290669I1166J-1166D01*
G01X655314Y290355D01*
G01X397540Y123467D02*
X397903Y123104D01*
G02X398190Y122412I-691J-692D01*
G01Y116302D01*
G03X398841Y114729I2224J-1D01*
G01X399349Y114221D01*
G02X399590Y113640I-580J-581D01*
G01Y107077D01*
G03X400718Y104354I3850J0D01*
G01X426546Y78526D01*
G03X429269Y77398I2723J2722D01*
G01X464156D01*
G02X465924Y76666I0J-2500D01*
G01X480962Y61628D01*
G03X483685Y60500I2723J2722D01*
G01X498315D01*
G03X501038Y61628I0J3850D01*
G01X582528Y143118D01*
G02X584296Y143850I1768J-1768D01*
G01X602006D01*
G03X604729Y144978I0J3850D01*
G01X657875Y198124D01*
G03X659976Y203196I-5072J5072D01*
G01Y296487D01*
G03X659254Y298230I-2465J0D01*
G01X409540Y123400D02*
G02X410505Y121812I-2777J-2775D01*
G02X410690Y120624I-3741J-1191D01*
G01Y117641D01*
G03X411496Y115695I2752J0D01*
G01X412979Y114212D01*
G02X413390Y113221I-991J-992D01*
G01Y112480D01*
G03X414295Y110295I3091J0D01*
G01X432262Y92328D01*
G03X434985Y91200I2723J2722D01*
G01X466444D01*
G03X469167Y92328I0J3850D01*
G01X479028Y102189D01*
G02X486901Y105450I7873J-7873D01*
G01X515300D01*
G03X528278Y110825I1J18354D01*
G01X579371Y161918D01*
G02X581139Y162650I1768J-1768D01*
G01X600909D01*
G03X603633Y163777I2J3850D01*
G01X627428Y187572D01*
G03X628415Y189955I-2384J2383D01*
G01Y292277D01*
G03X627440Y294523I-3073J1D01*
G02X627384Y297860I1585J1696D01*
G01X627754Y298230D01*
G01X412040Y123400D02*
Y117641D01*
G03X412451Y116650I1402J1D01*
G01X413934Y115167D01*
G02X414740Y113222I-1946J-1946D01*
G01Y112481D01*
G03X415250Y111250I1741J0D01*
G01X433218Y93282D01*
G03X434986Y92550I1768J1768D01*
G01X466443D01*
G03X468211Y93282I0J2500D01*
G01X478073Y103144D01*
G02X486900Y106800I8827J-8828D01*
G01X515300D01*
G03X527323Y111780I0J17003D01*
G01X578415Y162872D01*
G02X581138Y164000I2723J-2722D01*
G01X600910D01*
G03X602678Y164732I0J2500D01*
G01X626473Y188527D01*
G03X627065Y189956I-1429J1429D01*
G01Y292277D01*
G03X625342Y294000I-1723J0D01*
G01X625000D01*
G03X624147Y293646I1J-1207D01*
G01X623500Y293000D01*
G03Y290674I1163J-1163D01*
G01X623819Y290355D01*
G01X406040Y125600D02*
G02X405975Y125757I157J157D01*
G01Y134058D01*
G03X405778Y134534I-673J0D01*
G01X405129Y135183D01*
G01X403540Y125600D02*
G03X404625Y128219I-2619J2619D01*
G01Y133605D01*
G03X404624Y133623I-335J-10D01*
G03X404527Y133842I-335J-17D01*
G01X404428Y133941D01*
Y133974D01*
X403652Y134750D01*
G02X402953Y136437I1686J1687D01*
G01Y139370D01*
G01X412040Y125600D02*
G02X411390Y127169I1569J1569D01*
G01Y132800D01*
G03X410224Y135615I-3981J0D01*
G01X408015Y137824D01*
X407958Y137961D01*
G01X409540Y125600D02*
G03X410040Y126807I-1207J1207D01*
G01Y132801D01*
G03X409269Y134660I-2631J-2D01*
G01X406871Y137058D01*
X406729Y137399D01*
X406728Y137401D01*
X406474Y137655D01*
G02X406328Y138008I354J353D01*
G01Y138939D01*
G03X406319Y139026I-499J-8D01*
G03X406313Y139050I-486J-109D01*
G03X406299Y139103I-488J-101D01*
G03X406182Y139291I-472J-163D01*
G01X406143Y139329D01*
X406103Y139371D01*
G01X400040Y125667D02*
G02X399890Y126007I362J363D01*
G02Y126029I512J11D01*
G01Y130120D01*
G03X399084Y132066I-2752J0D01*
G01X398416Y132734D01*
G02X398005Y133725I991J992D01*
G01Y137965D01*
G03X398260Y138220I0J255D01*
G01X397540Y125667D02*
G03X398540Y128081I-2414J2414D01*
G01Y130120D01*
G03X398129Y131111I-1402J-1D01*
G01X397461Y131779D01*
G02X396655Y133724I1946J1946D01*
G01Y137094D01*
G03X396607Y137306I-499J-2D01*
G03X396606Y137308I-447J-222D01*
G03X396507Y137449I-452J-212D01*
G01X396175Y137781D01*
Y138854D01*
X396683Y139362D01*
G01X607933Y70118D02*
Y70079D01*
X610730Y67282D01*
G02X611215Y66111I-1171J-1171D01*
G01Y63700D01*
G03X614765Y60150I3550J0D01*
G01X639748D01*
Y60149D01*
G03X643421Y61672I0J5190D01*
G01X643504Y61756D01*
X648586Y66837D01*
X650140Y68391D01*
G03X650179Y68430I-1635J1674D01*
G01X669848Y88100D01*
G02X672021Y89000I2173J-2173D01*
G01X684125D01*
G03X687748Y90500I1J5123D01*
G01X694348Y97100D01*
G03X695748Y100480I-3381J3380D01*
G01Y119020D01*
G03X694348Y122400I-4781J0D01*
G01X686248Y130500D01*
G02X685898Y131345I845J845D01*
G01Y133380D01*
G01X603897Y80118D02*
X605766D01*
X607082Y80918D01*
Y85082D01*
X611500Y89500D01*
X611590D01*
X612440Y90350D01*
X643440D01*
X662090Y109000D01*
X687403D01*
G02X689698Y108050I1J-3245D01*
G02X690748Y105515I-2536J-2535D01*
G01Y103061D01*
G02X689998Y101250I-2562J0D01*
G02X687847Y100359I-2152J2152D01*
G01X676833D01*
G03X674469Y99380I0J-3343D01*
G01X611889Y80118D02*
X610148D01*
X608598Y81668D01*
Y84598D01*
X613000Y89000D01*
X644000D01*
X662650Y107650D01*
X667427D01*
G02X668233Y107316I0J-1140D01*
G02X668283Y107255I-740J-658D01*
G03X669073Y106860I791J595D01*
G01X670723D01*
G03X671513Y107255I-1J990D01*
G02X671563Y107316I790J-596D01*
G02X672303Y107650I741J-656D01*
G01X677076D01*
G02X677866Y107255I-1J-990D01*
G03X678656Y106860I791J595D01*
G01X680306D01*
G03X681096Y107255I-1J990D01*
G02X681886Y107650I791J-595D01*
G01X687403D01*
G02X688743Y107095I0J-1895D01*
G02X689398Y105514I-1581J-1581D01*
G01Y103062D01*
G02X689043Y102205I-1212J0D01*
G02X687846Y101709I-1197J1197D01*
G01X674948D01*
G02X674358Y102299I0J590D01*
G01Y103170D01*
G01X615925Y70118D02*
X615886D01*
X613058Y67290D01*
G03X612565Y66100I1190J-1190D01*
G01Y63700D01*
G03X614765Y61500I2200J0D01*
G01X621310D01*
G03X622100Y61895I-1J990D01*
G02X622890Y62290I791J-595D01*
G01X624540D01*
G02X625330Y61895I-1J-990D01*
G03X626120Y61500I791J595D01*
G01X627770D01*
G03X628560Y61895I-1J990D01*
G02X629350Y62290I791J-595D01*
G01X631000D01*
G02X631790Y61895I-1J-990D01*
G03X632580Y61500I791J595D01*
G01X639748D01*
G03X642463Y62624I1J3839D01*
G01X642543Y62705D01*
X644616Y64778D01*
G03X644895Y65616I-701J699D01*
G02X645175Y66454I980J138D01*
G01X646341Y67621D01*
G02X647179Y67900I699J-701D01*
G01X647500D01*
X647857Y68019D01*
X649184Y69346D01*
G03X649463Y70184I-701J699D01*
G02X649743Y71022I980J138D01*
G01X650909Y72188D01*
G02X651747Y72468I700J-700D01*
G03X652585Y72747I139J980D01*
G01X653752Y73914D01*
G03X654031Y74752I-701J699D01*
G02X654310Y75590I981J139D01*
G01X655477Y76756D01*
G02X656315Y77036I700J-700D01*
G03X657153Y77315I139J980D01*
G01X658320Y78482D01*
G03X658599Y79320I-701J699D01*
G02X658878Y80158I980J139D01*
G01X660045Y81324D01*
G02X660883Y81604I700J-700D01*
G03X661721Y81883I139J980D01*
G01X664129Y84291D01*
G03X664408Y85129I-701J699D01*
G02X664688Y85967I980J138D01*
G01X665854Y87134D01*
G02X666692Y87413I699J-701D01*
G03X667530Y87692I139J980D01*
G01X668893Y89055D01*
G02X672021Y90350I3127J-3128D01*
G01X676563D01*
G03X677353Y90745I-1J990D01*
G02X678143Y91140I791J-595D01*
G01X679793D01*
G02X680583Y90745I-1J-990D01*
G03X681373Y90350I791J595D01*
G01X684125D01*
G03X686793Y91455I0J3773D01*
G01X693393Y98055D01*
G03X694398Y100481I-2426J2426D01*
G01Y119019D01*
G03X693393Y121445I-3431J0D01*
G01X691315Y123523D01*
G03X690477Y123803I-700J-701D01*
G02X689639Y124082I-139J980D01*
G01X688472Y125249D01*
G02X688193Y126087I701J699D01*
G03X687914Y126924I-980J138D01*
G01X684806Y130032D01*
G03X682470I-1168J-1168D01*
G01X682418Y129980D01*
G01X619884Y308070D02*
Y309734D01*
G03X618462Y311156I-1422J0D01*
G01X617823D01*
G03X617232Y310911I0J-836D01*
G03X616550Y309265I1646J-1646D01*
G01Y304890D01*
G03X616806Y304272I874J0D01*
G01X617828Y303250D01*
G01X615944Y315945D02*
X617367Y313104D01*
G02X617122Y312366I-492J-246D01*
G01X617121D01*
X617119Y312365D01*
Y312366D01*
G03X617117Y312363I1373J-917D01*
G01X616455Y312032D01*
G03X615200Y309266I2423J-2767D01*
G01Y304890D01*
G02X614916Y304203I-971J-1D01*
G01X613962Y303250D01*
G01X635629Y308070D02*
Y309614D01*
G03X635055Y311000I-1960J0D01*
G03X633618Y311232I-879J-880D01*
G01X632979Y310912D01*
G03X632325Y309333I1579J-1579D01*
G01Y305360D01*
G03X632931Y303897I2069J0D01*
G01X633578Y303250D01*
G01X631694Y315945D02*
X633114Y313105D01*
G02X632868Y312367I-492J-246D01*
G01X632865Y312365D01*
X632375Y312120D01*
X632202Y312033D01*
G03X632024Y311867I2353J-2702D01*
G03X630975Y309332I2534J-2533D01*
G01Y305360D01*
G02X630376Y303914I-2045J0D01*
G01X629712Y303250D01*
G01X651379Y308070D02*
Y309734D01*
G03X649957Y311156I-1422J0D01*
G01X649318D01*
G03X648727Y310911I0J-836D01*
G03X648045Y309265I1646J-1646D01*
G01Y304890D01*
G03X648301Y304272I874J0D01*
G01X649323Y303250D01*
G01X647439Y315945D02*
X648862Y313104D01*
G02X648617Y312366I-492J-246D01*
G01X648616D01*
X648614Y312365D01*
Y312366D01*
G03X648612Y312363I1373J-917D01*
G01X647950Y312032D01*
G03X646695Y309266I2423J-2767D01*
G01Y304890D01*
G02X646411Y304203I-971J-1D01*
G01X645457Y303250D01*
G01X667124Y308070D02*
Y309739D01*
G03X665707Y311156I-1417J0D01*
G01X665068D01*
G03X664477Y310911I0J-836D01*
G03X663795Y309265I1646J-1646D01*
G01Y304890D01*
G03X664051Y304272I874J0D01*
G01X665073Y303250D01*
G01X663189Y315945D02*
X664612Y313104D01*
G02X664367Y312366I-492J-246D01*
G01X664366D01*
X664364Y312365D01*
Y312366D01*
G03X664362Y312363I1373J-917D01*
G01X663700Y312032D01*
G03X662445Y309266I2423J-2767D01*
G01Y304890D01*
G02X662161Y304203I-971J-1D01*
G01X661207Y303250D01*
G01X757679Y315945D02*
X759102Y313104D01*
G02X758857Y312366I-492J-246D01*
G01X758856D01*
X758854Y312365D01*
Y312366D01*
G03X758852Y312363I1373J-917D01*
G01X758190Y312032D01*
G03X756935Y309266I2423J-2767D01*
G01Y304890D01*
G02X756651Y304203I-971J-1D01*
G01X755697Y303250D01*
G01X761614Y308070D02*
Y309739D01*
G03X760197Y311156I-1417J0D01*
G01X759558D01*
G03X758967Y310911I0J-836D01*
G03X758285Y309265I1646J-1646D01*
G01Y304890D01*
G03X758541Y304272I874J0D01*
G01X759563Y303250D01*
G01X773424Y315945D02*
Y315944D01*
X774479Y314889D01*
G02X775055Y313500I-1389J-1390D01*
G02X774685Y312684I-1084J0D01*
G01X773940Y312032D01*
G03X773762Y311866I2418J-2772D01*
G03X772685Y309266I2601J-2601D01*
G01Y304890D01*
G02X772401Y304203I-971J-1D01*
G01X771447Y303250D01*
G01X789174Y315945D02*
X790597Y313104D01*
G02X790352Y312366I-492J-246D01*
G01X790351D01*
X790349Y312365D01*
Y312366D01*
G03X790347Y312363I1373J-917D01*
G01X789685Y312032D01*
G03X788430Y309266I2423J-2767D01*
G01Y304890D01*
G02X788146Y304203I-971J-1D01*
G01X787192Y303250D01*
G01X777364Y308070D02*
Y309739D01*
G03X775947Y311156I-1417J0D01*
G01X775308D01*
G03X774717Y310911I0J-836D01*
G03X774035Y309265I1646J-1646D01*
G01Y304890D01*
G03X774291Y304272I874J0D01*
G01X775313Y303250D01*
G01X804919Y315945D02*
X804960D01*
G02X806405Y314500I0J-1445D01*
G01Y313100D01*
G02X806241Y312737I-482J-1D01*
G01X805435Y312032D01*
G03X805257Y311866I2418J-2772D01*
G03X804180Y309266I2601J-2601D01*
G01Y304890D01*
G02X803896Y304203I-971J-1D01*
G01X802942Y303250D01*
G01X793109Y308070D02*
Y309739D01*
G03X791692Y311156I-1417J0D01*
G01X791053D01*
G03X790462Y310911I0J-836D01*
G03X789780Y309265I1646J-1646D01*
G01Y304890D01*
G03X790036Y304272I874J0D01*
G01X791058Y303250D01*
G01X808859Y308070D02*
X809055Y308266D01*
G03Y310500I-1117J1117D01*
G03X807471Y311156I-1584J-1584D01*
G01X806803D01*
G03X806212Y310911I0J-836D01*
G03X805530Y309265I1646J-1646D01*
G01Y304890D01*
G03X805786Y304272I874J0D01*
G01X806808Y303250D01*
G01X1336017Y533012D02*
X1334212D01*
G03X1333300Y532100I0J-912D01*
G01Y530668D01*
G02X1332232Y529600I-1068J0D01*
G01X1309699D01*
G03X1304735Y527544I1J-7023D01*
G01X1304447Y527257D01*
X1282326Y505136D01*
G02X1275600Y502350I-6726J6726D01*
G01X1252810D01*
G03X1246050Y499550I0J-9561D01*
G01X1206800Y460300D01*
X1206752Y460253D01*
G02X1198900Y457000I-7853J7852D01*
G01X1045739D01*
G03X1037650Y453650I-1J-11439D01*
G01X1034950Y450950D01*
G02X1030242Y449000I-4708J4708D01*
G01X944982D01*
G03X940045Y446955I1J-6983D01*
G01X934595Y441505D01*
G02X930298Y439725I-4297J4297D01*
G01X924956D01*
G03X919595Y437505I-1J-7581D01*
G01X909514Y427424D01*
G02X903300Y424850I-6214J6214D01*
G01X873690D01*
G03X865040Y416200I0J-8650D01*
G01Y407961D01*
G02X864645Y407171I-990J1D01*
G03X864250Y406381I595J-791D01*
G01Y404731D01*
G03X864645Y403941I990J1D01*
G02X865040Y403151I-595J-791D01*
G01Y401501D01*
G02X864645Y400711I-990J1D01*
G03X864250Y399921I595J-791D01*
G01Y398271D01*
G03X864645Y397481I990J1D01*
G02X865040Y396691I-595J-791D01*
G01Y395041D01*
G02X864645Y394251I-990J1D01*
G03X864250Y393461I595J-791D01*
G01Y391811D01*
G03X864645Y391021I990J1D01*
G02X865040Y390231I-595J-791D01*
G01Y378298D01*
G02X863740Y375160I-4438J0D01*
G01X842090Y353510D01*
G03X839200Y346533I6978J-6978D01*
G01Y344883D01*
G02X838805Y344093I-990J1D01*
G03X838410Y343303I595J-791D01*
G01Y341653D01*
G03X838805Y340863I990J1D01*
G02X839200Y340073I-595J-791D01*
G01Y338423D01*
G02X838805Y337633I-990J1D01*
G03X838410Y336843I595J-791D01*
G01Y335193D01*
G03X838805Y334403I990J1D01*
G02X839200Y333613I-595J-791D01*
G01Y331963D01*
G02X838805Y331173I-990J1D01*
G03X838410Y330383I595J-791D01*
G01Y328733D01*
G03X838805Y327943I990J1D01*
G02X839200Y327153I-595J-791D01*
G01Y325503D01*
G02X838805Y324713I-990J1D01*
G03X838410Y323923I595J-791D01*
G01Y322273D01*
G03X838805Y321483I990J1D01*
G02X839200Y320692I-595J-791D01*
G01Y317722D01*
G02X839141Y317270I-1777J2D01*
G02X837423Y315945I-1718J451D01*
G01X836419D01*
G01X1336017Y525012D02*
X1334488D01*
G02X1333400Y526100I0J1088D01*
G01Y527250D01*
G03X1332400Y528250I-1000J0D01*
G01X1309700D01*
G03X1305689Y526588I1J-5673D01*
G01X1305400Y526300D01*
X1283281Y504181D01*
G02X1275600Y501000I-7680J7681D01*
G01X1252811D01*
G03X1247005Y498595I0J-8211D01*
G01X1207745Y459335D01*
X1207702Y459293D01*
G02X1198901Y455650I-8802J8812D01*
G01X1045739D01*
G03X1038605Y452695I0J-10089D01*
G01X1035905Y449995D01*
G02X1030242Y447650I-5662J5663D01*
G01X944983D01*
G03X941000Y446000I0J-5633D01*
G01X935550Y440550D01*
G02X930299Y438375I-5251J5252D01*
G01X924956D01*
G03X920550Y436550I0J-6231D01*
G01X910469Y426469D01*
G02X903300Y423500I-7168J7169D01*
G01X873690D01*
G03X866390Y416200I0J-7300D01*
G01Y378297D01*
G02X864695Y374205I-5788J1D01*
G01X843045Y352555D01*
G03X840550Y346532I6023J-6023D01*
G01Y308543D01*
G02X840354Y308070I-669J0D01*
G01X1165000Y308175D02*
X1165383Y307792D01*
G03X1167500Y306915I2117J2117D01*
G01X1214901D01*
G02X1221189Y304311I0J-8894D01*
G01X1244300Y281200D01*
X1244412Y281087D01*
G03X1247400Y279850I2987J2988D01*
G01X1253301D01*
G02X1258851Y274300I0J-5550D01*
G01Y271776D01*
G02X1256900Y269825I-1951J0D01*
G01X1256430D01*
G03X1256041Y269664I0J-550D01*
G01X1254944Y268567D01*
G01Y272433D02*
X1256041Y271336D01*
G03X1256430Y271175I389J389D01*
G01X1256900D01*
G03X1257501Y271776I0J601D01*
G01Y274300D01*
G03X1253301Y278500I-4200J0D01*
G01X1247400D01*
Y278499D01*
G02X1243455Y280134I0J5576D01*
G01X1243341Y280249D01*
X1237843Y285747D01*
G03X1237005Y286026I-699J-701D01*
G02X1236167Y286306I-138J980D01*
G01X1235000Y287472D01*
G02X1234721Y288310I702J699D01*
G03X1234442Y289148I-980J139D01*
G01X1233275Y290315D01*
G03X1232437Y290594I-699J-701D01*
G02X1231599Y290874I-138J980D01*
G01X1230433Y292040D01*
G02X1230153Y292878I700J700D01*
G03X1229874Y293716I-980J139D01*
G01X1228707Y294883D01*
G03X1227869Y295162I-699J-701D01*
G02X1227031Y295441I-139J981D01*
G01X1225865Y296608D01*
G02X1225585Y297446I700J700D01*
G03X1225306Y298284I-980J139D01*
G01X1220595Y302995D01*
X1220234Y303355D01*
G03X1214900Y305565I-5335J-5334D01*
G01X1208151D01*
G03X1207361Y305170I1J-990D01*
G02X1206571Y304775I-791J595D01*
G01X1204921D01*
G02X1204131Y305170I1J990D01*
G03X1203341Y305565I-791J-595D01*
G01X1201691D01*
G03X1200901Y305170I1J-990D01*
G02X1200111Y304775I-791J595D01*
G01X1198461D01*
G02X1197671Y305170I1J990D01*
G03X1196881Y305565I-791J-595D01*
G01X1192633D01*
G03X1191843Y305170I1J-990D01*
G02X1191053Y304775I-791J595D01*
G01X1189403D01*
G02X1188613Y305170I1J990D01*
G03X1187823Y305565I-791J-595D01*
G01X1186173D01*
G03X1185383Y305170I1J-990D01*
G02X1184593Y304775I-791J595D01*
G01X1182943D01*
G02X1182153Y305170I1J990D01*
G03X1181363Y305565I-791J-595D01*
G01X1179713D01*
G03X1178923Y305170I1J-990D01*
G02X1178133Y304775I-791J595D01*
G01X1176483D01*
G02X1175693Y305170I1J990D01*
G03X1174903Y305565I-791J-595D01*
G01X1167414D01*
G03X1165000Y304565I0J-3414D01*
G01X1155500Y450758D02*
X1156162Y450095D01*
G03X1157600Y449500I1437J1438D01*
G01X1198300D01*
G03X1206205Y452775I-1J11180D01*
G01X1206465Y453034D01*
X1245915Y492484D01*
G02X1252836Y495350I6920J-6921D01*
G01X1327600D01*
G03X1334343Y498143I0J9536D01*
G01X1356981Y520781D01*
G03X1357900Y523000I-2219J2219D01*
G01Y525137D01*
G03X1354700Y528337I-3200J0D01*
G01X1345800D01*
G03X1344700Y527237I0J-1100D01*
G01Y525600D01*
G02X1344112Y525012I-588J0D01*
G01X1342017D01*
G01X1155500Y446892D02*
X1156162Y447555D01*
G02X1157600Y448150I1437J-1438D01*
G01X1198301D01*
G03X1207159Y451819I-1J12530D01*
G01X1207418Y452077D01*
X1246870Y491529D01*
G02X1252836Y494000I5966J-5966D01*
G01X1327600D01*
G03X1335298Y497188I1J10886D01*
G01X1357936Y519826D01*
G03X1359250Y523000I-3175J3173D01*
G01Y525137D01*
G03X1354700Y529687I-4550J0D01*
G01X1345800D01*
G02X1344600Y530887I0J1200D01*
G01Y532100D01*
G03X1343688Y533012I-912J0D01*
G01X1342017D01*
G01X1330517Y525012D02*
X1323312D01*
X1322900Y524600D01*
G01X1330517Y533012D02*
X1322488D01*
X1322400Y533100D01*
G01X1336017Y525012D02*
X1336517D01*
G01X1347517D02*
X1351488D01*
X1351900Y524600D01*
G01X1336017Y533012D02*
X1336517D01*
G01X1347517D02*
X1351812D01*
X1352400Y533600D01*
G54D81*
G01X41304Y927220D02*
X49720Y935636D01*
X86364D01*
X95700Y926300D01*
G01X81304Y884470D02*
X81554Y884720D01*
X86304D01*
X96804Y895220D01*
X102304D01*
G01X87928Y848107D02*
X92304Y843731D01*
Y835720D01*
G01X95700Y926300D02*
X96554Y925446D01*
Y901127D01*
X102304Y895377D01*
Y895220D01*
G01X157750Y662250D02*
X153500Y666500D01*
X130000D01*
G01X267718Y989460D02*
Y1009860D01*
G01X271653Y993525D02*
Y1009860D01*
G01X275588D02*
Y996210D01*
G01X312925Y462560D02*
X312795D01*
X299395Y449160D01*
G01X312925Y462560D02*
Y529726D01*
X312773Y529878D01*
G01X367022Y482783D02*
X370505Y486266D01*
Y517995D01*
X370500Y518000D01*
G01X426928Y864000D02*
X430778D01*
G01X440228Y829653D02*
X437875Y827300D01*
X432678D01*
G01X441528Y862250D02*
X435528D01*
X433778Y864000D01*
X430778D01*
G01X450678Y812250D02*
Y821700D01*
X453878Y824900D01*
G01X456278Y829500D02*
Y827100D01*
X454078Y824900D01*
X453878D01*
G01X456278Y833500D02*
Y829500D01*
G01Y858000D02*
Y866500D01*
G01X455778Y872250D02*
Y867000D01*
X456278Y866500D01*
G01X476978Y830500D02*
X481278D01*
X482778Y832000D01*
G01X476278Y830500D02*
X476978D01*
G01X475278Y864000D02*
X478778D01*
X482278Y867500D01*
G01X482778Y832000D02*
X488028D01*
G01X482278Y867500D02*
X486478D01*
G01D02*
Y875500D01*
G01X684197Y74703D02*
X684000Y74506D01*
Y67000D01*
X676748Y59748D01*
Y52000D01*
G01X766928Y1009860D02*
Y999500D01*
G01X770868Y1009860D02*
Y998632D01*
G01X785345Y999345D02*
X786613Y1000613D01*
Y1009860D01*
G01X777469Y998469D02*
X778738Y999738D01*
Y1009860D01*
G01X789025Y998733D02*
X790553Y1000261D01*
Y1009860D01*
G01X783655Y999345D02*
X782678Y1000322D01*
Y1009860D01*
G01X774803Y999500D02*
Y1009860D01*
G01X980490Y198827D02*
X980560Y198757D01*
X1003257D01*
X1022976Y218476D01*
X1031524D01*
G01X1205240Y568760D02*
X1198980Y562500D01*
X1158000D01*
X1151000Y569500D01*
Y586000D01*
X1154000Y589000D01*
G54D18*
X45300Y872500D03*
Y868500D03*
X337340Y193000D03*
X337229Y189000D03*
X337340Y197500D03*
X343300Y396000D03*
X358810Y179910D03*
X413300Y225000D03*
X437729Y113500D03*
X448229Y175500D03*
X476300Y186231D03*
X467455Y308700D03*
X476323Y334283D03*
X488078Y844000D03*
Y836000D03*
Y840000D03*
Y848500D03*
X524229Y124500D03*
X531300Y148500D03*
X776800Y973000D03*
X1035800Y141000D03*
X1066168Y681554D03*
X1077800Y667500D03*
Y679500D03*
Y675500D03*
Y671500D03*
Y683500D03*
Y695500D03*
Y687500D03*
Y691500D03*
Y699500D03*
Y711500D03*
Y707500D03*
Y703500D03*
Y723500D03*
Y719500D03*
Y715500D03*
Y727500D03*
X1078800Y736500D03*
X1086300Y630000D03*
X1087800Y655000D03*
X1087788Y650584D03*
X1168500Y679300D03*
X1222300Y727000D03*
Y718500D03*
Y735500D03*
Y731000D03*
X1257800Y651000D03*
Y657000D03*
Y661000D03*
X1250300Y671000D03*
X1257800Y667500D03*
X1250300Y687500D03*
Y683500D03*
G54D45*
X343929Y215450D03*
X356929Y215700D03*
X364909Y190119D03*
X365429Y215450D03*
X394029Y196100D03*
X385429Y219700D03*
X410729Y196200D03*
X407214Y196250D03*
X403109Y215980D03*
X438055Y319200D03*
X461929Y180200D03*
X451055Y378200D03*
Y385700D03*
X455778Y872200D03*
X471429Y126200D03*
X489555Y427700D03*
X678400Y398800D03*
X731716Y109484D03*
X735216D03*
X1149268Y675884D03*
X1144768Y677484D03*
X1157000Y677200D03*
X1154300Y802700D03*
X1160300Y801200D03*
X1165300D03*
X1170300D03*
X1200370Y704450D03*
X1217000Y198700D03*
X1220500D03*
X1273236Y687078D03*
X1277000Y705700D03*
X1273000Y724200D03*
X1292500Y405700D03*
X1312500Y607700D03*
X1306500Y645200D03*
X1379500Y319200D03*
G54D54*
X437478Y845016D03*
Y843047D03*
Y848953D03*
Y846984D03*
X473078Y843047D03*
Y845016D03*
Y846984D03*
Y848953D03*
G54D63*
X670800Y446000D03*
X712548Y117000D03*
X1073300Y140500D03*
X1144768Y695784D03*
X1144800Y700500D03*
X1199250Y698520D03*
X1290300Y433000D03*
X1345300Y394500D03*
X1336317Y533012D03*
Y525012D03*
X1341817Y533012D03*
Y525012D03*
G54D36*
X299750Y88000D03*
X307250Y84125D03*
Y91875D03*
X343250Y287625D03*
X335750Y291500D03*
X343250Y295375D03*
X510179Y125500D03*
X517679Y121625D03*
Y129375D03*
G54D27*
X121890Y269528D03*
X131890D03*
X141890D03*
X1346396Y21656D03*
X1338526D03*
X1346396Y29526D03*
X1338526D03*
X1362146Y21656D03*
X1354271D03*
X1362146Y29526D03*
X1354271D03*
X1377896Y21656D03*
X1370021D03*
X1377896Y29526D03*
X1370021D03*
X1385766Y21656D03*
Y29526D03*
G54D72*
X1350084Y284018D03*
G54D82*
G01X423679Y190000D02*
Y190837D01*
X422599Y191917D01*
Y192179D01*
X421876Y192902D01*
G01X1179750Y701300D02*
X1179790Y701340D01*
X1182459D01*
X1182815Y701696D01*
G54D37*
X314500Y76800D03*
X307500Y294300D03*
X319500Y76800D03*
X332500Y74300D03*
X1031500Y69300D03*
X1036500D03*
X1041500D03*
X1046500D03*
X1051500D03*
X1124800Y809800D03*
X1131300D03*
X1142000Y805300D03*
X1212500Y203300D03*
X1204390Y709000D03*
G54D19*
X43520Y910988D03*
X48020D03*
X52520D03*
X57020D03*
X61520D03*
X66020D03*
X99804Y913020D03*
X103804D03*
X107804D03*
X111804D03*
X115804D03*
X119804D03*
X123804D03*
X127804D03*
X131804D03*
X135804D03*
X313000Y89300D03*
X330000Y84300D03*
X314453Y245152D03*
X344040Y207300D03*
X357040D03*
X348540D03*
X353040D03*
X351000Y392800D03*
X373200Y179840D03*
X371429Y203800D03*
X380829Y187900D03*
X393000Y940800D03*
X406555Y323300D03*
X405000Y940800D03*
X409000D03*
X397000D03*
X401000D03*
X425278Y808800D03*
X413000Y940800D03*
X417000D03*
X429940Y151600D03*
X444055Y295300D03*
X431778Y808800D03*
X431278Y872300D03*
X437778D03*
X456278Y808800D03*
X460778Y872300D03*
X462778Y808800D03*
X467278Y872300D03*
X544178Y964800D03*
X548555Y341800D03*
X554955Y368200D03*
X558955D03*
X641000Y472300D03*
X646500Y448800D03*
X678500Y406800D03*
X787000Y411300D03*
X1010500Y74800D03*
X1178500Y644300D03*
X1281000Y687300D03*
Y705800D03*
X1273000Y698300D03*
X1281000D03*
X1277000Y716300D03*
X1281000Y724300D03*
X1292500Y413300D03*
X1372300Y281000D03*
X1384300D03*
G54D46*
X343929Y219050D03*
X356929Y219300D03*
X364909Y193719D03*
X365429Y219050D03*
X394029Y199700D03*
X385429Y223300D03*
X410729Y199800D03*
X407214Y199850D03*
X403109Y219580D03*
X438055Y322800D03*
X461929Y183800D03*
X451055Y381800D03*
Y389300D03*
X455778Y875800D03*
X471429Y129800D03*
X489555Y431300D03*
X678400Y402400D03*
X731716Y113084D03*
X735216D03*
X1149268Y679484D03*
X1144768Y681084D03*
X1157000Y680800D03*
X1154300Y806300D03*
X1160300Y804800D03*
X1165300D03*
X1170300D03*
X1200370Y708050D03*
X1217000Y202300D03*
X1220500D03*
X1273236Y690678D03*
X1277000Y709300D03*
X1273000Y727800D03*
X1292500Y409300D03*
X1312500Y611300D03*
X1306500Y648800D03*
X1379500Y322800D03*
G54D55*
X439530Y839000D03*
X441498D03*
X443467D03*
Y853000D03*
X441498D03*
X439530D03*
X445435Y839000D03*
X447404D03*
X449372D03*
X451341D03*
X453309D03*
X455278D03*
X457247D03*
X459215D03*
X461184D03*
Y853000D03*
X459215D03*
X457247D03*
X455278D03*
X453309D03*
X451341D03*
X449372D03*
X447404D03*
X445435D03*
X463152Y839000D03*
X465121D03*
X467089D03*
X469058D03*
X471026D03*
Y853000D03*
X469058D03*
X467089D03*
X465121D03*
X463152D03*
G54D64*
X665200Y446000D03*
X706948Y117000D03*
X1067700Y140500D03*
X1139168Y695784D03*
X1139200Y700500D03*
X1193650Y698520D03*
X1284700Y433000D03*
X1330717Y533012D03*
Y525012D03*
X1339700Y394500D03*
X1336217Y533012D03*
Y525012D03*
G54D73*
X1376300Y284050D03*
X1380300D03*
G54D28*
X153937Y238898D03*
Y246772D03*
Y260551D03*
X224015Y234961D03*
Y246772D03*
Y260551D03*
G54D83*
G01X47476Y393529D02*
X47483Y393522D01*
Y387776D01*
G01X43976Y393529D02*
Y387862D01*
X43883Y387769D01*
G01X43976Y397029D02*
X44801Y397855D01*
G03X44976Y398276I-421J422D01*
G01Y414860D01*
G02X46830Y419337I6331J1D01*
G01X59949Y432456D01*
G02X73563Y438095I13614J-13615D01*
G01X138275D01*
G02X142765Y436235I0J-6350D01*
G01X193686Y385314D01*
G03X197221Y383850I3535J3536D01*
G01X219491D01*
G02X230705Y379205I0J-15860D01*
G01X296990Y312920D01*
G02X298850Y308430I-4490J-4490D01*
G01Y223500D01*
G03X300575Y219334I5891J-1D01*
G01X301455Y218455D01*
X344350Y175560D01*
Y175547D01*
X349951Y169946D01*
G03X350132Y169920I182J625D01*
G01X358663D01*
G02X359955Y169385I0J-1828D01*
G01X360350Y168990D01*
G03X360688Y168850I338J338D01*
G01X364329D01*
G03X366211Y169232I0J4827D01*
G03X367743Y170264I-1882J4447D01*
G01X368309Y170830D01*
G01X47476Y397029D02*
G02X46480Y398712I2775J2778D01*
G02X46353Y399340I3772J1090D01*
G02X46326Y399805I3899J460D01*
G01Y414860D01*
G02X47785Y418382I4981J0D01*
G01X60904Y431501D01*
G02X73564Y436745I12660J-12660D01*
G01X138274D01*
G02X141809Y435281I0J-5000D01*
G01X192730Y384360D01*
G03X197220Y382500I4490J4490D01*
G01X219490D01*
G02X229750Y378250I0J-14510D01*
G01X241877Y366123D01*
G02X242210Y365126I-793J-819D01*
G03X242542Y364129I1126J-179D01*
G01X243391Y363280D01*
G03X244388Y362948I818J794D01*
G02X245385Y362615I178J-1126D01*
G01X256869Y351131D01*
G02X257201Y350134I-794J-818D01*
G03X257533Y349137I1126J-179D01*
G01X258382Y348289D01*
G03X259379Y347956I819J793D01*
G02X260376Y347624I179J-1126D01*
G01X261225Y346775D01*
G02X261557Y345778I-794J-818D01*
G03X261889Y344781I1126J-179D01*
G01X262738Y343933D01*
G03X263735Y343601I818J794D01*
G02X264732Y343268I178J-1126D01*
G01X265580Y342420D01*
G02X265913Y341423I-793J-819D01*
G03X266245Y340426I1126J-179D01*
G01X267094Y339577D01*
G03X268091Y339245I818J794D01*
G02X269088Y338912I178J-1126D01*
G01X296036Y311964D01*
G02X297500Y308429I-3536J-3535D01*
G01Y223500D01*
X297499D01*
G03X299620Y218378I7242J-1D01*
G01X300500Y217500D01*
X343000Y175000D01*
Y174987D01*
X349172Y168815D01*
G03X350132Y168570I960J1757D01*
G01X358663D01*
G02X359000Y168429I-2J-477D01*
G01X359394Y168035D01*
G03X360688Y167500I1292J1294D01*
G01X364329D01*
G03X366737Y167988I1J6179D01*
G03X367318Y168270I-2404J5692D01*
G02X367844Y168196I214J-387D01*
G01X368334Y167706D01*
G01X62976Y393529D02*
Y388242D01*
G02X62783Y387776I-659J0D01*
G01X66476Y393529D02*
Y387883D01*
X66483Y387876D01*
G01X56976Y393529D02*
Y387969D01*
X56883Y387876D01*
G01X53476Y393529D02*
Y388383D01*
G02X53183Y387676I-1000J0D01*
G01X53476Y397029D02*
G03X54133Y398615I-1586J1586D01*
G01Y414135D01*
G02X55816Y418197I5746J-1D01*
G01X57769Y420151D01*
X60953Y423335D01*
G02X78119Y430445I17166J-17168D01*
G01X135425D01*
G02X139915Y428585I0J-6350D01*
G01X190685Y377815D01*
G03X194221Y376350I3536J3535D01*
G01X214405D01*
G02X223205Y372705I0J-12446D01*
G01X271467Y324443D01*
G03X272464Y324111I818J794D01*
G02X273461Y323779I179J-1126D01*
G01X274309Y322930D01*
G02X274642Y321933I-793J-819D01*
G03X274974Y320936I1126J-179D01*
G01X275823Y320087D01*
G03X276820Y319755I818J794D01*
G02X277817Y319423I179J-1126D01*
G01X278665Y318574D01*
G02X278997Y317577I-794J-818D01*
G03X279330Y316580I1126J-178D01*
G01X280178Y315732D01*
G03X281175Y315399I819J793D01*
G02X282172Y315067I179J-1126D01*
G01X283021Y314219D01*
G02X283353Y313221I-794J-818D01*
G03X283686Y312224I1126J-178D01*
G01X289959Y305951D01*
G02X291819Y301461I-4490J-4490D01*
G01Y220030D01*
G03X293103Y216930I4384J0D01*
G01X295767Y214267D01*
X330864Y179170D01*
X343407Y166795D01*
X343535Y166667D01*
G03X345629Y165800I2094J2095D01*
G01X362150D01*
G02X365158Y164554I0J-4254D01*
G01X56976Y397029D02*
G02X56045Y397414I-1J1316D01*
G01X55881Y397579D01*
X55603Y397858D01*
G02X55483Y398148I290J290D01*
G01Y414134D01*
G02X56771Y417242I4396J-1D01*
G01X58724Y419196D01*
X61908Y422380D01*
G02X78120Y429095I16212J-16213D01*
G01X135424D01*
G02X138959Y427631I0J-5000D01*
G01X189730Y376860D01*
G03X194220Y375000I4490J4490D01*
G01X214404D01*
G02X222250Y371750I0J-11096D01*
G01X289005Y304995D01*
G02X290469Y301460I-3536J-3535D01*
G01Y220030D01*
G03X292148Y215975I5734J-1D01*
G01X294812Y213312D01*
X329948Y178176D01*
X342458Y165833D01*
X342580Y165711D01*
G03X345630Y164450I3047J3052D01*
G01X362302D01*
G01X62976Y397029D02*
G03X63860Y398783I-2222J2220D01*
G03X63870Y398851I-3102J491D01*
G03X63889Y399060I-3116J389D01*
G03X63896Y399250I-3133J211D01*
G01Y411770D01*
G02X65946Y416718I6999J-1D01*
G01X66189Y416961D01*
G02X76303Y421150I10114J-10116D01*
G01X134620D01*
G02X139110Y419290I0J-6350D01*
G01X187585Y370815D01*
G03X191121Y369350I3536J3535D01*
G01X210500D01*
G02X219137Y365773I1J-12214D01*
G01X283209Y301701D01*
G02X285069Y297211I-4490J-4490D01*
G01Y216455D01*
G03X286500Y213000I4886J0D01*
G01X338579Y160921D01*
G03X342500Y159297I3921J3921D01*
G01X365915D01*
G03X367129Y159800I0J1717D01*
G01X368041Y160712D01*
G03X368326Y161400I-688J688D01*
G01X66476Y397029D02*
X65753Y397752D01*
G02X65246Y398976I1224J1224D01*
G01Y411769D01*
G02X66901Y415763I5649J-1D01*
G01X67144Y416006D01*
G02X76304Y419800I9160J-9161D01*
G01X77504D01*
G02X78444Y419330I18J-1140D01*
G03X79384Y418860I922J670D01*
G01X80584D01*
G03X81524Y419330I18J1140D01*
G02X82464Y419800I922J-670D01*
G01X83664D01*
G02X84604Y419330I18J-1140D01*
G03X85544Y418860I922J670D01*
G01X86744D01*
G03X87684Y419330I18J1140D01*
G02X88624Y419800I922J-670D01*
G01X89824D01*
G02X90764Y419330I18J-1140D01*
G03X91704Y418860I922J670D01*
G01X92904D01*
G03X93844Y419330I18J1140D01*
G02X94784Y419800I922J-670D01*
G01X101488D01*
G02X102428Y419330I18J-1140D01*
G03X103368Y418860I923J670D01*
G01X104568D01*
G03X105508Y419330I18J1140D01*
G02X106448Y419800I923J-670D01*
G01X111506D01*
G02X112446Y419330I18J-1140D01*
G03X113386Y418860I922J670D01*
G01X114586D01*
G03X115526Y419330I18J1140D01*
G02X116466Y419800I922J-670D01*
G01X134619D01*
G02X138154Y418336I0J-5000D01*
G01X186630Y369860D01*
G03X191120Y368000I4490J4490D01*
G01X210501D01*
G02X218182Y364818I-1J-10864D01*
G01X282255Y300745D01*
G02X283719Y297210I-3536J-3535D01*
G01Y216455D01*
G03X285545Y212045I6236J-1D01*
G01X337624Y159966D01*
G03X342501Y157947I4875J4876D01*
G01X367496D01*
G03X368271Y158268I0J1096D01*
G01X71976Y393529D02*
Y388201D01*
G02X71883Y387976I-318J0D01*
G01X75476Y393529D02*
Y389441D01*
G03X76083Y387976I2072J0D01*
G01X75476Y397029D02*
X74590Y398770D01*
G02X74455Y399244I1150J584D01*
G01X74433Y399495D01*
G02Y399547I3561J26D01*
G01Y401900D01*
G02X75305Y404005I2977J0D01*
G01X76800Y405500D01*
G02X82111Y407700I5311J-5311D01*
G01X136219D01*
G02X139754Y406236I0J-5000D01*
G01X183130Y362860D01*
G03X187620Y361000I4490J4490D01*
G01X205844D01*
G02X215500Y357000I-1J-13657D01*
G01X275505Y296995D01*
G02X276969Y293460I-3536J-3535D01*
G01Y212143D01*
G03X278045Y209545I3675J0D01*
G01X337313Y150276D01*
G03X341001Y148750I3685J3687D01*
G01X353272D01*
G03X354687Y149336I0J2002D01*
G01X355859Y150508D01*
G02X356319Y150700I462J-459D01*
G01X360478D01*
X361616Y151838D01*
X362632D01*
X364311Y153517D01*
G01X365140Y155100D02*
X364667D01*
X362755Y153188D01*
X361056D01*
X359918Y152050D01*
X356320D01*
G03X354904Y151464I-1J-2002D01*
G01X353731Y150291D01*
G02X353271Y150100I-461J460D01*
G01X341000D01*
G02X338268Y151231I-1J3863D01*
G01X279000Y210500D01*
G02X278319Y212144I1644J1644D01*
G01Y293461D01*
G03X276459Y297951I-6350J0D01*
G01X216455Y357955D01*
G03X205843Y362350I-10611J-10612D01*
G01X187621D01*
G02X184086Y363814I0J5000D01*
G01X140710Y407190D01*
G03X136220Y409050I-4490J-4490D01*
G01X107816D01*
G02X106876Y409520I-18J1140D01*
G03X105936Y409990I-922J-670D01*
G01X104736D01*
G03X103796Y409520I-18J-1140D01*
G02X102856Y409050I-922J670D01*
G01X101656D01*
G02X100716Y409520I-18J1140D01*
G03X99776Y409990I-922J-670D01*
G01X98576D01*
G03X97636Y409520I-18J-1140D01*
G02X96696Y409050I-922J670D01*
G01X82110D01*
G03X75845Y406455I0J-8861D01*
G01X74350Y404960D01*
G03X73083Y401900I3060J-3059D01*
G01Y399156D01*
G02X72362Y397415I-2462J0D01*
G01X71976Y397029D01*
G01X165795Y303959D02*
X166156Y303598D01*
G02X167041Y301461I-2138J-2137D01*
G01Y295723D01*
G02X166924Y295440I-401J0D01*
G01X165793Y294309D01*
G01X155874Y313961D02*
X157122Y315209D01*
X163374D01*
G02X167120Y311463I0J-3746D01*
G01Y310009D01*
G02X166720Y309609I-400J0D01*
G01X166195D01*
G03X165795Y309209I0J-400D01*
G01Y307459D01*
G01X155874Y317807D02*
X157122Y316559D01*
X163374D01*
G02X168470Y311463I0J-5096D01*
G01Y310009D01*
G03X168870Y309609I400J0D01*
G01X169395D01*
G02X169795Y309209I0J-400D01*
G01Y307459D01*
G01X155874Y326957D02*
X157122Y325709D01*
X168724D01*
G02X177724Y316709I0J-9000D01*
G01Y309859D01*
X179295Y308288D01*
Y307459D01*
G01X155874Y323111D02*
X157122Y324359D01*
X168724D01*
G02X176374Y316709I0J-7650D01*
G01Y309788D01*
X175295Y308709D01*
Y307459D01*
G01X169795Y303959D02*
G03X168391Y300569I3390J-3390D01*
G01Y295723D01*
G03X168508Y295440I401J0D01*
G01X169639Y294309D01*
G01X179295Y303959D02*
X178756Y303419D01*
G03X177840Y301209I2210J-2211D01*
G01Y296323D01*
G03X177957Y296040I401J0D01*
G01X179088Y294909D01*
G01X175295Y303959D02*
X175940Y303314D01*
G02X176490Y301987I-1327J-1328D01*
G01Y296323D01*
G02X176373Y296040I-401J0D01*
G01X175242Y294909D01*
G01X203795Y303959D02*
Y305788D01*
X202874Y306709D01*
Y308709D01*
G02X204642Y312977I6036J0D01*
G02X213652Y316709I9010J-9010D01*
G01X216374D01*
G03X219224Y319559I0J2850D01*
G01Y323296D01*
G03X217829Y326664I-4763J0D01*
G01X213829Y330664D01*
G03X208047Y333059I-5783J-5783D01*
G01X194874D01*
G02X193591Y333591I1J1815D01*
G01X192874Y334307D01*
G01Y330461D02*
X193591Y331177D01*
G02X194874Y331709I1284J-1283D01*
G01X208046D01*
G02X212874Y329709I0J-6828D01*
G01X216874Y325709D01*
G02X217873Y323296I-2413J-2412D01*
G01X217874Y323297D01*
Y319559D01*
G02X216374Y318059I-1500J0D01*
G01X213653D01*
G03X203687Y313932I-2J-14092D01*
G03X201524Y308709I5223J-5222D01*
G01Y306709D01*
X200295Y305480D01*
Y303959D01*
G01X209795D02*
Y305709D01*
G02X210195Y306109I400J0D01*
G01X210720D01*
G03X211120Y306509I0J400D01*
G01Y308709D01*
G02X213470Y311059I2350J0D01*
G01X221874D01*
G03X224945Y314130I0J3071D01*
G01Y323709D01*
G03X221056Y333098I-13278J0D01*
G01X214677Y339477D01*
G03X206874Y342709I-7803J-7803D01*
G01X195525D01*
G03X192874Y341611I0J-3749D01*
G01X213795Y303959D02*
Y305709D01*
G03X213395Y306109I-400J0D01*
G01X212870D01*
G02X212470Y306509I0J400D01*
G01Y308709D01*
G02X213470Y309709I1000J0D01*
G01X221874D01*
G03X226295Y314130I0J4421D01*
G01Y323709D01*
G03X222011Y334053I-14628J1D01*
G01X215632Y340432D01*
G03X206874Y344059I-8757J-8759D01*
G01X196249D01*
G02X192874Y345457I0J4773D01*
G01X203795Y300459D02*
G03X203037Y298629I1830J-1830D01*
G01Y296323D01*
G03X203154Y296040I401J0D01*
G01X204285Y294909D01*
G01X213795Y300459D02*
X213150Y299813D01*
G03X212485Y298209I1604J-1605D01*
G01Y296323D01*
G03X212602Y296040I401J0D01*
G01X213733Y294909D01*
G01X200295Y300459D02*
X201384Y299370D01*
G02X201687Y298638I-733J-732D01*
G01Y296323D01*
G02X201570Y296040I-401J0D01*
G01X200439Y294909D01*
G01X209795Y300459D02*
X210813Y299441D01*
G02X211135Y298664I-776J-777D01*
G01Y296323D01*
G02X211018Y296040I-401J0D01*
G01X209887Y294909D01*
G01X287403Y1009860D02*
Y1002677D01*
G03X288041Y1001137I2178J0D01*
G02X288231Y1000678I-459J-459D01*
G03X288285Y1000489I358J0D01*
G01X288309Y1000450D01*
G02X288328Y1000344I-309J-110D01*
G01Y879314D01*
G03X291545Y871545I10985J-2D01*
G01X332045Y831045D01*
G02X334150Y825963I-5082J-5082D01*
G01Y679999D01*
G03X336627Y674018I8460J0D01*
G01X400021Y610624D01*
G02X402097Y605611I-5013J-5013D01*
G01X402098Y605550D01*
Y450776D01*
G03X403396Y447642I4433J0D01*
G01X412566Y438472D01*
X412876Y438163D01*
G02X413705Y436160I-2003J-2002D01*
G01Y433025D01*
G03X414989Y429925I4385J0D01*
G01X414988Y429924D01*
X417791Y427122D01*
G02X418523Y425354I-1769J-1768D01*
G01Y408948D01*
G03X419255Y407180I2501J0D01*
G01X419761Y406674D01*
G02X420303Y405862I-1768J-1767D01*
G01X420668Y404981D01*
Y404922D01*
G01X291338Y1009860D02*
Y1003196D01*
G02X290606Y1001428I-2501J0D01*
G01X289868Y999644D01*
G03X289678Y998688I2310J-956D01*
G01Y969320D01*
G03X290148Y968380I1140J-18D01*
G02X290618Y967440I-670J-922D01*
G01Y966240D01*
G02X290148Y965300I-1140J-18D01*
G03X289678Y964360I670J-922D01*
G01Y963160D01*
G03X290148Y962220I1140J-18D01*
G02X290618Y961280I-670J-922D01*
G01Y960080D01*
G02X290148Y959140I-1140J-18D01*
G03X289678Y958200I670J-922D01*
G01Y957000D01*
G03X290148Y956060I1140J-18D01*
G02X290618Y955120I-670J-922D01*
G01Y953920D01*
G02X290148Y952980I-1140J-18D01*
G03X289678Y952040I670J-922D01*
G01Y932040D01*
G03X290148Y931100I1140J-18D01*
G02X290618Y930160I-670J-922D01*
G01Y928960D01*
G02X290148Y928020I-1140J-18D01*
G03X289678Y927080I670J-922D01*
G01Y925880D01*
G03X290148Y924940I1140J-18D01*
G02X290618Y924000I-670J-922D01*
G01Y922800D01*
G02X290148Y921860I-1140J-18D01*
G03X289678Y920920I670J-922D01*
G01Y919720D01*
G03X290148Y918780I1140J-18D01*
G02X290618Y917840I-670J-922D01*
G01Y916640D01*
G02X290148Y915700I-1140J-18D01*
G03X289678Y914760I670J-922D01*
G01Y894760D01*
G03X290148Y893820I1140J-18D01*
G02X290618Y892880I-670J-922D01*
G01Y891680D01*
G02X290148Y890740I-1140J-18D01*
G03X289678Y889800I670J-922D01*
G01Y879313D01*
G03X292500Y872500I9635J0D01*
G01X333000Y832000D01*
G02X335500Y825963I-6037J-6036D01*
G01Y680000D01*
G03X337582Y674973I7110J0D01*
G01X400976Y611579D01*
G02X403447Y605625I-5969J-5967D01*
G01X403448Y605581D01*
Y450777D01*
G03X404351Y448597I3083J0D01*
G01X413520Y439428D01*
X413831Y439119D01*
G02X415056Y436160I-2958J-2958D01*
G01X415055D01*
Y433026D01*
G03X415944Y430880I3035J0D01*
G01X418747Y428077D01*
G02X419873Y425354I-2726J-2721D01*
G01Y410690D01*
G03X420605Y408922I2501J0D01*
G01X420668Y408859D01*
G01X327100Y136294D02*
X326111Y137283D01*
G03X325828Y137400I-283J-284D01*
G01X313597D01*
G02X311023Y138465I-1J3640D01*
G01X310744Y138746D01*
G02X309750Y141149I2405J2402D01*
G01Y143874D01*
G03X309208Y145182I-1849J0D01*
G02X307100Y150270I5088J5088D01*
G01Y162386D01*
G03X306983Y162669I-401J0D01*
G01X305852Y163800D01*
G01X334600Y129468D02*
X334544Y129524D01*
G03X332309Y130450I-2235J-2234D01*
G01X310029D01*
Y130449D01*
G02X307534Y131483I-1J3524D01*
G01X307420Y131599D01*
X302181Y136838D01*
G02X301079Y139500I2663J2661D01*
G01Y142478D01*
G03X301019Y142782I-800J0D01*
G01X300828Y143245D01*
G03X300654Y143506I-740J-305D01*
G01X299831Y144328D01*
G01X334600Y133031D02*
G02X331628Y131800I-2972J2972D01*
G01X310029D01*
G02X308492Y132436I-1J2173D01*
G01X308379Y132550D01*
X303136Y137793D01*
G02X302429Y139500I1707J1707D01*
G01Y143369D01*
G02X302663Y143934I799J0D01*
G01X302823Y144094D01*
G02X303388Y144328I565J-565D01*
G01X303677D01*
G01X327100Y139857D02*
X326110Y138867D01*
G02X325827Y138750I-283J284D01*
G01X313598D01*
G02X311979Y139420I-1J2289D01*
G01X311700Y139700D01*
G02X311100Y141149I1449J1449D01*
G01Y143875D01*
G03X310163Y146137I-3199J0D01*
G02X308451Y150270I4133J4133D01*
G01X308450Y162386D01*
G02X308567Y162669I401J0D01*
G01X309698Y163800D01*
G01X313402Y156000D02*
X313989Y155413D01*
G02X314450Y154300I-1113J-1113D01*
G01Y146650D01*
G03X316800Y144300I2350J0D01*
G01X318386D01*
G02X318669Y144183I0J-401D01*
G01X319800Y143052D01*
G01X303148Y1009860D02*
G03X302978Y1009450I409J-410D01*
G01Y1001255D01*
G03X303653Y999625I2306J0D01*
G02X304327Y997998I-1631J-1629D01*
G02X304328Y997995I-2075J-693D01*
G01Y872399D01*
G03X306545Y867045I7571J-1D01*
G01X339545Y834045D01*
G02X341650Y828963I-5082J-5082D01*
G01Y684337D01*
G03X345072Y676073I11685J-2D01*
G01X405600Y615545D01*
G02X408848Y607704I-7841J-7841D01*
G01Y452020D01*
G03X410318Y448470I5020J-1D01*
G01X417466Y441322D01*
G02X418573Y438649I-2673J-2673D01*
G01Y433191D01*
G03X420105Y429491I5232J-1D01*
G02X421435Y426281I-3210J-3210D01*
G01Y411743D01*
G03X421686Y410482I3280J-3D01*
G01X421845Y410103D01*
G03X422227Y409534I1603J664D01*
G01X422231Y409530D01*
X422312Y409451D01*
G02X422723Y408835I-1343J-1341D01*
G01X423972Y406017D01*
G03X424424Y405359I1993J885D01*
G02X424605Y404922I-437J-437D01*
G01X307088Y1009860D02*
Y1001916D01*
G02X306923Y1001022I-2500J-1D01*
G01X305843Y998204D01*
G03X305678Y997310I2335J-893D01*
G01Y980098D01*
G03X306148Y979158I1140J-18D01*
G02X306618Y978218I-670J-923D01*
G01Y977018D01*
G02X306148Y976078I-1140J-18D01*
G03X305678Y975138I670J-923D01*
G01Y973938D01*
G03X306148Y972998I1140J-18D01*
G02X306618Y972058I-670J-923D01*
G01Y970858D01*
G02X306148Y969918I-1140J-18D01*
G03X305678Y968978I670J-923D01*
G01Y948978D01*
G03X306148Y948038I1140J-18D01*
G02X306618Y947098I-670J-923D01*
G01Y945898D01*
G02X306148Y944958I-1140J-18D01*
G03X305678Y944018I670J-923D01*
G01Y942818D01*
G03X306148Y941878I1140J-18D01*
G02X306618Y940938I-670J-923D01*
G01Y939738D01*
G02X306148Y938798I-1140J-18D01*
G03X305678Y937858I670J-923D01*
G01Y936658D01*
G03X306148Y935718I1140J-18D01*
G02X306618Y934778I-670J-923D01*
G01Y933578D01*
G02X306148Y932638I-1140J-18D01*
G03X305678Y931698I670J-923D01*
G01Y907802D01*
G03X306148Y906862I1140J-18D01*
G02X306618Y905922I-670J-922D01*
G01Y904722D01*
G02X306148Y903782I-1140J-18D01*
G03X305678Y902842I670J-922D01*
G01Y901642D01*
G03X306148Y900702I1140J-18D01*
G02X306618Y899762I-670J-922D01*
G01Y898562D01*
G02X306148Y897622I-1140J-18D01*
G03X305678Y896682I670J-922D01*
G01Y872399D01*
G03X307500Y868000I6221J0D01*
G01X340500Y835000D01*
G02X343000Y828963I-6037J-6036D01*
G01Y684336D01*
G03X346027Y677028I10335J0D01*
G01X406555Y616500D01*
G02X410198Y607705I-8796J-8795D01*
G01Y452020D01*
G03X411273Y449425I3670J0D01*
G01X418421Y442277D01*
G02X419923Y438648I-3628J-3627D01*
G01Y433191D01*
G03X421060Y430446I3882J0D01*
G02X422785Y426282I-4165J-4165D01*
G01Y411743D01*
G03X422933Y411002I1929J0D01*
G01X423011Y410814D01*
X423091Y410623D01*
X423093Y410620D01*
G03X423175Y410496I356J146D01*
G02X424605Y408859I-11412J-11412D01*
G01X331040Y152601D02*
Y152169D01*
G02X330271Y151400I-769J0D01*
G01X327429D01*
G02X326422Y152407I0J1007D01*
G01Y152507D01*
G01X330929Y148600D02*
Y149250D01*
G03X330129Y150050I-800J0D01*
G01X327464D01*
G03X326422Y149008I0J-1042D01*
G01Y148944D01*
G01X317248Y156000D02*
X315978Y154730D01*
G03X315800Y154300I430J-430D01*
G01Y146650D01*
G03X316800Y145650I1000J0D01*
G01X318386D01*
G03X318669Y145767I0J401D01*
G01X319800Y146898D01*
G01X322833Y1009860D02*
G02X322993Y1009474I-386J-386D01*
G01Y1001416D01*
G02X322286Y999708I-2417J0D01*
G03X321578Y997999I1709J-1709D01*
G01Y993600D01*
G02X319598Y988820I-6760J0D01*
G01X318639Y987861D01*
G03X317500Y985111I2750J-2750D01*
G01Y978208D01*
G03X317970Y977268I1140J-18D01*
G02X318440Y976328I-670J-923D01*
G01Y975128D01*
G02X317970Y974188I-1140J-18D01*
G03X317500Y973248I670J-923D01*
G01Y972048D01*
G03X317970Y971108I1140J-18D01*
G02X318440Y970168I-670J-923D01*
G01Y968968D01*
G02X317970Y968028I-1140J-18D01*
G03X317500Y967088I670J-923D01*
G01Y965888D01*
G03X317970Y964948I1140J-18D01*
G02X318440Y964008I-670J-923D01*
G01Y962808D01*
G02X317970Y961868I-1140J-18D01*
G03X317500Y960928I670J-923D01*
G01Y940928D01*
G03X317970Y939988I1140J-18D01*
G02X318440Y939048I-670J-923D01*
G01Y937848D01*
G02X317970Y936908I-1140J-18D01*
G03X317500Y935968I670J-923D01*
G01Y934768D01*
G03X317970Y933828I1140J-18D01*
G02X318440Y932888I-670J-923D01*
G01Y931688D01*
G02X317970Y930748I-1140J-18D01*
G03X317500Y929808I670J-923D01*
G01Y928608D01*
G03X317970Y927668I1140J-18D01*
G02X318440Y926728I-670J-923D01*
G01Y925528D01*
G02X317970Y924588I-1140J-18D01*
G03X317500Y923648I670J-923D01*
G01Y903648D01*
G03X317970Y902708I1140J-18D01*
G02X318440Y901768I-670J-923D01*
G01Y900568D01*
G02X317970Y899628I-1140J-18D01*
G03X317500Y898688I670J-923D01*
G01Y870968D01*
G03X318955Y867455I4968J0D01*
G01X346955Y839455D01*
G02X350000Y832102I-7353J-7352D01*
G01Y691487D01*
G03X352632Y685133I8986J0D01*
G01X411610Y626155D01*
G02X418555Y609388I-16768J-16767D01*
G01Y454200D01*
G03X421871Y446193I11323J-1D01*
G01X422360Y445705D01*
X423310Y444755D01*
G02X426823Y436272I-8483J-8482D01*
G01Y416054D01*
G03X427112Y415358I986J2D01*
G01Y415357D01*
G02X428192Y412751I-2607J-2607D01*
G01Y409209D01*
G03X428542Y408859I350J0D01*
G01X318898Y1009860D02*
G03X318813Y1009655I205J-205D01*
G01Y1001066D01*
G03X319520Y999358I2417J0D01*
G02X320228Y997649I-1709J-1709D01*
G01Y993600D01*
G02X318643Y989775I-5410J1D01*
G01X317684Y988816D01*
G03X316150Y985110I3705J-3704D01*
G01Y870968D01*
G03X318000Y866500I6318J-1D01*
G01X346000Y838500D01*
G02X348650Y832102I-6398J-6398D01*
G01Y691486D01*
G03X351677Y684178I10336J0D01*
G01X410655Y625200D01*
G02X417205Y609387I-15813J-15813D01*
G01Y454200D01*
X417204D01*
G03X420916Y445237I12674J-1D01*
G01X421406Y444749D01*
X422355Y443800D01*
G02X425473Y436272I-7528J-7528D01*
G01Y416054D01*
G03X426156Y414403I2337J0D01*
G01X426157Y414402D01*
G02X426842Y412750I-1652J-1653D01*
G01Y408704D01*
G03X427450Y407235I2077J-1D01*
G01X428240Y406445D01*
G02X428533Y405896I-756J-756D01*
G02X428542Y405809I-436J-89D01*
G01Y404922D01*
G01X338583Y1009860D02*
Y1002220D01*
G02X337936Y1000658I-2209J0D01*
G03X337288Y999094I1563J-1564D01*
G01Y987019D01*
G02X335532Y982778I-5997J-1D01*
G01X332819Y980065D01*
G03X329256Y970324I11535J-9741D01*
G01Y967959D01*
G03X329726Y967019I1140J-18D01*
G02X330196Y966079I-670J-922D01*
G01Y964879D01*
G02X329726Y963939I-1140J-18D01*
G03X329256Y962999I670J-922D01*
G01Y961799D01*
G03X329726Y960859I1140J-18D01*
G02X330196Y959919I-670J-922D01*
G01Y958719D01*
G02X329726Y957779I-1140J-18D01*
G03X329256Y956839I670J-922D01*
G01Y955639D01*
G03X329726Y954699I1140J-18D01*
G02X330196Y953759I-670J-922D01*
G01Y952559D01*
G02X329726Y951619I-1140J-18D01*
G03X329256Y950679I670J-922D01*
G01Y949479D01*
G03X329726Y948539I1140J-18D01*
G02X330196Y947599I-670J-922D01*
G01Y946399D01*
G02X329726Y945459I-1140J-18D01*
G03X329256Y944519I670J-922D01*
G01Y924519D01*
G03X329726Y923579I1140J-18D01*
G02X330196Y922639I-670J-922D01*
G01Y921439D01*
G02X329726Y920499I-1140J-18D01*
G03X329256Y919559I670J-922D01*
G01Y918359D01*
G03X329726Y917419I1140J-18D01*
G02X330196Y916479I-670J-922D01*
G01Y915279D01*
G02X329726Y914339I-1140J-18D01*
G03X329256Y913399I670J-922D01*
G01Y912199D01*
G03X329726Y911259I1140J-18D01*
G02X330196Y910319I-670J-922D01*
G01Y909119D01*
G02X329726Y908179I-1140J-18D01*
G03X329256Y907239I670J-922D01*
G01Y873428D01*
G03X331154Y868846I6480J0D01*
G01X354319Y845681D01*
G02X357500Y838000I-7681J-7680D01*
G01Y696129D01*
G03X360027Y690028I8628J0D01*
G01X421555Y628500D01*
G02X426273Y617107I-11392J-11391D01*
G01Y452340D01*
G03X427190Y450126I3131J0D01*
G01X428991Y448325D01*
G02X429723Y446557I-1769J-1768D01*
G01Y423368D01*
G03X430455Y421600I2501J0D01*
G01X430841Y421214D01*
G02X431573Y419446I-1769J-1768D01*
G01Y416285D01*
G02X431376Y415067I-3850J-2D01*
G01X430882Y413585D01*
Y413584D01*
G03X430848Y413463I1088J-371D01*
G01X430801Y413243D01*
G03X430792Y413160I391J-84D01*
G01Y411899D01*
G03X431117Y410898I2488J255D01*
G01X431511Y410387D01*
X431568D01*
X432261Y409694D01*
G02X432479Y409168I-527J-527D01*
G01Y408859D01*
G01X334643Y1009860D02*
Y1002025D01*
G03X335290Y1000462I2211J0D01*
G02X335938Y998898I-1563J-1564D01*
G01Y987019D01*
G02X334577Y983733I-4647J0D01*
G01X331786Y980942D01*
Y980936D01*
G03X327906Y970323I12568J-10611D01*
G01Y873427D01*
G03X330199Y867891I7830J0D01*
G01X353364Y844726D01*
G02X356150Y838000I-6726J-6726D01*
G01Y696130D01*
G03X359072Y689073I9978J-2D01*
G01X420600Y627545D01*
G02X424923Y617108I-10437J-10437D01*
G01Y452341D01*
G03X426235Y449171I4481J-2D01*
G01X426234Y449170D01*
X428035Y447370D01*
G02X428373Y446557I-812J-815D01*
G01Y423368D01*
G03X429500Y420645I3851J-1D01*
G01X429885Y420259D01*
G02X430223Y419446I-812J-815D01*
G01Y416284D01*
X430222D01*
G02X430095Y415494I-2499J-3D01*
G01X429601Y414013D01*
G03X429528Y413747I2371J-794D01*
G01X429457Y413416D01*
G03X429442Y413277I645J-140D01*
G01Y411522D01*
G03X429665Y410573I2131J0D01*
G01X429835Y410230D01*
G02X430242Y409248I-981J-982D01*
G01Y408539D01*
G03X430974Y406771I2501J0D01*
G01X432236Y405509D01*
G02X432479Y404922I-587J-587D01*
G01X350393Y1009860D02*
Y1001794D01*
G03X350612Y1001267I746J1D01*
G01X350700Y1001179D01*
G03X351001Y1000977I653J648D01*
G01X351068Y1000949D01*
G02X351249Y1000829I-210J-514D01*
G01X351328Y1000750D01*
G02X351688Y999881I-869J-869D01*
G01Y970189D01*
G02X349023Y963755I-9099J0D01*
G01X347889Y962621D01*
G03X343656Y952400I10222J-10220D01*
G01Y866952D01*
G03X345500Y862500I6297J0D01*
G01X362500Y845500D01*
G02X364650Y840309I-5191J-5191D01*
G01Y702499D01*
G03X367127Y696518I8460J0D01*
G01X424100Y639545D01*
G02X431673Y621262I-18283J-18283D01*
G01Y425852D01*
G03X432768Y423207I3740J-1D01*
G02X433073Y422472I-735J-736D01*
G01Y418076D01*
G03X433303Y416764I3851J-1D01*
G01X434303Y414006D01*
X434304D01*
G02X434373Y413614I-1081J-392D01*
G01Y410160D01*
G03Y409871I2254J-145D01*
G03X434391Y409873I1J76D01*
G01X434373Y408458D01*
G03X435105Y406690I2501J0D01*
G01X436254Y405541D01*
G02X436416Y405151I-390J-391D01*
G01Y404922D01*
G01X354333Y1009860D02*
Y1001110D01*
G02X353686Y1000462I-648J0D01*
G03X353038Y999814I0J-648D01*
G01Y970190D01*
G02X349978Y962800I-10449J-2D01*
G01X348844Y961666D01*
G03X345006Y952400I9266J-9266D01*
G01Y945298D01*
G03X345476Y944358I1140J-18D01*
G02X345946Y943418I-670J-922D01*
G01Y942218D01*
G02X345476Y941278I-1140J-18D01*
G03X345006Y940338I670J-922D01*
G01Y939138D01*
G03X345476Y938198I1140J-18D01*
G02X345946Y937258I-670J-922D01*
G01Y936058D01*
G02X345476Y935118I-1140J-18D01*
G03X345006Y934178I670J-922D01*
G01Y932978D01*
G03X345476Y932038I1140J-18D01*
G02X345946Y931098I-670J-922D01*
G01Y929898D01*
G02X345476Y928958I-1140J-18D01*
G03X345006Y928018I670J-922D01*
G01Y908018D01*
G03X345476Y907078I1140J-18D01*
G02X345946Y906138I-670J-922D01*
G01Y904938D01*
G02X345476Y903998I-1140J-18D01*
G03X345006Y903058I670J-922D01*
G01Y901858D01*
G03X345476Y900918I1140J-18D01*
G02X345946Y899978I-670J-922D01*
G01Y898778D01*
G02X345476Y897838I-1140J-18D01*
G03X345006Y896898I670J-922D01*
G01Y895698D01*
G03X345476Y894758I1140J-18D01*
G02X345946Y893818I-670J-922D01*
G01Y892618D01*
G02X345476Y891678I-1140J-18D01*
G03X345006Y890738I670J-922D01*
G01Y875437D01*
G03X345476Y874497I1140J-18D01*
G02X345946Y873557I-670J-923D01*
G01Y872357D01*
G02X345476Y871417I-1140J-18D01*
G03X345006Y870477I670J-923D01*
G01Y866953D01*
G03X346455Y863455I4947J0D01*
G01X363455Y846455D01*
G02X366000Y840309I-6146J-6145D01*
G01Y702500D01*
G03X368082Y697473I7110J0D01*
G01X425055Y640500D01*
G02X433023Y621262I-19238J-19237D01*
G01Y425852D01*
G03X433723Y424162I2390J0D01*
G02X434423Y422472I-1690J-1690D01*
G01Y418077D01*
G03X434573Y417225I2500J1D01*
G01X435573Y414467D01*
G02X435723Y413615I-2350J-853D01*
G01Y410160D01*
G03X435891Y409636I901J0D01*
G01X435940Y409567D01*
G03X436069Y409415I963J687D01*
G01X436341Y409143D01*
G02X436416Y408964I-178J-180D01*
G01Y408859D01*
G01X385828Y1009860D02*
Y1002134D01*
G02X385203Y1000625I-2134J0D01*
G03X384578Y999116I1509J-1509D01*
G01Y994437D01*
G02X382909Y990408I-5698J0D01*
G03X381911Y988000I2408J-2409D01*
G01Y982499D01*
G02X380499Y979089I-4824J0D01*
G01X374922Y973512D01*
G03X374589Y972515I793J-819D01*
G02X374257Y971518I-1126J-179D01*
G01X373408Y970669D01*
G02X372411Y970337I-818J794D01*
G03X371414Y970004I-178J-1126D01*
G01X356955Y955545D01*
G03X354768Y950265I5280J-5280D01*
G01Y947488D01*
G03X355238Y946548I1140J-17D01*
G02X355708Y945608I-670J-922D01*
G01Y944408D01*
G02X355238Y943468I-1140J-17D01*
G03X354768Y942528I670J-922D01*
G01Y924766D01*
X355238Y923861D01*
G02X355708Y922921I-670J-922D01*
G01Y921721D01*
G02X355238Y920781I-1140J-18D01*
G01X354768Y919876D01*
Y918606D01*
X355238Y917701D01*
G02X355708Y916761I-670J-922D01*
G01Y915561D01*
G02X355238Y914621I-1140J-18D01*
G01X354768Y913716D01*
Y912446D01*
X355238Y911541D01*
G02X355708Y910601I-670J-922D01*
G01Y909401D01*
G02X355238Y908461I-1140J-18D01*
G01X354768Y907556D01*
Y906286D01*
X355238Y905381D01*
G02X355708Y904441I-670J-922D01*
G01Y903241D01*
G02X355238Y902301I-1140J-18D01*
G01X354768Y901396D01*
Y881326D01*
X355238Y880421D01*
G02X355708Y879481I-670J-922D01*
G01Y878281D01*
G02X355238Y877341I-1140J-18D01*
G01X354768Y876436D01*
Y875166D01*
X355238Y874261D01*
G02X355708Y873321I-670J-922D01*
G01Y872121D01*
G02X355238Y871181I-1140J-18D01*
G01X354768Y870276D01*
Y869500D01*
G03X356725Y864774I6683J-1D01*
G01X358000Y863500D01*
X370000Y851500D01*
G02X373500Y843050I-8451J-8450D01*
G01Y709629D01*
G03X376027Y703528I8628J0D01*
G01X432479Y647076D01*
G02X441055Y626370I-20706J-20705D01*
G01Y455402D01*
G02X439928Y452679I-3851J-1D01*
G01X439731Y452482D01*
G02X439463Y452249I-1770J1766D01*
G01X439281Y452113D01*
G03X439145Y452003I1503J-1998D01*
G01X438594Y451525D01*
G03X437735Y449642I1634J-1883D01*
G01Y423074D01*
G03X438467Y421306I2501J0D01*
G01X439096Y420677D01*
G02X439828Y418909I-1769J-1768D01*
G01Y415854D01*
G02X439290Y414555I-1837J0D01*
G03X438753Y413258I1298J-1297D01*
G01Y412033D01*
G03X438917Y411639I558J1D01*
G01X439080Y411475D01*
X439603Y410952D01*
G02X440257Y409805I-1768J-1768D01*
G01X440312Y409591D01*
G02X440353Y409270I-1249J-323D01*
G01Y408859D01*
G01X381888Y1009860D02*
Y1001477D01*
G03X382500Y1000000I2089J0D01*
G02X383228Y998242I-1758J-1758D01*
G01Y994438D01*
G02X381954Y991363I-4348J0D01*
G03X380561Y988001I3363J-3363D01*
G01Y982500D01*
G02X379543Y980044I-3474J1D01*
G01X379250Y979750D01*
X356000Y956500D01*
G03X353418Y950265I6235J-6234D01*
G01Y869500D01*
X353417D01*
G03X355770Y863819I8034J0D01*
G01X357045Y862545D01*
X369045Y850545D01*
G02X372150Y843049I-7496J-7496D01*
G01Y709630D01*
G03X375072Y702573I9978J-2D01*
G01X431524Y646121D01*
G02X439705Y626370I-19751J-19751D01*
G01Y455401D01*
X439704Y455402D01*
G02X438972Y453634I-2501J0D01*
G01X438774Y453436D01*
G02X438652Y453330I-813J813D01*
G01X438471Y453194D01*
G03X438260Y453023I2318J-3075D01*
G01X437709Y452545D01*
G03X436385Y449642I2521J-2903D01*
G01Y423074D01*
G03X437512Y420351I3851J-1D01*
G01X438141Y419722D01*
X438140D01*
G02X438478Y418909I-812J-815D01*
G01Y415854D01*
G02X438334Y415510I-487J2D01*
G03X437403Y413258I2254J-2250D01*
G01Y411591D01*
G03X437707Y410857I1038J0D01*
G01X438011Y410553D01*
G02X438036Y410524I-1881J-1647D01*
G02X438434Y409867I-1914J-1609D01*
G02X438623Y408915I-2312J-954D01*
G01Y408308D01*
G03X439355Y406540I2501J0D01*
G01X440134Y405761D01*
G02X440353Y405232I-529J-529D01*
G01Y404922D01*
G01X376656Y133872D02*
X376671Y133886D01*
G01X375756Y134882D02*
G03X376187Y135611I-1208J1206D01*
G03X376256Y136089I-1638J480D01*
G01Y136183D01*
G03X376213Y136564I-1742J-4D01*
G03X375968Y137141I-1700J-381D01*
G03X375745Y137416I-1458J-954D01*
G01X375165Y137995D01*
X375163Y137996D01*
X374872Y138289D01*
G02X374607Y138929I640J640D01*
G01Y139383D01*
X374600Y139390D01*
G01X378896Y131533D02*
G03X379181Y132221I-688J688D01*
G01X377520Y132067D02*
G03X378011Y132873I-1415J1415D01*
G03X378106Y133482I-1906J609D01*
G01Y134663D01*
X378181Y134738D01*
Y137704D01*
G01X437008Y1009860D02*
Y1003026D01*
G03X438184Y1000187I4015J0D01*
G02X438650Y999062I-1125J-1125D01*
G01Y911440D01*
G02X433431Y898841I-17817J0D01*
G01X404298Y869708D01*
G03X395928Y849500I20208J-20207D01*
G01Y733499D01*
G03X398460Y727385I8648J0D01*
G01X431190Y694655D01*
G02X446705Y657199I-37455J-37456D01*
G01Y452388D01*
G02X443355Y444300I-11438J0D01*
G03X439555Y435124I9174J-9174D01*
G01Y425286D01*
G03X440682Y422563I3851J-1D01*
G01X440917Y422327D01*
G02X441255Y421514I-812J-815D01*
G01Y415586D01*
G03X441536Y414143I3850J1D01*
G01X441711Y413709D01*
X441887Y413274D01*
G02X441953Y412938I-829J-337D01*
G01Y408295D01*
G03X442685Y406527I2501J0D01*
G01X444290Y404922D01*
G01X440943Y1009860D02*
Y1001109D01*
G02X440297Y1000463I-646J0D01*
G01X440000Y1000166D01*
Y911439D01*
G02X434386Y897886I-19167J0D01*
G01X405253Y868753D01*
G03X397278Y849500I19253J-19253D01*
G01Y836328D01*
G03X397748Y835388I1140J-18D01*
G02X398218Y834448I-670J-922D01*
G01Y833248D01*
G02X397748Y832308I-1140J-18D01*
G03X397278Y831368I670J-922D01*
G01Y830168D01*
G03X397748Y829228I1140J-18D01*
G02X398218Y828288I-670J-922D01*
G01Y827088D01*
G02X397748Y826148I-1140J-18D01*
G03X397278Y825208I670J-922D01*
G01Y824008D01*
G03X397748Y823068I1140J-18D01*
G02X398218Y822128I-670J-922D01*
G01Y820928D01*
G02X397748Y819988I-1140J-18D01*
G03X397278Y819048I670J-922D01*
G01Y817848D01*
G03X397748Y816908I1140J-18D01*
G02X398218Y815968I-670J-922D01*
G01Y814768D01*
G02X397748Y813828I-1140J-18D01*
G03X397278Y812888I670J-922D01*
G01Y800525D01*
G03X397748Y799585I1140J-18D01*
G02X398218Y798645I-670J-922D01*
G01Y797445D01*
G02X397748Y796505I-1140J-18D01*
G03X397278Y795565I670J-922D01*
G01Y794365D01*
G03X397748Y793425I1140J-18D01*
G02X398218Y792485I-670J-922D01*
G01Y791285D01*
G02X397748Y790345I-1140J-18D01*
G03X397278Y789405I670J-922D01*
G01Y788205D01*
G03X397748Y787265I1140J-18D01*
G02X398218Y786325I-670J-922D01*
G01Y785125D01*
G02X397748Y784185I-1140J-18D01*
G03X397278Y783245I670J-922D01*
G01Y733500D01*
G03X399416Y728340I7298J1D01*
G01X399877Y727878D01*
X432145Y695610D01*
G02X448055Y657198I-38410J-38410D01*
G01Y452388D01*
G02X444310Y443345I-12788J-1D01*
G03X440905Y435125I8219J-8220D01*
G01Y425286D01*
G03X441637Y423518I2501J0D01*
G01X441873Y423282D01*
G02X442605Y421514I-1769J-1768D01*
G01Y415587D01*
G03X442788Y414649I2500J1D01*
G01X443139Y413781D01*
G02X443303Y412939I-2081J-842D01*
G01Y410205D01*
G03X443432Y409555I1696J-1D01*
G01X443572Y409218D01*
G03X443900Y408890I560J232D01*
G03X444054Y408859I154J369D01*
G01X444290D01*
G01X425278Y808750D02*
G02X426971Y807322I-2024J-4117D01*
G02X427878Y804520I-3873J-2802D01*
G01Y783959D01*
G03X429727Y779492I6323J1D01*
G01X429802Y779416D01*
X449103Y760115D01*
G02X453500Y749500I-10615J-10615D01*
G01Y448327D01*
G02X452965Y447035I-1827J0D01*
G01X451992Y446062D01*
X449340Y443411D01*
G03X446022Y435400I8011J-8011D01*
G01X446023D01*
Y416440D01*
G02X445703Y415198I-2570J0D01*
G03X445645Y415096I3319J-1955D01*
G03X445173Y413247I3380J-1847D01*
G01Y411868D01*
G03X445954Y409542I3851J-1D01*
G02X446411Y408555I-837J-987D01*
G03X446472Y408305I2456J467D01*
G03X446691Y407789I2397J713D01*
G01X447549Y406271D01*
G02X447681Y406001I-2176J-1231D01*
G01X448059Y405090D01*
X448227Y404922D01*
G01X425278Y805250D02*
Y802000D01*
G01Y812250D02*
X425594Y812381D01*
G02X425825Y812427I231J-557D01*
G03X426303Y812625I0J676D01*
G01X427899Y814221D01*
G03X428133Y814786I-565J565D01*
G01Y816024D01*
G02X428367Y816589I799J0D01*
G01X434627Y822849D01*
X435306Y823530D01*
G02X438260Y824753I2953J-2953D01*
G01Y824752D01*
G03X438721Y824943I0J652D01*
G01X447522Y833744D01*
G03X447713Y834205I-461J461D01*
G01Y836029D01*
G03X447586Y836335I-432J0D01*
G01X447531Y836390D01*
G02X447404Y836696I305J306D01*
G01Y839000D01*
G01X431778Y808750D02*
X430451Y807424D01*
G03X429227Y804470I2954J-2954D01*
G01X429228D01*
Y783960D01*
G03X430685Y780444I4973J1D01*
G01X430763Y780365D01*
X450058Y761070D01*
G02X454850Y749501I-11570J-11569D01*
G01Y739223D01*
G03X455320Y738283I1140J-18D01*
G02X455790Y737343I-670J-922D01*
G01Y736143D01*
G02X455320Y735203I-1140J-18D01*
G03X454850Y734263I670J-922D01*
G01Y733063D01*
G03X455320Y732123I1140J-18D01*
G02X455790Y731183I-670J-922D01*
G01Y729983D01*
G02X455320Y729043I-1140J-18D01*
G03X454850Y728103I670J-922D01*
G01Y726903D01*
G03X455320Y725963I1140J-18D01*
G02X455790Y725023I-670J-922D01*
G01Y723823D01*
G02X455320Y722883I-1140J-18D01*
G03X454850Y721943I670J-922D01*
G01Y687843D01*
G03X455320Y686903I1140J-18D01*
G02X455790Y685963I-670J-922D01*
G01Y684763D01*
G02X455320Y683823I-1140J-18D01*
G03X454850Y682883I670J-922D01*
G01Y681683D01*
G03X455320Y680743I1140J-18D01*
G02X455790Y679803I-670J-922D01*
G01Y678603D01*
G02X455320Y677663I-1140J-18D01*
G03X454850Y676723I670J-922D01*
G01Y675523D01*
G03X455320Y674583I1140J-18D01*
G02X455790Y673643I-670J-922D01*
G01Y672443D01*
G02X455320Y671503I-1140J-18D01*
G03X454850Y670563I670J-922D01*
G01Y587445D01*
G03X455320Y586505I1140J-18D01*
G02X455790Y585565I-670J-922D01*
G01Y584365D01*
G02X455320Y583425I-1140J-18D01*
G03X454850Y582485I670J-922D01*
G01Y448327D01*
G02X453920Y446080I-3177J-1D01*
G01X452947Y445107D01*
X450295Y442456D01*
G03X447373Y435400I7056J-7055D01*
G01Y416440D01*
G02X446885Y414545I-3920J-1D01*
G02X446830Y414448I-4232J2335D01*
G03X446523Y413247I2194J-1201D01*
G01Y411867D01*
X446524Y411868D01*
G03X447030Y410357I2501J-3D01*
G01X447031D01*
G03X447254Y410102I1990J1515D01*
G01X447582Y409774D01*
X447586Y409764D01*
G02X447746Y409571I-929J-933D01*
G01X448227Y408859D01*
G01X453309Y839000D02*
Y836696D01*
G02X453182Y836390I-432J0D01*
G01X453127Y836335D01*
G03X453000Y836029I305J-306D01*
G01Y829640D01*
G02X452414Y828226I-2001J1D01*
G01X445183Y820995D01*
X445182D01*
X443419Y819233D01*
G03X441832Y815400I3833J-3832D01*
G01Y805077D01*
G03X442066Y804512I799J0D01*
G01X444266Y802312D01*
G03X444778Y802100I512J512D01*
G01X451341Y839000D02*
Y836696D01*
G03X451468Y836390I432J0D01*
G01X451523Y836335D01*
G02X451650Y836029I-305J-306D01*
G01Y829641D01*
G02X451459Y829181I-651J1D01*
G01X446466Y824189D01*
X444227Y821950D01*
X442464Y820188D01*
G03X440481Y815400I4788J-4788D01*
G01X440482D01*
Y803935D01*
G02X440248Y803370I-799J0D01*
G01X439212Y802334D01*
G02X438647Y802100I-565J565D01*
G01X438278D01*
G01X431778Y805250D02*
Y802000D01*
G01Y812250D02*
X431059D01*
G02X430494Y812484I0J799D01*
G01X429717Y813261D01*
G02X429483Y813826I565J565D01*
G01Y815464D01*
G02X429717Y816029I799J0D01*
G01X435583Y821895D01*
X436262Y822575D01*
G02X438260Y823402I1997J-1998D01*
G03X439676Y823988I1J2002D01*
G01X448477Y832789D01*
G03X449063Y834205I-1416J1415D01*
G01Y836029D01*
G02X449190Y836335I432J0D01*
G01X449245Y836390D01*
G03X449372Y836696I-305J306D01*
G01Y839000D01*
G01X452758Y1009860D02*
Y1001077D01*
G03X453293Y999785I1828J0D01*
G02X453828Y998493I-1293J-1292D01*
G01Y908000D01*
G02X453021Y906053I-2754J1D01*
G01X448024Y901056D01*
X437522Y890555D01*
X435354Y888387D01*
G03X433828Y884700I3688J-3686D01*
G01Y878297D01*
G02X432509Y876093I-2500J-1D01*
G01X432186Y875920D01*
G02X431511Y875750I-676J1259D01*
G01X431278D01*
G01X456693Y1009860D02*
Y1002151D01*
G02X455961Y1000383I-2501J0D01*
G01X455910Y1000332D01*
G03X455178Y998564I1769J-1768D01*
G01Y908000D01*
G02X453976Y905098I-4104J0D01*
G01X436978Y888100D01*
X436309Y887432D01*
G03X435178Y884700I2732J-2731D01*
G01Y878485D01*
G03X435307Y877838I1693J1D01*
G01X435446Y877501D01*
G03X436298Y876461I2145J888D01*
G01X436475Y876342D01*
G03X436913Y876108I1391J2077D01*
G01X437778Y875750D01*
G01Y872250D02*
X437303D01*
G03X437014Y872193I-1J-755D01*
G01X435844Y871708D01*
G03X435528Y871426I247J-595D01*
G03X435478Y871234I344J-192D01*
G01Y868632D01*
X435479Y868631D01*
G03X435713Y868066I799J0D01*
G01X436725Y867053D01*
X437737Y866041D01*
G03X438198Y865850I461J461D01*
G01X443009D01*
G02X444424Y865264I0J-2001D01*
G01X447796Y861892D01*
G02X449068Y858821I-3072J-3071D01*
G01Y855395D01*
G03X449220Y855028I519J0D01*
G02X449372Y854661I-367J-367D01*
G01Y853000D01*
G01X431278Y872250D02*
X431853D01*
G02X432835Y871843I0J-1388D01*
G01X433451Y871227D01*
G02X433667Y870951I-1021J-1021D01*
G02X433748Y870767I-690J-413D01*
G03X433784Y870692I266J82D01*
G01X433807Y870657D01*
G02X433880Y870520I-666J-443D01*
G01X434067Y870068D01*
G02X434119Y869873I-740J-302D01*
G02X434127Y869762I-791J-113D01*
G01X434128D01*
Y868631D01*
G03X434758Y867111I2149J0D01*
G01X435264Y866605D01*
X436782Y865086D01*
G03X438198Y864500I1415J1416D01*
G01X443009D01*
G02X443469Y864309I-1J-651D01*
G01X446841Y860937D01*
G02X447718Y858820I-2117J-2117D01*
G01Y855442D01*
G02X447561Y855063I-536J0D01*
G03X447404Y854684I379J-379D01*
G01Y853000D01*
G01X431278Y883000D02*
Y879250D01*
G01X451341Y853000D02*
Y855304D01*
G02X451468Y855610I432J0D01*
G01X451523Y855665D01*
G03X451650Y855971I-305J306D01*
G01Y861195D01*
G03X450573Y863795I-3677J0D01*
G01X448377Y865991D01*
G02X446928Y869499I3522J3508D01*
G01Y880819D01*
G03X446694Y881384I-799J0D01*
G01X445312Y882766D01*
G03X444747Y883000I-565J-565D01*
G01X444278D01*
G01X437778D02*
Y879250D01*
G01X484253Y1009860D02*
Y1002156D01*
G03X484840Y1000738I2006J0D01*
G02X485428Y999318I-1421J-1420D01*
G01Y940840D01*
G03X490023Y929745I15690J-1D01*
G01X508423Y911345D01*
G02X514296Y897166I-14179J-14179D01*
G01Y676089D01*
G02X512572Y671927I-5886J0D01*
G01X476450Y635805D01*
G03X469705Y619521I16285J-16284D01*
G01Y449386D01*
G02X466830Y442445I-9816J0D01*
G01X457776Y433391D01*
G03X455635Y428221I5172J-5170D01*
G01Y417581D01*
G02X455298Y416768I-1151J1D01*
G01X454040Y415510D01*
G03X452922Y412812I2696J-2698D01*
G03X454039Y410116I3813J1D01*
G01X454331Y409824D01*
G02X454623Y409119I-705J-705D01*
G01Y408428D01*
G03X455355Y406660I2501J0D01*
G01X455580Y406435D01*
G02X456223Y404883I-1552J-1552D01*
G01X488188Y1009860D02*
Y1002773D01*
G02X487944Y1001696I-2499J0D01*
G01X487044Y999810D01*
G03X486803Y998857I2256J-1077D01*
G01X486780Y998391D01*
G03X486778Y998331I1203J-70D01*
G01Y991132D01*
G03X487248Y990192I1140J-18D01*
G02X487718Y989252I-670J-923D01*
G01Y988052D01*
G02X487248Y987112I-1140J-18D01*
G03X486778Y986172I670J-923D01*
G01Y984972D01*
G03X487248Y984032I1140J-18D01*
G02X487718Y983092I-670J-923D01*
G01Y981892D01*
G02X487248Y980952I-1140J-18D01*
G03X486778Y980012I670J-923D01*
G01Y978812D01*
G03X487248Y977872I1140J-18D01*
G02X487718Y976932I-670J-923D01*
G01Y975732D01*
G02X487248Y974792I-1140J-18D01*
G03X486778Y973852I670J-923D01*
G01Y972652D01*
G03X487248Y971712I1140J-18D01*
G02X487718Y970772I-670J-923D01*
G01Y969572D01*
G02X487248Y968632I-1140J-18D01*
G03X486778Y967692I670J-923D01*
G01Y940840D01*
G03X490978Y930700I14340J0D01*
G01X509378Y912300D01*
G02X515646Y897166I-15134J-15133D01*
G01Y852955D01*
G03X516116Y852015I1140J-18D01*
G02X516586Y851075I-670J-922D01*
G01Y849875D01*
G02X516116Y848935I-1140J-18D01*
G03X515646Y847995I670J-922D01*
G01Y846795D01*
G03X516116Y845855I1140J-18D01*
G02X516586Y844915I-670J-922D01*
G01Y843715D01*
G02X516116Y842775I-1140J-18D01*
G03X515646Y841835I670J-922D01*
G01Y840635D01*
G03X516116Y839695I1140J-18D01*
G02X516586Y838755I-670J-922D01*
G01Y837555D01*
G02X516116Y836615I-1140J-18D01*
G03X515646Y835675I670J-922D01*
G01Y676088D01*
G02X513527Y670972I-7236J0D01*
G01X477405Y634850D01*
G03X471055Y619520I15330J-15330D01*
G01Y449386D01*
G02X467785Y441490I-11166J-1D01*
G01X459635Y433340D01*
X458732Y432436D01*
G03X456985Y428220I4216J-4217D01*
G01Y417581D01*
G02X456253Y415813I-2501J0D01*
G01X454995Y414555D01*
G03X454273Y412812I1742J-1743D01*
G03X454994Y411071I2463J0D01*
G01X455286Y410779D01*
G02X455578Y410487I-1514J-1806D01*
G01X455548Y410467D01*
X455849Y410216D01*
G02X456223Y409312I-904J-903D01*
G01Y408783D01*
G01X456278Y808750D02*
G02X457729Y808149I0J-2052D01*
G01X457878Y808000D01*
G02X458703Y806595I-2295J-2292D01*
G02X458715Y806549I-3132J-842D01*
G02X458828Y805706I-3130J-849D01*
G01Y780181D01*
G03X461148Y774580I7922J0D01*
G01X461220Y774508D01*
G02X462673Y771000I-3508J-3508D01*
G01Y451369D01*
G02X461877Y449447I-2718J0D01*
G01X456215Y443785D01*
G03X452705Y435311I8474J-8474D01*
G01Y425770D01*
G02X451808Y423604I-3063J0D01*
G01X450299Y422095D01*
G03X449173Y419372I2726J-2721D01*
G01Y415998D01*
G03X449427Y414794I2965J-3D01*
G03X449527Y414591I2708J1208D01*
G02X449761Y414120I-1683J-1130D01*
G02X449834Y413858I-2167J-745D01*
G02X449873Y413460I-1988J-396D01*
G01Y409738D01*
G03X451644Y405461I6048J-1D01*
G01X452223Y404883D01*
G01X462778Y808750D02*
G03X460577Y807500I0J-2563D01*
G03X460429Y807013I7019J-2399D01*
G03X460178Y805100I7167J-1913D01*
G01Y780182D01*
G03X462103Y775535I6572J0D01*
G01X462175Y775463D01*
G02X464023Y771000I-4463J-4462D01*
G01Y739367D01*
G03X464493Y738427I1140J-18D01*
G02X464963Y737487I-670J-922D01*
G01Y736287D01*
G02X464493Y735347I-1140J-18D01*
G03X464023Y734407I670J-922D01*
G01Y733207D01*
G03X464493Y732267I1140J-18D01*
G02X464963Y731327I-670J-922D01*
G01Y730127D01*
G02X464493Y729187I-1140J-18D01*
G03X464023Y728247I670J-922D01*
G01Y727047D01*
G03X464493Y726107I1140J-18D01*
G02X464963Y725167I-670J-922D01*
G01Y723967D01*
G02X464493Y723027I-1140J-18D01*
G03X464023Y722087I670J-922D01*
G01Y720887D01*
G03X464493Y719947I1140J-18D01*
G02X464963Y719007I-670J-922D01*
G01Y717807D01*
G02X464493Y716867I-1140J-18D01*
G03X464023Y715927I670J-922D01*
G01Y696583D01*
G03X464493Y695643I1140J-18D01*
G02X464963Y694703I-670J-922D01*
G01Y693503D01*
G02X464493Y692563I-1140J-18D01*
G03X464023Y691623I670J-922D01*
G01Y690423D01*
G03X464493Y689483I1140J-18D01*
G02X464963Y688543I-670J-922D01*
G01Y687343D01*
G02X464493Y686403I-1140J-18D01*
G03X464023Y685463I670J-922D01*
G01Y684263D01*
G03X464493Y683323I1140J-18D01*
G02X464963Y682383I-670J-922D01*
G01Y681183D01*
G02X464493Y680243I-1140J-18D01*
G03X464023Y679303I670J-922D01*
G01Y451370D01*
G02X462832Y448492I-4068J-2D01*
G01X457170Y442830D01*
G03X454055Y435311I7519J-7520D01*
G01Y425770D01*
G02X452763Y422649I-4413J-1D01*
G01X452185Y422070D01*
X451255Y421140D01*
G03X450523Y419372I1769J-1768D01*
G01Y415998D01*
G03X450694Y415275I1614J0D01*
G02X451039Y414560I-2849J-1815D01*
G02X451157Y414123I-3195J-1097D01*
G02X451223Y413460I-3312J-664D01*
G01Y411197D01*
G03X452223Y408783I3414J0D01*
G01X456278Y805250D02*
Y802100D01*
G01Y812250D02*
X457900D01*
G03X458700Y813050I0J800D01*
G01Y816493D01*
G02X459200Y817700I1707J0D01*
G03X459524Y818482I-782J782D01*
G01Y836028D01*
G03X459397Y836334I-432J0D01*
G01X459342Y836389D01*
G02X459215Y836695I305J306D01*
G01Y839000D01*
G01X462778Y812250D02*
X461581D01*
G02X460050Y813781I0J1531D01*
G01Y816492D01*
G02X460155Y816745I357J0D01*
G03X460874Y818481I-1737J1736D01*
G01Y836027D01*
G02X461001Y836334I435J0D01*
G01X461057Y836390D01*
G03X461184Y836697I-308J307D01*
G01Y839000D01*
G01X467278Y872250D02*
X466859D01*
G03X466294Y872016I0J-799D01*
G01X464619Y870341D01*
G03X464385Y869776I565J-565D01*
G01Y866212D01*
G02X463413Y863865I-3319J0D01*
G01X462013Y862465D01*
X461812Y862263D01*
G03X460874Y860000I2263J-2264D01*
G01Y855973D01*
G03X461001Y855666I435J0D01*
G01X461057Y855610D01*
G02X461184Y855303I-308J-307D01*
G01Y853000D01*
G01X460778Y872250D02*
X461597D01*
G02X462162Y872016I0J-799D01*
G01X462801Y871377D01*
G02X463035Y870812I-565J-565D01*
G01Y866211D01*
X463034Y866212D01*
G02X462458Y864820I-1968J-1D01*
G01X461056Y863418D01*
X460856Y863217D01*
G03X459524Y860001I3219J-3217D01*
G01Y855972D01*
G02X459397Y855666I-432J0D01*
G01X459342Y855611D01*
G03X459215Y855305I305J-306D01*
G01Y853000D01*
G01X453309D02*
Y855304D01*
G03X453182Y855610I-432J0D01*
G01X453127Y855665D01*
G02X453000Y855971I305J306D01*
G01Y861196D01*
G03X451528Y864750I-5027J0D01*
G01X449333Y866945D01*
G02X448278Y869500I2566J2555D01*
G01Y880919D01*
X448276D01*
X448278Y881019D01*
X448276D01*
X448278Y881069D01*
G02X448512Y881634I799J0D01*
G01X449644Y882766D01*
G02X450209Y883000I565J-565D01*
G01X450778D01*
G01X468503Y1009860D02*
Y1002111D01*
G03X469164Y1000513I2262J0D01*
G01X469165Y1000512D01*
G02X469828Y998913I-1599J-1600D01*
G01Y900013D01*
G02X468023Y895655I-6163J0D01*
G01X465137Y892769D01*
G03X463328Y888400I4370J-4368D01*
G01Y878511D01*
G02X463162Y877680I-2169J1D01*
G01X462805Y876820D01*
G02X462577Y876479I-974J404D01*
G02X462237Y876252I-741J741D01*
G01X461077Y875772D01*
G02X460964Y875750I-112J274D01*
G01X460778D01*
G01Y879250D02*
Y883000D01*
G01X503938Y1009860D02*
Y1001780D01*
G02X503358Y1000380I-1980J0D01*
G03X502778Y998980I1400J-1400D01*
G01Y979873D01*
G03X503248Y978933I1140J-17D01*
G02X503718Y977993I-670J-922D01*
G01Y976793D01*
G02X503248Y975853I-1140J-17D01*
G03X502778Y974913I670J-922D01*
G01Y973713D01*
G03X503248Y972773I1140J-17D01*
G02X503718Y971833I-670J-922D01*
G01Y970633D01*
G02X503248Y969693I-1140J-17D01*
G03X502778Y968753I670J-922D01*
G01Y967553D01*
G03X503248Y966613I1140J-17D01*
G02X503718Y965673I-670J-922D01*
G01Y964473D01*
G02X503248Y963533I-1140J-17D01*
G03X502778Y962593I670J-922D01*
G01Y934843D01*
G03X507301Y923924I15442J0D01*
G01X519151Y912074D01*
G02X523646Y901222I-10853J-10852D01*
G01Y846673D01*
G03X524116Y845733I1140J-18D01*
G02X524586Y844793I-670J-922D01*
G01Y843593D01*
G02X524116Y842653I-1140J-18D01*
G03X523646Y841713I670J-922D01*
G01Y840513D01*
G03X524116Y839573I1140J-18D01*
G02X524586Y838633I-670J-922D01*
G01Y837433D01*
G02X524116Y836493I-1140J-18D01*
G03X523646Y835553I670J-922D01*
G01Y834353D01*
G03X524116Y833413I1140J-18D01*
G02X524586Y832473I-670J-922D01*
G01Y831273D01*
G02X524116Y830333I-1140J-18D01*
G03X523646Y829393I670J-922D01*
G01Y828193D01*
G03X524116Y827253I1140J-18D01*
G02X524586Y826313I-670J-922D01*
G01Y825113D01*
G02X524116Y824173I-1140J-18D01*
G03X523646Y823233I670J-922D01*
G01Y670999D01*
G02X521237Y665183I-8228J1D01*
G01X521029Y664974D01*
X484855Y628800D01*
G03X478055Y612383I16417J-16417D01*
G01Y450211D01*
G02X475514Y444074I-8677J-2D01*
G01X464268Y432827D01*
G03X463536Y431060I1768J-1768D01*
G01Y409924D01*
G03X463977Y408859I1506J0D01*
G01X499998Y1009860D02*
Y1003041D01*
G03X500188Y1002085I2500J0D01*
G01X501238Y999546D01*
G02X501415Y998841I-2310J-955D01*
G02X501428Y998590I-2487J-255D01*
G01Y934842D01*
G03X506346Y922969I16792J1D01*
G01X518196Y911119D01*
G02X522296Y901221I-9898J-9898D01*
G01Y671000D01*
G02X520281Y666137I-6878J1D01*
G01X520072Y665927D01*
X483900Y629755D01*
G03X476705Y612382I17372J-17371D01*
G01Y450210D01*
G02X474559Y445029I-7327J0D01*
G01X463313Y433782D01*
G03X462186Y431061I2723J-2722D01*
G01Y409924D01*
G03Y409300I2857J-312D01*
G01Y408038D01*
G03X462392Y407131I2100J0D01*
G01X462787Y406307D01*
G03X463005Y406000I1009J485D01*
G02X463172Y405816I-1766J-1770D01*
G01X463522Y405388D01*
X463547Y405358D01*
G03X463600Y405299I619J503D01*
G01X463977Y404922D01*
G01X519683Y1009860D02*
Y1001628D01*
G02X519030Y1000053I-2228J1D01*
G01X519029Y1000052D01*
G03X518378Y998478I1577J-1574D01*
G01Y988700D01*
G03X518848Y987760I1140J-18D01*
G02X519318Y986820I-670J-923D01*
G01Y985620D01*
G02X518848Y984680I-1140J-18D01*
G03X518378Y983740I670J-923D01*
G01Y982540D01*
G03X518848Y981600I1140J-18D01*
G02X519318Y980660I-670J-923D01*
G01Y979460D01*
G02X518848Y978520I-1140J-18D01*
G03X518378Y977580I670J-923D01*
G01Y976380D01*
G03X518848Y975440I1140J-18D01*
G02X519318Y974500I-670J-923D01*
G01Y973300D01*
G02X518848Y972360I-1140J-18D01*
G03X518378Y971420I670J-923D01*
G01Y934200D01*
G03X525732Y916446I25108J0D01*
G01X526978Y915200D01*
G02X527994Y914125I-18513J-18514D01*
G02X534646Y896686I-19530J-17438D01*
G01Y884188D01*
G03X535116Y883248I1140J-18D01*
G02X535586Y882308I-670J-922D01*
G01Y881108D01*
G02X535116Y880168I-1140J-18D01*
G03X534646Y879228I670J-922D01*
G01Y878028D01*
G03X535116Y877088I1140J-18D01*
G02X535586Y876148I-670J-922D01*
G01Y874948D01*
G02X535116Y874008I-1140J-18D01*
G03X534646Y873068I670J-922D01*
G01Y871868D01*
G03X535116Y870928I1140J-18D01*
G02X535586Y869988I-670J-922D01*
G01Y868788D01*
G02X535116Y867848I-1140J-18D01*
G03X534646Y866908I670J-922D01*
G01Y865708D01*
G03X535116Y864768I1140J-18D01*
G02X535586Y863828I-670J-922D01*
G01Y862628D01*
G02X535116Y861688I-1140J-18D01*
G03X534646Y860748I670J-922D01*
G01Y670795D01*
G02X532027Y664472I-8943J0D01*
G01X491255Y623700D01*
G03X485023Y608655I15045J-15045D01*
G01Y445928D01*
G02X481597Y437657I-11698J1D01*
G01X471027Y427087D01*
X470677Y426738D01*
G03X469923Y424916I1822J-1821D01*
G02X468627Y421787I-4426J0D01*
G01X467046Y420206D01*
G03X466314Y418438I1769J-1768D01*
G01Y412657D01*
G03X466835Y411127I2502J-2D01*
G03X467046Y410889I1974J1537D01*
G01X467182Y410753D01*
G02X467292Y410634I-1780J-1756D01*
G02X467914Y408985I-1879J-1650D01*
G01Y408859D01*
G01X515748Y1009860D02*
Y1002035D01*
G03X516388Y1000490I2185J0D01*
G02X517028Y998945I-1545J-1545D01*
G01Y934200D01*
G03X524777Y915491I26458J-1D01*
G01X526023Y914245D01*
G02X526986Y913225I-17567J-17550D01*
G02X533296Y896686I-18522J-16540D01*
G01Y670796D01*
G02X531072Y665427I-7593J0D01*
G01X490300Y624655D01*
G03X483673Y608656I16000J-16000D01*
G01Y445929D01*
G02X480642Y438612I-10348J0D01*
G01X470073Y428043D01*
X469722Y427694D01*
G03X468572Y424916I2777J-2777D01*
G02X467672Y422742I-3076J0D01*
G01X466090Y421161D01*
G03X464964Y418438I2726J-2721D01*
G01Y412657D01*
G03X465767Y410302I3852J-1D01*
G02X466091Y409580I-642J-722D01*
G01Y408530D01*
G03X466823Y406762I2501J0D01*
G01X467384Y406201D01*
G02X467914Y404922I-1278J-1279D01*
G01X465121Y839000D02*
Y836697D01*
G02X464994Y836390I-435J0D01*
G01X464938Y836334D01*
G03X464811Y836027I308J-307D01*
G03X465207Y835071I1352J0D01*
G01X471878Y828400D01*
G02X473128Y825382I-3019J-3018D01*
G01Y804681D01*
G03X473362Y804116I799J0D01*
G01X475144Y802334D01*
G03X475709Y802100I565J565D01*
G01X475778D01*
G01X462778Y805250D02*
Y802100D01*
G01X463152Y839000D02*
Y836695D01*
G03X463279Y836389I432J0D01*
G01X463334Y836334D01*
G02X463461Y836028I-305J-306D01*
G01Y836027D01*
G03X464252Y834116I2702J-1D01*
G01X470923Y827445D01*
G02X471778Y825381I-2064J-2064D01*
G01Y804431D01*
G02X471544Y803866I-799J0D01*
G01X470012Y802334D01*
G02X469447Y802100I-565J565D01*
G01X469278D01*
G01X463152Y853000D02*
Y853082D01*
X463428Y853358D01*
Y857299D01*
G02X464735Y860457I4464J2D01*
G01X465478Y861200D01*
X465477D01*
X474299Y870022D01*
X474582Y870304D01*
X474850Y870572D01*
G03X476278Y874019I-3446J3447D01*
G01Y881069D01*
G03X476044Y881634I-799J0D01*
G01X474912Y882766D01*
G03X474347Y883000I-565J-565D01*
G01X473778D01*
G01X465121Y853000D02*
X464922Y853199D01*
G02X464778Y853546I346J347D01*
G01Y857300D01*
G02X465690Y859502I3114J0D01*
G01X475805Y869617D01*
G03X477628Y874018I-4401J4401D01*
G01Y880719D01*
G02X477862Y881284I799J0D01*
G01X479344Y882766D01*
G02X479909Y883000I565J-565D01*
G01X480278D01*
G01X472443Y1009860D02*
Y1001659D01*
G02X471810Y1000132I-2158J0D01*
G03X471178Y998606I1526J-1526D01*
G01Y900013D01*
G02X468978Y894700I-7513J-1D01*
G01X466092Y891814D01*
G03X464678Y888400I3414J-3414D01*
G01Y878529D01*
G03X464846Y877684I2209J0D01*
G01X465133Y876990D01*
G03X465468Y876490I1426J593D01*
G03X465969Y876156I1090J1092D01*
G01X466875Y875780D01*
G03X467027Y875750I152J368D01*
G01X467278D01*
G01Y879250D02*
Y883000D01*
G01X491257Y315952D02*
X491586Y316281D01*
G03X492505Y318500I-2219J2219D01*
G01Y319800D01*
G03X491911Y321234I-2028J0D01*
G01X489250Y323895D01*
X489192Y323954D01*
G03X488355Y324300I-836J-837D01*
G01X487455D01*
G02X484190Y325653I1J4618D01*
G01X483662Y326180D01*
G01X484000Y322000D02*
Y318709D01*
G02X483955Y318600I-154J0D01*
G01X495103Y315952D02*
X494774Y316281D01*
G02X493855Y318500I2219J2219D01*
G01Y319800D01*
G03X492866Y322189I-3378J1D01*
G01X490209Y324846D01*
X490063Y324993D01*
G03X488468Y325653I-1594J-1595D01*
G02X488123Y325744I86J1025D01*
G02X487828Y325951I434J933D01*
G01X487599Y326180D01*
G01X487155Y321900D02*
X487067D01*
G03X486705Y321750I0J-512D01*
G03X486555Y321388I362J-362D01*
G01Y319289D01*
G03X486755Y318806I683J0D01*
G03X487238Y318606I483J483D01*
G01X487612D01*
G01X487500Y333833D02*
G02X488579Y333386I0J-1526D01*
G01X489589Y332376D01*
G03X490255Y332100I666J666D01*
G01X490855D01*
G02X493244Y331111I1J-3378D01*
G01X494355Y330000D01*
G03X495562Y329500I1207J1207D01*
G01X507755D01*
G02X510855Y326400I0J-3100D01*
G01Y321145D01*
X512000Y320000D01*
G01X483662Y334054D02*
X484808Y332908D01*
G03X487000Y332000I2192J2192D01*
G01X487882D01*
G02X488177Y331878I0J-417D01*
G01X488634Y331421D01*
G03X490255Y330750I1620J1621D01*
G01X490855D01*
G02X492289Y330156I0J-2028D01*
G01X493400Y329045D01*
G03X495561Y328150I2161J2162D01*
G01X507755D01*
G02X509505Y326400I0J-1750D01*
G01Y321005D01*
X508500Y320000D01*
G01X487599Y330117D02*
X488211Y329503D01*
X488217Y329498D01*
G03X488455Y329400I237J238D01*
G01X488656D01*
G02X490713Y328552I0J-2919D01*
G01X493434Y325831D01*
X494892Y325200D01*
X500900D01*
G02X503100Y323000I0J-2200D01*
G01Y315800D01*
G03X504453Y314200I1623J0D01*
G01X500607D02*
X501285Y314879D01*
G03X501750Y316000I-1121J1122D01*
G01Y323000D01*
G03X500900Y323850I-850J0D01*
G01X494612D01*
X492661Y324694D01*
X489805Y327550D01*
X489764Y327590D01*
G03X488655Y328050I-1110J-1109D01*
G01X486382D01*
G02X485267Y328512I0J1577D01*
G01X483662Y330117D01*
G01X570868Y1009860D02*
Y1001834D01*
G03X571450Y1000427I1989J-1D01*
G01X571567Y1000311D01*
G02X572033Y999186I-1123J-1124D01*
G01Y644754D01*
G02X570045Y639955I-6787J0D01*
G01X510264Y580174D01*
G03X507500Y573500I6674J-6673D01*
G01Y453999D01*
G03X510679Y446323I10857J0D01*
G01X526751Y430251D01*
G02X529205Y424327I-5924J-5924D01*
G01Y390300D01*
G02X527724Y386724I-5058J0D01*
G01X509083Y368083D01*
G02X506500Y367013I-2583J2583D01*
G01X505475D01*
G03X503453Y366666I0J-6065D01*
G03X501187Y365237I2022J-5718D01*
G01X496316Y360366D01*
G02X494225Y359500I-2091J2091D01*
G01X487441D01*
G03X485673Y358768I0J-2501D01*
G01X484906Y358001D01*
G02X484121Y357676I-784J784D01*
G01X483662D01*
G01X574803Y1009860D02*
Y1002889D01*
G02X574613Y1001933I-2500J0D01*
G01X574400Y1001418D01*
G03X573383Y996100I13396J-5318D01*
G01Y644753D01*
G02X571000Y639000I-8137J1D01*
G01X511219Y579219D01*
G03X508850Y573500I5719J-5719D01*
G01Y558283D01*
G03X509320Y557343I1140J-18D01*
G02X509790Y556403I-670J-922D01*
G01Y555203D01*
G02X509320Y554263I-1140J-18D01*
G03X508850Y553323I670J-922D01*
G01Y490050D01*
G03X509320Y489110I1140J-18D01*
G02X509790Y488170I-670J-923D01*
G01Y486970D01*
G02X509320Y486030I-1140J-18D01*
G03X508850Y485090I670J-923D01*
G01Y483890D01*
G03X509320Y482950I1140J-18D01*
G02X509790Y482010I-670J-923D01*
G01Y480810D01*
G02X509320Y479870I-1140J-18D01*
G03X508850Y478930I670J-923D01*
G01Y477730D01*
G03X509320Y476790I1140J-18D01*
G02X509790Y475850I-670J-923D01*
G01Y474650D01*
G02X509320Y473710I-1140J-18D01*
G03X508850Y472770I670J-923D01*
G01Y454000D01*
G03X511635Y447278I9507J1D01*
G01X512456Y446456D01*
X527706Y431206D01*
G02X530555Y424328I-6879J-6879D01*
G01Y390299D01*
G02X528679Y385769I-6408J0D01*
G01X510038Y367128D01*
G02X506500Y365663I-3537J3538D01*
G01X505476D01*
G03X503903Y365393I0J-4715D01*
G01Y365392D01*
G03X502142Y364282I1571J-4445D01*
G01X497271Y359411D01*
G02X494225Y358150I-3045J3047D01*
G01X489240D01*
G03X488283Y357960I-1J-2500D01*
G01X487599Y357676D01*
G01X555118Y1009860D02*
Y1000922D01*
G03X555500Y1000000I1304J0D01*
G01X555646Y999853D01*
G03X556038Y999592I852J855D01*
G02X556307Y999480I-1J-381D01*
G02X556650Y998652I-828J-828D01*
G01Y980567D01*
G02X556180Y979627I-1140J-18D01*
G03X555710Y978687I670J-922D01*
G01Y977487D01*
G03X556180Y976547I1140J-18D01*
G02X556650Y975607I-670J-922D01*
G01Y640530D01*
X556649Y640531D01*
G02X553521Y632978I-10681J-1D01*
G01X502771Y582228D01*
G03X500500Y576745I5484J-5483D01*
G01Y453289D01*
G03X504977Y442478I15287J-2D01*
G01X504976Y442477D01*
X519476Y427977D01*
X519477Y427978D01*
G02X522455Y420789I-7188J-7189D01*
G01Y389200D01*
G02X521221Y386221I-4213J0D01*
G01X510500Y375500D01*
G02X508100Y374506I-2400J2400D01*
G01X505944D01*
G03X503066Y373314I0J-4071D01*
G01X498393Y368641D01*
G02X496225Y367743I-2168J2168D01*
G01X494026D01*
G03X491230Y366585I0J-3955D01*
G01X489555Y364910D01*
G02X488742Y364573I-814J814D01*
G01X487415D01*
Y364572D01*
G03X486264Y364368I15J-3432D01*
G03X486120Y364314I1133J-3241D01*
G01X486117Y364313D01*
X484941Y363827D01*
G02X483705Y364340I-361J875D01*
G02X483663Y365463I1494J618D01*
G01X559053Y1009860D02*
Y1001835D01*
G02X558500Y1000500I-1888J0D01*
G03X558102Y999874I1207J-1207D01*
G03X558067Y999767I1604J-584D01*
G01Y999766D01*
G03X558005Y999431I1639J-477D01*
G03X558000Y999293I1702J-131D01*
G01Y640531D01*
G02X554476Y632023I-12032J0D01*
G01X503726Y581273D01*
G03X501850Y576744I4529J-4529D01*
G01Y453288D01*
G03X505932Y443433I13937J0D01*
G01X520432Y428933D01*
G02X523805Y420790I-8143J-8143D01*
G01Y389199D01*
G02X522176Y385266I-5563J0D01*
G01X511455Y374545D01*
G02X508100Y373156I-3354J3355D01*
G01X505945D01*
G03X504021Y372359I0J-2721D01*
G01X499348Y367686D01*
G02X496225Y366393I-3122J3123D01*
G01X494027D01*
G03X492185Y365630I0J-2605D01*
G01X490510Y363955D01*
G02X488742Y363223I-1768J1769D01*
G01X487430D01*
G03X487422Y363222I254J-2067D01*
G03X486720Y363097I9J-2082D01*
G03X486633Y363064I695J-1963D01*
G01X484500Y362181D01*
G03X483688Y361639I955J-2310D01*
G01X483662Y361613D01*
G01X586613Y1009860D02*
Y1002101D01*
G03X587345Y1000333I2501J0D01*
G01X587466Y1000212D01*
G02X588198Y998444I-1769J-1768D01*
G01Y993027D01*
G02X587400Y991100I-2725J0D01*
G01X584650Y988350D01*
G03X582428Y982984I5366J-5365D01*
G01Y624000D01*
G02X580546Y619455I-6427J-1D01*
G01X580045Y618955D01*
X538795Y577705D01*
G03X535955Y570847I6858J-6857D01*
G01Y389500D01*
G02X534368Y385668I-5420J0D01*
G01X510400Y361700D01*
G02X507100Y360333I-3300J3300D01*
G01X501902D01*
G03X499512Y359343I1J-3381D01*
G01X498016Y357847D01*
G02X496075Y357043I-1941J1941D01*
G01X491755D01*
Y357044D01*
G03X489434Y356379I-1J-4381D01*
G02X487835Y355760I-1599J1756D01*
G03X486435Y355180I1J-1981D01*
G01X485726Y354471D01*
G02X483958Y353739I-1768J1769D01*
G01X483662D01*
G01X590553Y1009860D02*
Y1001583D01*
G02X590363Y1000626I-2500J-1D01*
G01X590050Y999872D01*
X589669Y998951D01*
G03X589548Y998345I1462J-607D01*
G01Y993027D01*
G02X588355Y990145I-4075J-1D01*
G01X585605Y987395D01*
G03X583778Y982984I4411J-4411D01*
G01Y624000D01*
X583779D01*
G02X581501Y618499I-7778J-1D01*
G01X580999Y617999D01*
X539750Y576750D01*
G03X537305Y570847I5903J-5903D01*
G01Y536201D01*
G03X537775Y535261I1140J-18D01*
G02X538245Y534321I-670J-922D01*
G01Y533121D01*
G02X537775Y532181I-1140J-18D01*
G03X537305Y531241I670J-922D01*
G01Y479494D01*
G03X537775Y478554I1140J-18D01*
G02X538245Y477614I-670J-922D01*
G01Y476414D01*
G02X537775Y475474I-1140J-18D01*
G03X537305Y474534I670J-922D01*
G01Y473334D01*
G03X537775Y472394I1140J-18D01*
G02X538245Y471454I-670J-922D01*
G01Y470254D01*
G02X537775Y469314I-1140J-18D01*
G03X537305Y468374I670J-922D01*
G01Y467174D01*
G03X537775Y466234I1140J-18D01*
G02X538245Y465294I-670J-922D01*
G01Y464094D01*
G02X537775Y463154I-1140J-18D01*
G03X537305Y462214I670J-922D01*
G01Y389499D01*
G02X535323Y384713I-6770J0D01*
G01X511355Y360745D01*
G02X507101Y358983I-4254J4255D01*
G01X501903D01*
G03X500467Y358388I0J-2031D01*
G01X498971Y356892D01*
G02X496075Y355693I-2895J2896D01*
G01X491755D01*
G03X490149Y355233I-1J-3030D01*
G03X489612Y354806I1605J-2570D01*
G01X489391Y354584D01*
X488969Y354162D01*
G02X487948Y353739I-1021J1021D01*
G01X487599D01*
G01X535433Y1009860D02*
Y1002031D01*
G02X534701Y1000263I-2501J0D01*
G01X534581Y1000143D01*
G03X534396Y999866I603J-603D01*
G01X533988Y998881D01*
G03X533838Y998129I1814J-753D01*
G01Y930056D01*
G03X536883Y922705I10396J0D01*
G01X538383Y921205D01*
G02X543146Y909706I-11500J-11499D01*
G01Y669295D01*
G02X540527Y662972I-8943J0D01*
G01X502527Y624972D01*
X500264Y622710D01*
G03X495000Y610000I12710J-12709D01*
G01Y448129D01*
G03X497527Y442028I8628J0D01*
G01X513656Y425899D01*
G02X517055Y417693I-8206J-8206D01*
G01Y387657D01*
G02X515705Y384395I-4611J-2D01*
G01X510755Y379445D01*
G02X507295Y378013I-3458J3459D01*
G01X506031D01*
G03X503747Y377067I0J-3230D01*
G01X500365Y373685D01*
G02X498597Y372953I-1768J1769D01*
G01X488571D01*
G03X486864Y372280I0J-2501D01*
G01X486654Y371937D01*
G03X486545Y371552I627J-385D01*
G01Y370541D01*
G03X487603Y369483I1058J0D01*
G01X531498Y1009860D02*
Y1001233D01*
G03X531868Y1000340I1263J0D01*
G01X531975Y1000199D01*
G03X532196Y999944I1995J1506D01*
G01X532282Y999858D01*
G02X532488Y999362I-495J-496D01*
G01Y930055D01*
G03X535928Y921750I11746J0D01*
G01X537428Y920250D01*
G02X541796Y909705I-10545J-10545D01*
G01Y669296D01*
G02X539572Y663927I-7593J0D01*
G01X501572Y625927D01*
X499309Y623665D01*
G03X493649Y610000I13665J-13665D01*
G01X493650D01*
Y448130D01*
G03X496572Y441073I9978J-2D01*
G01X512701Y424944D01*
G02X515705Y417693I-7251J-7252D01*
G01Y387656D01*
G02X514750Y385350I-3261J0D01*
G01X509800Y380400D01*
G02X507296Y379363I-2504J2504D01*
G01X506032D01*
G03X502792Y378022I-2J-4580D01*
G01X502791D01*
X499410Y374641D01*
G02X498597Y374303I-815J812D01*
G01X488571D01*
G03X485797Y373125I-1J-3852D01*
G01X485503Y372643D01*
G03X485195Y371553I1778J-1091D01*
G01Y371302D01*
G02X484866Y370741I-1243J352D01*
G01X483793Y369668D01*
G03X483683Y369403I264J-265D01*
G01X1148188Y667106D02*
Y666752D01*
X1149750Y665190D01*
Y663293D01*
X1147500Y661043D01*
Y660471D01*
G01X1146588Y666326D02*
Y668368D01*
X1148188Y669968D01*
Y670256D01*
G01X1135130Y661280D02*
X1135139D01*
X1137153Y663294D01*
Y665525D01*
X1135598Y667080D01*
G01X1140304Y721904D02*
Y718896D01*
X1141682Y717518D01*
X1141870D01*
G01X1152745Y741345D02*
X1152025Y742065D01*
Y745585D01*
X1153215Y746775D01*
X1156865D01*
X1157550Y747460D01*
Y748240D01*
X1156615Y749175D01*
X1153215D01*
X1152025Y750365D01*
Y753885D01*
X1153215Y755075D01*
X1153950D01*
X1154850Y755975D01*
Y757540D01*
X1154240Y758150D01*
X1153540D01*
X1152025Y759665D01*
Y763975D01*
X1149400Y766600D01*
Y770279D01*
X1147564Y772115D01*
Y777051D01*
X1145970Y778645D01*
X1144839D01*
X1143234Y780250D01*
X1142323D01*
G01X1156700Y745425D02*
X1157425D01*
X1158900Y746900D01*
Y748800D01*
X1157175Y750525D01*
X1153775D01*
X1153375Y750925D01*
Y753325D01*
X1153775Y753725D01*
X1154510D01*
X1156200Y755415D01*
Y758100D01*
X1154800Y759500D01*
X1154100D01*
X1153375Y760225D01*
Y764535D01*
X1150750Y767160D01*
Y770839D01*
X1148914Y772675D01*
Y777611D01*
X1146530Y779995D01*
X1145399D01*
X1143470Y781924D01*
Y782805D01*
G01X1164000Y660000D02*
X1162344Y661656D01*
Y668221D01*
X1161170Y669395D01*
Y673021D01*
X1160770Y673421D01*
G01X1153118Y665815D02*
X1152896Y666037D01*
Y668665D01*
X1154487Y670256D01*
G01X1152400Y727600D02*
Y727808D01*
X1153547Y728955D01*
X1153697D01*
X1155300Y730558D01*
Y739580D01*
X1155301Y739581D01*
Y740699D01*
X1153375Y742625D01*
Y745025D01*
X1153775Y745425D01*
X1156700D01*
G01X1160000Y734480D02*
X1159280D01*
X1157112Y732312D01*
Y731702D01*
G01X1157500Y739200D02*
X1157700Y739000D01*
Y735800D01*
X1157000Y735100D01*
Y734500D01*
G01X1152745Y741345D02*
X1151900Y740500D01*
G01X1152248Y730404D02*
X1153236D01*
X1153950Y731118D01*
Y740140D01*
X1152745Y741345D01*
G01X1156700Y745425D02*
Y744100D01*
G01X1163600Y777900D02*
X1163186D01*
X1162693Y778393D01*
Y780865D01*
G01X1168465Y779808D02*
X1168292D01*
X1167143Y780957D01*
X1165492D01*
G01X1184446Y707400D02*
X1183459Y706413D01*
X1180360D01*
X1180323Y706450D01*
X1178779D01*
X1177185Y708045D01*
X1176515D01*
G01X1180210Y718150D02*
X1178103Y716043D01*
Y712933D01*
X1176515Y711345D01*
Y711144D01*
G54D65*
X673200Y466000D03*
X1341717Y533012D03*
Y525012D03*
G54D74*
X1376300Y281350D03*
X1380300D03*
G54D38*
X301200Y98500D03*
X309200D03*
X349780Y179800D03*
X365129Y199389D03*
X383200Y901500D03*
Y906000D03*
X407200Y889500D03*
Y893500D03*
Y905500D03*
Y897500D03*
Y909500D03*
Y901500D03*
X428700Y314500D03*
X418223Y326283D03*
X426978Y828500D03*
Y837500D03*
Y842000D03*
Y833000D03*
Y846500D03*
Y851000D03*
Y860000D03*
Y855500D03*
X437083Y145701D03*
X430200Y241000D03*
Y245000D03*
X446740Y118000D03*
X449629Y113500D03*
X451629Y171500D03*
Y184500D03*
Y180000D03*
X468129Y104000D03*
X471129Y122000D03*
X477700Y140000D03*
X474129Y149000D03*
Y153500D03*
X474200Y144500D03*
X474700Y157500D03*
X474200Y162000D03*
X469700Y169000D03*
Y176000D03*
X465700Y286500D03*
X479731Y190291D03*
X491478Y857000D03*
Y852500D03*
Y861500D03*
X511629Y135000D03*
X527629Y129000D03*
X514629Y151000D03*
X780200Y968500D03*
X1010200Y66500D03*
X1039200Y145500D03*
X1063700Y124500D03*
X1081200Y640000D03*
X1088700D03*
X1135538Y688864D03*
X1225700Y722500D03*
X1253700Y641000D03*
Y647000D03*
X1261200D03*
X1253700Y657000D03*
Y651000D03*
Y661000D03*
Y667000D03*
Y675500D03*
Y679500D03*
Y691500D03*
Y695500D03*
Y699500D03*
Y703500D03*
Y707500D03*
Y711500D03*
X1251700Y715500D03*
Y719500D03*
X1259200Y715500D03*
X1344200Y399500D03*
G54D29*
X180118Y729409D03*
Y739409D03*
X200118Y729409D03*
X190118D03*
X200118Y739409D03*
X190118D03*
X210118Y729409D03*
Y739409D03*
X230118Y729409D03*
X220118D03*
X230118Y739409D03*
X220118D03*
X250118Y729409D03*
X240118D03*
X250118Y739409D03*
X240118D03*
X260118Y729409D03*
Y739409D03*
X270118Y729409D03*
Y739409D03*
G54D47*
X357940Y135500D03*
X360140D03*
X354440Y146000D03*
X356640D03*
X355940Y155000D03*
X358140D03*
X355940Y162000D03*
X358140D03*
X378229Y158600D03*
X378189Y164630D03*
X383400Y149500D03*
X385600D03*
X396029Y148500D03*
X380429Y158600D03*
X380389Y164630D03*
X401400Y148500D03*
X403600D03*
X406529Y151600D03*
X408729D03*
X398229Y148500D03*
X433155Y348900D03*
X435355D03*
X441055Y362700D03*
X443255D03*
X441055Y360400D03*
X443255D03*
X437155Y372000D03*
X439355D03*
X437055Y383900D03*
X439255D03*
X437055Y386300D03*
X439255D03*
X451055Y357800D03*
X453255D03*
X477423Y325583D03*
Y327983D03*
X472555Y347300D03*
X474755D03*
X472855Y364900D03*
X475055D03*
X472555Y374800D03*
X474755D03*
X472555Y372500D03*
X474755D03*
X472555Y383800D03*
X474755D03*
X479623Y325583D03*
Y327983D03*
X490455Y371500D03*
X492655D03*
X499255Y344400D03*
X501455D03*
X497455Y380000D03*
X499655D03*
X498955Y393000D03*
X501155D03*
X494955Y405500D03*
X497155D03*
X622640Y417801D03*
X624840D03*
X622640Y413401D03*
X624840D03*
X622640Y431001D03*
X624840D03*
X622640Y426601D03*
X624840D03*
X622640Y422201D03*
X624840D03*
X622640Y435401D03*
X624840D03*
G54D56*
X455278Y846000D03*
G54D84*
G01X276500Y888500D02*
X274500Y886500D01*
Y880258D01*
X274700Y880058D01*
Y866800D01*
X321500Y820000D01*
Y688000D01*
G01X524179Y129000D02*
Y131550D01*
X523129Y132600D01*
G01X517679Y129375D02*
X520904Y132600D01*
X523129D01*
G01X527679Y129000D02*
Y124500D01*
G01X535000Y134750D02*
Y127271D01*
X532229Y124500D01*
X531500D01*
G01X527679D02*
X531500D01*
G01X534750Y148500D02*
X533000Y150250D01*
Y153800D01*
G01X543308Y1009860D02*
Y980370D01*
X544178Y979500D01*
Y973500D01*
G01D02*
Y968250D01*
G01X654600Y447700D02*
X653550Y448750D01*
X651000D01*
G01Y442250D02*
X654600Y445850D01*
Y447700D01*
G01X651000Y448750D02*
X646500D01*
G01X649375Y458750D02*
X651150D01*
X654000Y455900D01*
G01X651000Y452250D02*
X654000Y455250D01*
Y455900D01*
G01X679000Y865050D02*
Y862500D01*
X674610Y858110D01*
Y753580D01*
X681950Y746240D01*
Y616450D01*
X677500Y612000D01*
G01X725000Y452300D02*
Y481758D01*
X730692Y487450D01*
X747050D01*
X748500Y486000D01*
X761500D01*
X763250Y487750D01*
Y532724D01*
X751474Y544500D01*
X727842D01*
X677200Y595142D01*
Y611700D01*
X677500Y612000D01*
G01X773500Y326000D02*
X765500Y334000D01*
X734000D01*
X725000Y343000D01*
Y452300D01*
G01X755000Y727500D02*
Y729500D01*
X749450Y735050D01*
Y804050D01*
X743000Y810500D01*
Y876500D01*
X737290Y882210D01*
Y903000D01*
G01X815900Y564000D02*
X815500Y564400D01*
Y589500D01*
X755000Y650000D01*
Y727500D01*
G01X749500Y974300D02*
Y964500D01*
X760500Y953500D01*
Y866283D01*
G01Y707950D02*
Y866283D01*
G01X826198Y239950D02*
X832000Y234148D01*
Y137500D01*
G01X937000Y489000D02*
X941750Y484250D01*
X947800D01*
X948325Y484775D01*
X1050775D01*
X1074500Y508500D01*
X1089000D01*
G01X1159000Y396500D02*
X1062148D01*
X1061074Y395426D01*
X1060766D01*
G01X1280000Y420500D02*
X1278667Y419167D01*
X1126850D01*
X1105933Y398250D01*
X1104067D01*
X1103317Y399000D01*
X1061200D01*
G01X1089000Y508500D02*
X1090250Y509750D01*
X1207750D01*
X1210000Y507500D01*
G01X1088750Y640000D02*
X1093500D01*
G01X1126000Y627329D02*
X1124471D01*
X1117537Y620395D01*
Y584963D01*
X1161000Y541500D01*
G01X1133200Y633500D02*
X1130742D01*
X1126000Y628758D01*
Y627329D01*
G01X1137500Y652750D02*
X1142000Y648250D01*
Y634500D01*
X1141000Y633500D01*
X1133200D01*
G01X1133000Y657000D02*
X1133925Y657925D01*
Y660075D01*
X1135130Y661280D01*
G01X1121760Y665640D02*
X1124420Y668300D01*
X1129960D01*
X1131885Y670225D01*
X1132395D01*
G01X1118630Y714820D02*
X1120680D01*
X1122319Y713181D01*
G01X1144425Y325500D02*
Y306075D01*
X1197000Y253500D01*
X1244177D01*
X1260677Y237000D01*
G01X1143500Y660500D02*
X1144983Y661983D01*
Y667085D01*
G01X1143500Y655500D02*
X1140228Y658772D01*
Y662272D01*
X1141900Y663944D01*
G01X1141790Y667130D02*
X1144860Y670200D01*
X1145020D01*
G01X1138760Y671560D02*
X1140047Y670273D01*
X1141868D01*
G01X1142900Y705300D02*
X1140826D01*
X1138826Y707300D01*
X1136486D01*
X1136304Y707482D01*
G01X1164000Y397000D02*
X1163500Y396500D01*
X1159000D01*
G01X1197675Y533125D02*
X1193392D01*
X1190492Y530225D01*
X1159725D01*
X1157700Y528200D01*
G01D02*
X1151500Y522000D01*
G01X1164000Y655000D02*
X1161071D01*
X1159098Y656973D01*
Y662500D01*
X1160547Y663949D01*
X1160741D01*
G01X1158780Y670430D02*
Y668212D01*
X1157655Y667087D01*
G01X1163700Y714400D02*
X1166790Y711310D01*
X1166900D01*
X1167103Y711107D01*
G01X1177000Y860000D02*
Y880000D01*
X1175500Y881500D01*
Y947125D01*
X1162000Y960625D01*
G01X1187230Y702250D02*
X1185834Y703646D01*
X1180790D01*
X1180344Y703200D01*
X1178976D01*
X1177331Y704845D01*
X1176515D01*
G01X1187330Y715720D02*
X1182817Y711207D01*
X1179676D01*
G01X1193960Y713250D02*
X1185560Y704850D01*
X1179660D01*
G01X1173600Y704500D02*
X1171930Y706170D01*
X1171200D01*
G01X1190760Y719450D02*
X1190520Y719210D01*
Y715620D01*
X1184820Y709920D01*
X1181530D01*
X1179660Y708050D01*
G01X1196100Y719100D02*
X1184446Y707446D01*
Y707400D01*
G01X1168000Y706000D02*
X1170329Y708329D01*
X1173015D01*
G01X1170000Y710790D02*
X1170329Y711119D01*
X1173262D01*
G01X1184850Y720120D02*
X1183260Y718530D01*
Y714814D01*
X1182802Y714356D01*
G01X1194000Y703000D02*
X1191500Y705500D01*
X1190000D01*
G01X1225750Y727000D02*
Y727750D01*
X1228400Y730400D01*
X1241000D01*
G01X1229000Y719600D02*
X1235500Y726100D01*
X1248600D01*
X1258500Y736000D01*
X1305500D01*
X1308850Y739350D01*
X1311267D01*
X1331500Y719117D01*
Y703000D01*
G01X1244371Y733129D02*
X1242457Y731215D01*
X1241815D01*
X1241000Y730400D01*
G01X1334500Y636000D02*
X1331500Y633000D01*
Y622860D01*
X1308540Y599900D01*
X1308400D01*
X1305000Y596500D01*
G01X1331500Y703000D02*
Y673500D01*
X1333500Y671500D01*
Y670000D01*
X1334500Y669000D01*
G54D75*
X1368000Y457750D03*
G54D57*
X535000Y134750D03*
X531125Y142250D03*
X538875D03*
G54D39*
X313029Y219500D03*
X310829D03*
X313029Y222500D03*
X310829D03*
X359029Y128500D03*
X356829D03*
X359029Y124500D03*
X356829D03*
X362329Y146000D03*
X361329Y139500D03*
X365600Y134500D03*
X363400D03*
X365529Y131500D03*
X363329D03*
X364529Y146000D03*
X363529Y139500D03*
X391609Y148420D03*
X389409D03*
X415705Y346250D03*
X413505D03*
X444955Y326500D03*
X439855Y327200D03*
X437655D03*
X434055Y359370D03*
X431855D03*
X434100Y372000D03*
X431900D03*
X439755Y374700D03*
X437555D03*
X447155Y326500D03*
X453155Y342000D03*
X450955D03*
X461155Y404000D03*
X458955D03*
X467155Y326500D03*
X464955D03*
X477155Y338500D03*
X474955D03*
X476455Y344500D03*
X473655Y404000D03*
X471455D03*
X474655Y410000D03*
X472455D03*
X478655Y344500D03*
G54D48*
X376000Y10700D03*
X381000D03*
X625500Y348200D03*
X640500D03*
X635500D03*
X630500D03*
X787000Y400700D03*
X1151000Y702200D03*
G54D66*
X678800Y466000D03*
X1347317Y533012D03*
Y525012D03*
G54D85*
G01X-185516Y-508119D02*
Y-490619D01*
G01X-176346D02*
Y-508119D01*
G01Y-499369D02*
X-185516D01*
G01X-163431Y-508119D02*
X-165178Y-507827D01*
X-166706Y-506661D01*
X-168016Y-504911D01*
X-168890Y-502869D01*
X-169326Y-500536D01*
Y-498202D01*
X-168890Y-495869D01*
X-168016Y-493827D01*
X-166706Y-492078D01*
X-165178Y-490911D01*
X-163431Y-490619D01*
X-161685Y-490911D01*
X-160156Y-492078D01*
X-158846Y-493827D01*
X-157972Y-495869D01*
X-157536Y-498202D01*
Y-500536D01*
X-157972Y-502869D01*
X-158846Y-504911D01*
X-160156Y-506661D01*
X-161685Y-507827D01*
X-163431Y-508119D01*
G01X-150953D02*
Y-490619D01*
X-140909Y-508119D01*
Y-490619D01*
G01X-124064Y-508119D02*
X-132798D01*
Y-490619D01*
X-124064D01*
G01X-127558Y-499077D02*
X-132798D01*
G01X-110931Y-508119D02*
Y-500244D01*
X-115298Y-490619D01*
G01X-106564D02*
X-110931Y-500244D01*
G01X-74185Y-498786D02*
X-73311Y-497911D01*
X-72656Y-496453D01*
X-72219Y-494410D01*
X-72656Y-492661D01*
X-73529Y-491494D01*
X-75058Y-490619D01*
X-80953D01*
Y-508119D01*
X-73748D01*
X-72219Y-506953D01*
X-71346Y-505202D01*
X-70909Y-503161D01*
X-71346Y-501119D01*
X-72656Y-499369D01*
X-74185Y-498786D01*
X-80953D01*
G01X-63890Y-508119D02*
X-58431Y-490619D01*
X-52972Y-508119D01*
G01X-54938Y-501994D02*
X-61925D01*
G01X-45734Y-508119D02*
Y-490619D01*
X-41368D01*
X-39621Y-491494D01*
X-38311Y-492661D01*
X-37219Y-494410D01*
X-36346Y-496453D01*
X-36128Y-499369D01*
X-36346Y-502286D01*
X-37219Y-504328D01*
X-38311Y-506078D01*
X-39621Y-507244D01*
X-41368Y-508119D01*
X-45734D01*
G01X-22121Y-499369D02*
X-17754D01*
Y-504619D01*
X-19064Y-506369D01*
X-20593Y-507536D01*
X-22776Y-508119D01*
X-24959Y-507536D01*
X-26488Y-506369D01*
X-27798Y-504619D01*
X-28671Y-502577D01*
X-29108Y-500244D01*
Y-498202D01*
X-28671Y-496453D01*
X-27798Y-494410D01*
X-26488Y-492661D01*
X-25178Y-491494D01*
X-23431Y-490619D01*
X-21903D01*
X-20156Y-491202D01*
X-18846Y-492369D01*
G01X-1564Y-508119D02*
X-10298D01*
Y-490619D01*
X-1564D01*
G01X-5058Y-499077D02*
X-10298D01*
G01X7202Y-508119D02*
Y-490619D01*
X12661D01*
X14407Y-491494D01*
X15499Y-492661D01*
X15936Y-494994D01*
X15499Y-497328D01*
X14189Y-498786D01*
X12661Y-499661D01*
X7202D01*
G01X12661D02*
X15936Y-508119D01*
G01X48315Y-498786D02*
X49189Y-497911D01*
X49844Y-496453D01*
X50281Y-494410D01*
X49844Y-492661D01*
X48971Y-491494D01*
X47442Y-490619D01*
X41547D01*
Y-508119D01*
X48752D01*
X50281Y-506953D01*
X51154Y-505202D01*
X51591Y-503161D01*
X51154Y-501119D01*
X49844Y-499369D01*
X48315Y-498786D01*
X41547D01*
G01X58610Y-508119D02*
X64069Y-490619D01*
X69528Y-508119D01*
G01X67562Y-501994D02*
X60575D01*
G01X76984Y-505786D02*
X78731Y-507244D01*
X80696Y-508119D01*
X82442D01*
X84189Y-507244D01*
X85499Y-505786D01*
X86154Y-503744D01*
X85717Y-501703D01*
X84626Y-499952D01*
X82661Y-498786D01*
X80041Y-498202D01*
X78512Y-497036D01*
X77857Y-494994D01*
X78294Y-492952D01*
X79386Y-491494D01*
X80914Y-490619D01*
X82442D01*
X83971Y-491202D01*
X85281Y-492661D01*
G01X103436Y-508119D02*
X94702D01*
Y-490619D01*
X103436D01*
G01X99942Y-499077D02*
X94702D01*
G01X118315Y-498786D02*
X119189Y-497911D01*
X119844Y-496453D01*
X120281Y-494410D01*
X119844Y-492661D01*
X118971Y-491494D01*
X117442Y-490619D01*
X111547D01*
Y-508119D01*
X118752D01*
X120281Y-506953D01*
X121154Y-505202D01*
X121591Y-503161D01*
X121154Y-501119D01*
X119844Y-499369D01*
X118315Y-498786D01*
X111547D01*
G01X134069Y-508119D02*
X132322Y-507827D01*
X130794Y-506661D01*
X129484Y-504911D01*
X128610Y-502869D01*
X128174Y-500536D01*
Y-498202D01*
X128610Y-495869D01*
X129484Y-493827D01*
X130794Y-492078D01*
X132322Y-490911D01*
X134069Y-490619D01*
X135815Y-490911D01*
X137344Y-492078D01*
X138654Y-493827D01*
X139528Y-495869D01*
X139964Y-498202D01*
Y-500536D01*
X139528Y-502869D01*
X138654Y-504911D01*
X137344Y-506661D01*
X135815Y-507827D01*
X134069Y-508119D01*
G01X146110D02*
X151569Y-490619D01*
X157028Y-508119D01*
G01X155062Y-501994D02*
X148075D01*
G01X164702Y-508119D02*
Y-490619D01*
X170161D01*
X171907Y-491494D01*
X172999Y-492661D01*
X173436Y-494994D01*
X172999Y-497328D01*
X171689Y-498786D01*
X170161Y-499661D01*
X164702D01*
G01X170161D02*
X173436Y-508119D01*
G01X181766D02*
Y-490619D01*
X186132D01*
X187879Y-491494D01*
X189189Y-492661D01*
X190281Y-494410D01*
X191154Y-496453D01*
X191372Y-499369D01*
X191154Y-502286D01*
X190281Y-504328D01*
X189189Y-506078D01*
X187879Y-507244D01*
X186132Y-508119D01*
X181766D01*
G01X-37858Y-463119D02*
Y-445619D01*
X-32181Y-460202D01*
X-26504Y-445619D01*
Y-463119D01*
G01X-14681D02*
X-15991Y-462827D01*
X-17301Y-461661D01*
X-18175Y-459619D01*
X-18611Y-457286D01*
X-18175Y-454952D01*
X-17301Y-452911D01*
X-15991Y-451744D01*
X-14681Y-451453D01*
X-13371Y-451744D01*
X-12061Y-452911D01*
X-11188Y-454952D01*
X-10969Y-457286D01*
X-11188Y-459619D01*
X-12061Y-461661D01*
X-13371Y-462827D01*
X-14681Y-463119D01*
G01X6749Y-445619D02*
Y-463119D01*
G01Y-460495D02*
X5876Y-461953D01*
X4565Y-462827D01*
X3037Y-463119D01*
X1291Y-462536D01*
X-19Y-461078D01*
X-893Y-459328D01*
X-1111Y-457286D01*
X-893Y-455244D01*
X-19Y-453494D01*
X1291Y-452036D01*
X3037Y-451453D01*
X4565Y-451744D01*
X5657Y-452328D01*
X6749Y-453494D01*
G01X17044Y-455244D02*
X24031D01*
X23376Y-453202D01*
X22284Y-452036D01*
X20756Y-451453D01*
X19227Y-451744D01*
X17917Y-452619D01*
X17044Y-454661D01*
X16607Y-456411D01*
Y-458161D01*
X17044Y-459911D01*
X18136Y-461661D01*
X19446Y-462827D01*
X20974Y-463119D01*
X22502Y-462536D01*
X24031Y-460786D01*
G01X37819Y-463119D02*
Y-445619D01*
G01X281019Y-508119D02*
Y-490619D01*
X278399Y-494119D01*
G01Y-508119D02*
X283639D01*
G01X293716Y-504619D02*
X295025Y-506661D01*
X296772Y-507827D01*
X298737Y-508119D01*
X300484Y-507827D01*
X302231Y-506369D01*
X303322Y-504619D01*
X303541Y-502869D01*
X303104Y-500828D01*
X301576Y-499369D01*
X300047Y-498786D01*
X298082D01*
G01X300047D02*
X301357Y-497911D01*
X302449Y-496453D01*
X302886Y-494703D01*
X302449Y-492952D01*
X301357Y-491494D01*
X299392Y-490619D01*
X297427Y-490911D01*
X295462Y-492078D01*
G01X312307Y-506078D02*
X313836Y-507536D01*
X315582Y-508119D01*
X317329Y-507536D01*
X318857Y-505786D01*
X319949Y-503161D01*
X320386Y-500536D01*
Y-497328D01*
X319949Y-494703D01*
X318857Y-492369D01*
X317547Y-491202D01*
X316019Y-490619D01*
X314272Y-491202D01*
X312962Y-492369D01*
X312089Y-494119D01*
X311652Y-496453D01*
X312089Y-498494D01*
X313181Y-500536D01*
X314491Y-501703D01*
X316019Y-501994D01*
X317765Y-501411D01*
X319076Y-499952D01*
X320386Y-497328D01*
G01X336139Y-508119D02*
Y-490619D01*
X328060Y-503161D01*
X338978D01*
G01X351019Y-508119D02*
X352547Y-507827D01*
X354294Y-506953D01*
X355386Y-505495D01*
X355822Y-503452D01*
X355386Y-501411D01*
X354076Y-499661D01*
X352111Y-498786D01*
X349927D01*
X348617Y-498202D01*
X347525Y-496744D01*
X347089Y-494703D01*
X347744Y-492661D01*
X349272Y-491202D01*
X351019Y-490619D01*
X352765Y-491202D01*
X354294Y-492661D01*
X354949Y-494703D01*
X354512Y-496744D01*
X353421Y-498202D01*
X352111Y-498786D01*
X349927D01*
X347962Y-499661D01*
X346652Y-501411D01*
X346216Y-503452D01*
X346652Y-505495D01*
X347744Y-506953D01*
X349491Y-507827D01*
X351019Y-508119D01*
G01X267902Y-463119D02*
Y-445619D01*
X273142D01*
X274889Y-446494D01*
X276199Y-448536D01*
X276636Y-450869D01*
X276199Y-453202D01*
X275107Y-454952D01*
X273142Y-455828D01*
X267902D01*
G01X294572Y-447078D02*
X293262Y-446202D01*
X291734Y-445619D01*
X289987D01*
X288022Y-446494D01*
X286494Y-447952D01*
X285402Y-449703D01*
X284529Y-452619D01*
X284310Y-455244D01*
X284747Y-457869D01*
X285402Y-459619D01*
X286712Y-461369D01*
X288241Y-462536D01*
X289769Y-463119D01*
X291297D01*
X292826Y-462536D01*
X294136Y-461661D01*
X295228Y-460495D01*
G01X309015Y-453786D02*
X309889Y-452911D01*
X310544Y-451453D01*
X310981Y-449410D01*
X310544Y-447661D01*
X309671Y-446494D01*
X308142Y-445619D01*
X302247D01*
Y-463119D01*
X309452D01*
X310981Y-461953D01*
X311854Y-460202D01*
X312291Y-458161D01*
X311854Y-456119D01*
X310544Y-454369D01*
X309015Y-453786D01*
X302247D01*
G01X318219Y-468952D02*
X331319D01*
G01X337247Y-463119D02*
Y-445619D01*
X347291Y-463119D01*
Y-445619D01*
G01X359769Y-463119D02*
X358022Y-462827D01*
X356494Y-461661D01*
X355184Y-459911D01*
X354310Y-457869D01*
X353874Y-455536D01*
Y-453202D01*
X354310Y-450869D01*
X355184Y-448827D01*
X356494Y-447078D01*
X358022Y-445911D01*
X359769Y-445619D01*
X361515Y-445911D01*
X363044Y-447078D01*
X364354Y-448827D01*
X365228Y-450869D01*
X365664Y-453202D01*
Y-455536D01*
X365228Y-457869D01*
X364354Y-459911D01*
X363044Y-461661D01*
X361515Y-462827D01*
X359769Y-463119D01*
G01X410610Y-445619D02*
X416069Y-463119D01*
X421528Y-445619D01*
G01X437936Y-463119D02*
X429202D01*
Y-445619D01*
X437936D01*
G01X434442Y-454077D02*
X429202D01*
G01X446702Y-463119D02*
Y-445619D01*
X452161D01*
X453907Y-446494D01*
X454999Y-447661D01*
X455436Y-449994D01*
X454999Y-452328D01*
X453689Y-453786D01*
X452161Y-454661D01*
X446702D01*
G01X452161D02*
X455436Y-463119D01*
G01X468569Y-463702D02*
X468132Y-463411D01*
Y-462827D01*
X468569Y-462536D01*
X469006Y-462827D01*
Y-463411D01*
X468569Y-463702D01*
G01X433569Y-508119D02*
Y-490619D01*
X430949Y-494119D01*
G01Y-508119D02*
X436189D01*
G01X452815Y-498786D02*
X453689Y-497911D01*
X454344Y-496453D01*
X454781Y-494410D01*
X454344Y-492661D01*
X453471Y-491494D01*
X451942Y-490619D01*
X446047D01*
Y-508119D01*
X453252D01*
X454781Y-506953D01*
X455654Y-505202D01*
X456091Y-503161D01*
X455654Y-501119D01*
X454344Y-499369D01*
X452815Y-498786D01*
X446047D01*
G01X544152Y-445619D02*
Y-463119D01*
X552886D01*
G01X569949D02*
Y-451453D01*
G01Y-453494D02*
X569076Y-452328D01*
X567765Y-451744D01*
X566237Y-451453D01*
X564709Y-452036D01*
X563399Y-453202D01*
X562525Y-454952D01*
X562089Y-457286D01*
X562525Y-459619D01*
X563399Y-461369D01*
X564709Y-462536D01*
X566237Y-463119D01*
X567765Y-462827D01*
X569076Y-461953D01*
X569949Y-460786D01*
G01X578934Y-468369D02*
X580244Y-468952D01*
X581991Y-468369D01*
X583082Y-467203D01*
X583956Y-465744D01*
X585265Y-461078D01*
X588104Y-451453D01*
G01X581117D02*
X585265Y-461078D01*
G01X597744Y-455244D02*
X604731D01*
X604076Y-453202D01*
X602984Y-452036D01*
X601456Y-451453D01*
X599927Y-451744D01*
X598617Y-452619D01*
X597744Y-454661D01*
X597307Y-456411D01*
Y-458161D01*
X597744Y-459911D01*
X598836Y-461661D01*
X600146Y-462827D01*
X601674Y-463119D01*
X603202Y-462536D01*
X604731Y-460786D01*
G01X615462Y-463119D02*
Y-451453D01*
G01Y-453786D02*
X616554Y-452619D01*
X617646Y-451744D01*
X619174Y-451453D01*
X620265Y-451744D01*
X621576Y-452619D01*
G01X596636Y-490619D02*
Y-508119D01*
X587902D01*
G01X574769D02*
X573241Y-507827D01*
X571494Y-506953D01*
X570402Y-505495D01*
X569966Y-503452D01*
X570402Y-501411D01*
X571712Y-499661D01*
X573677Y-498786D01*
X575861D01*
X577171Y-498202D01*
X578263Y-496744D01*
X578699Y-494703D01*
X578044Y-492661D01*
X576516Y-491202D01*
X574769Y-490619D01*
X573023Y-491202D01*
X571494Y-492661D01*
X570839Y-494703D01*
X571276Y-496744D01*
X572367Y-498202D01*
X573677Y-498786D01*
X575861D01*
X577826Y-499661D01*
X579136Y-501411D01*
X579572Y-503452D01*
X579136Y-505495D01*
X578044Y-506953D01*
X576297Y-507827D01*
X574769Y-508119D01*
G01X686702Y-490619D02*
Y-508119D01*
X695436D01*
G01X703984Y-513369D02*
X705294Y-513952D01*
X707041Y-513369D01*
X708132Y-512203D01*
X709006Y-510744D01*
X710315Y-506078D01*
X713154Y-496453D01*
G01X706167D02*
X710315Y-506078D01*
G01X722357Y-508119D02*
Y-496453D01*
G01Y-499369D02*
X723231Y-497911D01*
X724541Y-496744D01*
X726287Y-496453D01*
X727815Y-496744D01*
X729126Y-497911D01*
X729781Y-499952D01*
Y-508119D01*
G01X739857D02*
Y-496453D01*
G01Y-499369D02*
X740731Y-497911D01*
X742041Y-496744D01*
X743787Y-496453D01*
X745315Y-496744D01*
X746626Y-497911D01*
X747281Y-499952D01*
Y-508119D01*
G01X774202Y-490619D02*
Y-508119D01*
X782936D01*
G01X796069Y-496453D02*
Y-508119D01*
G01Y-491786D02*
X795632Y-491494D01*
Y-490911D01*
X796069Y-490619D01*
X796506Y-490911D01*
Y-491494D01*
X796069Y-491786D01*
G01X809857Y-496453D02*
Y-504619D01*
X810731Y-506661D01*
X812041Y-507827D01*
X813569Y-508119D01*
X815097Y-507827D01*
X816407Y-506661D01*
X817281Y-504619D01*
G01Y-508119D02*
Y-496453D01*
G01X686266Y-463119D02*
Y-445619D01*
X690632D01*
X692379Y-446494D01*
X693689Y-447661D01*
X694781Y-449410D01*
X695654Y-451453D01*
X695872Y-454369D01*
X695654Y-457286D01*
X694781Y-459328D01*
X693689Y-461078D01*
X692379Y-462244D01*
X690632Y-463119D01*
X686266D01*
G01X705294Y-455244D02*
X712281D01*
X711626Y-453202D01*
X710534Y-452036D01*
X709006Y-451453D01*
X707477Y-451744D01*
X706167Y-452619D01*
X705294Y-454661D01*
X704857Y-456411D01*
Y-458161D01*
X705294Y-459911D01*
X706386Y-461661D01*
X707696Y-462827D01*
X709224Y-463119D01*
X710752Y-462536D01*
X712281Y-460786D01*
G01X722794Y-461078D02*
X723886Y-462244D01*
X725414Y-463119D01*
X726724D01*
X728034Y-462536D01*
X728907Y-461661D01*
X729344Y-460495D01*
X729126Y-458744D01*
X728252Y-457869D01*
X724322Y-456119D01*
X723449Y-454077D01*
X723886Y-452619D01*
X724759Y-451744D01*
X726069Y-451453D01*
X727379Y-451744D01*
X728689Y-452619D01*
G01X743569Y-451453D02*
Y-463119D01*
G01Y-446786D02*
X743132Y-446494D01*
Y-445911D01*
X743569Y-445619D01*
X744006Y-445911D01*
Y-446494D01*
X743569Y-446786D01*
G01X758012Y-467494D02*
X759541Y-468661D01*
X761287Y-468952D01*
X762815Y-468661D01*
X764126Y-467203D01*
X764999Y-465161D01*
Y-451453D01*
G01Y-453786D02*
X764126Y-452619D01*
X762815Y-451744D01*
X761287Y-451453D01*
X759541Y-452036D01*
X758449Y-453202D01*
X757575Y-455244D01*
X757139Y-457286D01*
X757357Y-459036D01*
X758231Y-461078D01*
X759541Y-462536D01*
X761287Y-463119D01*
X762597Y-462827D01*
X764126Y-461661D01*
X764999Y-460495D01*
G01X774857Y-463119D02*
Y-451453D01*
G01Y-454369D02*
X775731Y-452911D01*
X777041Y-451744D01*
X778787Y-451453D01*
X780315Y-451744D01*
X781626Y-452911D01*
X782281Y-454952D01*
Y-463119D01*
G01X792794Y-455244D02*
X799781D01*
X799126Y-453202D01*
X798034Y-452036D01*
X796506Y-451453D01*
X794977Y-451744D01*
X793667Y-452619D01*
X792794Y-454661D01*
X792357Y-456411D01*
Y-458161D01*
X792794Y-459911D01*
X793886Y-461661D01*
X795196Y-462827D01*
X796724Y-463119D01*
X798252Y-462536D01*
X799781Y-460786D01*
G01X810512Y-463119D02*
Y-451453D01*
G01Y-453786D02*
X811604Y-452619D01*
X812696Y-451744D01*
X814224Y-451453D01*
X815315Y-451744D01*
X816626Y-452619D01*
G01X857269Y-508119D02*
Y-490619D01*
X854649Y-494119D01*
G01Y-508119D02*
X859889D01*
G01X874769D02*
Y-490619D01*
X872149Y-494119D01*
G01Y-508119D02*
X877389D01*
G01X888339Y-508702D02*
X896199Y-490619D01*
G01X909769Y-508119D02*
Y-490619D01*
X907149Y-494119D01*
G01Y-508119D02*
X912389D01*
G01X922466Y-504619D02*
X923775Y-506661D01*
X925522Y-507827D01*
X927487Y-508119D01*
X929234Y-507827D01*
X930981Y-506369D01*
X932072Y-504619D01*
X932291Y-502869D01*
X931854Y-500828D01*
X930326Y-499369D01*
X928797Y-498786D01*
X926832D01*
G01X928797D02*
X930107Y-497911D01*
X931199Y-496453D01*
X931636Y-494703D01*
X931199Y-492952D01*
X930107Y-491494D01*
X928142Y-490619D01*
X926177Y-490911D01*
X924212Y-492078D01*
G01X940839Y-508702D02*
X948699Y-490619D01*
G01X958121Y-493536D02*
X959431Y-491786D01*
X960959Y-490911D01*
X962706Y-490619D01*
X964889Y-491202D01*
X966417Y-492661D01*
X966854Y-494410D01*
X966636Y-496161D01*
X965762Y-497619D01*
X961396Y-500536D01*
X959431Y-502577D01*
X958121Y-505495D01*
X957684Y-508119D01*
X966854D01*
G01X979769Y-490619D02*
X978022Y-491202D01*
X976712Y-492661D01*
X975839Y-494410D01*
X975184Y-496744D01*
X974966Y-499369D01*
X975184Y-501994D01*
X975839Y-504328D01*
X976712Y-506078D01*
X978022Y-507536D01*
X979769Y-508119D01*
X981515Y-507536D01*
X982826Y-506078D01*
X983699Y-504328D01*
X984354Y-501994D01*
X984572Y-499369D01*
X984354Y-496744D01*
X983699Y-494410D01*
X982826Y-492661D01*
X981515Y-491202D01*
X979769Y-490619D01*
G01X997269Y-508119D02*
Y-490619D01*
X994649Y-494119D01*
G01Y-508119D02*
X999889D01*
G01X1017389D02*
Y-490619D01*
X1009310Y-503161D01*
X1020228D01*
G01X904966Y-463119D02*
Y-445619D01*
X909332D01*
X911079Y-446494D01*
X912389Y-447661D01*
X913481Y-449410D01*
X914354Y-451453D01*
X914572Y-454369D01*
X914354Y-457286D01*
X913481Y-459328D01*
X912389Y-461078D01*
X911079Y-462244D01*
X909332Y-463119D01*
X904966D01*
G01X931199D02*
Y-451453D01*
G01Y-453494D02*
X930326Y-452328D01*
X929015Y-451744D01*
X927487Y-451453D01*
X925959Y-452036D01*
X924649Y-453202D01*
X923775Y-454952D01*
X923339Y-457286D01*
X923775Y-459619D01*
X924649Y-461369D01*
X925959Y-462536D01*
X927487Y-463119D01*
X929015Y-462827D01*
X930326Y-461953D01*
X931199Y-460786D01*
G01X944769Y-445619D02*
Y-463119D01*
G01X941712Y-451453D02*
X947826D01*
G01X958994Y-455244D02*
X965981D01*
X965326Y-453202D01*
X964234Y-452036D01*
X962706Y-451453D01*
X961177Y-451744D01*
X959867Y-452619D01*
X958994Y-454661D01*
X958557Y-456411D01*
Y-458161D01*
X958994Y-459911D01*
X960086Y-461661D01*
X961396Y-462827D01*
X962924Y-463119D01*
X964452Y-462536D01*
X965981Y-460786D01*
G54D67*
X1015740Y50500D03*
X1012000D03*
X1008260D03*
Y59500D03*
X1015740D03*
G54D49*
X376000Y16300D03*
X381000D03*
X625500Y353800D03*
X640500D03*
X635500D03*
X630500D03*
X787000Y406300D03*
X1151000Y707800D03*
G54D76*
X1368000Y455250D03*
G54D58*
X545079Y290355D03*
Y315945D03*
X560829Y290355D03*
X556889Y298230D03*
X552954Y290355D03*
X549014Y298230D03*
X560829Y315945D03*
X556889Y308070D03*
X552954Y315945D03*
X549014Y308070D03*
X576574Y290355D03*
X572639Y298230D03*
X568699Y290355D03*
X564764Y298230D03*
X576574Y315945D03*
X572639Y308070D03*
X568699Y315945D03*
X564764Y308070D03*
X592324Y290355D03*
X588384Y298230D03*
X584449Y290355D03*
X580514Y298230D03*
X592324Y315945D03*
X588384Y308070D03*
X584449Y315945D03*
X580514Y308070D03*
X608069Y290355D03*
X604134Y298230D03*
X600199Y290355D03*
X596259Y298230D03*
X608069Y315945D03*
X604134Y308070D03*
X600199Y315945D03*
X596259Y308070D03*
X627754Y298230D03*
X623819Y290355D03*
X619884Y298230D03*
X615944Y290355D03*
X612009Y298230D03*
X627754Y308070D03*
X623819Y315945D03*
X619884Y308070D03*
X615944Y315945D03*
X612009Y308070D03*
X643504Y298230D03*
X639569Y290355D03*
X635629Y298230D03*
X631694Y290355D03*
X643504Y308070D03*
X639569Y315945D03*
X635629Y308070D03*
X631694Y315945D03*
X659254Y298230D03*
X655314Y290355D03*
X651379Y298230D03*
X647439Y290355D03*
X659254Y308070D03*
X655314Y315945D03*
X651379Y308070D03*
X647439Y315945D03*
X674999Y298230D03*
X671064Y290355D03*
X667124Y298230D03*
X663189Y290355D03*
X674999Y308070D03*
X671064Y315945D03*
X667124Y308070D03*
X663189Y315945D03*
X690749Y298230D03*
X686809Y290355D03*
X682874Y298230D03*
X678939Y290355D03*
X690749Y308070D03*
X686809Y315945D03*
X682874Y308070D03*
X678939Y315945D03*
X706494Y298230D03*
X702559Y290355D03*
X698624Y298230D03*
X694684Y290355D03*
X706494Y308070D03*
X702559Y315945D03*
X698624Y308070D03*
X694684Y315945D03*
X726179Y290355D03*
X722244Y298230D03*
X718309Y290355D03*
X714369Y298230D03*
X710434Y290355D03*
X726179Y315945D03*
X722244Y308070D03*
X718309Y315945D03*
X714369Y308070D03*
X710434Y315945D03*
X741929Y290355D03*
X737994Y298230D03*
X734054Y290355D03*
X730119Y298230D03*
X741929Y315945D03*
X737994Y308070D03*
X734054Y315945D03*
X730119Y308070D03*
X757679Y290355D03*
X753739Y298230D03*
X749804Y290355D03*
X745864Y298230D03*
X757679Y315945D03*
X753739Y308070D03*
X749804Y315945D03*
X745864Y308070D03*
X773424Y290355D03*
X769489Y298230D03*
X765549Y290355D03*
X761614Y298230D03*
X773424Y315945D03*
X769489Y308070D03*
X765549Y315945D03*
X761614Y308070D03*
X789174Y290355D03*
X785234Y298230D03*
X781299Y290355D03*
X777364Y298230D03*
X789174Y315945D03*
X785234Y308070D03*
X781299Y315945D03*
X777364Y308070D03*
X804919Y290355D03*
X800984Y298230D03*
X797049Y290355D03*
X793109Y298230D03*
X804919Y315945D03*
X800984Y308070D03*
X797049Y315945D03*
X793109Y308070D03*
X820669Y290355D03*
X816734Y298230D03*
X812794Y290355D03*
X808859Y298230D03*
X820669Y315945D03*
X816734Y308070D03*
X812794Y315945D03*
X808859Y308070D03*
X840354Y298230D03*
X836419Y290355D03*
X832479Y298230D03*
X840354Y308070D03*
X836419Y315945D03*
X832479Y308070D03*
X856104Y298230D03*
X852164Y290355D03*
X848229Y298230D03*
X844289Y290355D03*
X856104Y308070D03*
X852164Y315945D03*
X848229Y308070D03*
X844289Y315945D03*
X871849Y298230D03*
X867914Y290355D03*
X863974Y298230D03*
X860039Y290355D03*
X871849Y308070D03*
X867914Y315945D03*
X863974Y308070D03*
X860039Y315945D03*
G54D86*
G01X435000Y294000D02*
X434800D01*
X432700Y291900D01*
Y291500D01*
X432600Y291400D01*
G01X435055Y287750D02*
X432600Y290205D01*
Y291400D01*
G01X459429Y106000D02*
Y102700D01*
G01X464679Y104000D02*
X462679Y106000D01*
X459429D01*
G01X447829Y104000D02*
Y100600D01*
X448929Y99500D01*
G01D02*
X449429Y99000D01*
X452829D01*
G01X494329Y149500D02*
Y149171D01*
X497500Y146000D01*
X499929D01*
G01D02*
X500429Y146500D01*
X503929D01*
G01X506429Y149500D02*
X509200Y146729D01*
Y146700D01*
G01X511179Y151000D02*
Y147500D01*
X510379Y146700D01*
X509200D01*
G01X1347000Y48000D02*
Y49512D01*
X1359200Y61711D01*
Y91800D01*
X1350000Y101000D01*
Y105500D01*
G01X1342500Y51000D02*
X1357500Y66000D01*
Y90500D01*
X1342000Y106000D01*
Y107000D01*
G01X1343500Y112000D02*
X1342000Y110500D01*
Y107000D01*
G01X1350000Y105500D02*
Y110500D01*
X1349500Y111000D01*
Y112000D01*
G54D77*
G01X323060Y291750D02*
X323810Y292500D01*
X326000D01*
G01X356829Y128500D02*
X353929D01*
G01X356829Y124500D02*
X353429D01*
X351429Y126500D01*
G01X357394Y131496D02*
X357398Y131500D01*
G01X363329D02*
X357398D01*
G01X360140Y135500D02*
Y134242D01*
X357398Y131500D01*
G01X357940Y135500D02*
X355940D01*
X353740Y133300D01*
G01X365133Y129133D02*
X364500Y128500D01*
X359029D01*
G01D02*
Y124500D01*
G01X356640Y146000D02*
X362329D01*
G01X358140Y155000D02*
X361890D01*
X362009Y155119D01*
G01X361329Y139500D02*
Y141840D01*
X362009Y142520D01*
G01X362329Y146000D02*
Y148499D01*
X362009Y148819D01*
G01X354440Y146000D02*
Y145400D01*
X352040Y143000D01*
G01X355940Y155000D02*
X351429D01*
X349829Y153400D01*
G01X358140Y162000D02*
X361440D01*
X362034Y161406D01*
G01X355940Y162000D02*
X352129D01*
X351929Y162200D01*
G01X365529Y131500D02*
X366929D01*
X367778Y130651D01*
X369075D01*
X371482Y133058D01*
G01X363529Y139500D02*
Y140879D01*
X365182Y142532D01*
G01X364529Y146000D02*
Y143185D01*
X365182Y142532D01*
G01X389540Y132600D02*
Y135407D01*
X390354Y136221D01*
G01X389540Y130400D02*
X390840D01*
X392240Y129000D01*
G01X399055Y443600D02*
Y447945D01*
X396055Y450945D01*
Y456500D01*
G01X413929Y133600D02*
Y134710D01*
X412429Y136210D01*
G01X409040Y143900D02*
X407870D01*
X406110Y145660D01*
G01X415879Y214680D02*
X414559Y216000D01*
Y216272D01*
X412500Y218331D01*
Y224250D01*
X413250Y225000D01*
G01X403055Y323900D02*
Y319500D01*
X401555Y318000D01*
G01X396500Y321700D02*
X397855D01*
X401555Y318000D01*
G01X403055Y326100D02*
X402955D01*
X401555Y327500D01*
X398300D01*
X396500Y329300D01*
G01X406555Y323250D02*
X406067Y323738D01*
X405965D01*
X403603Y326100D01*
X403055D01*
G01X406305Y338850D02*
Y339376D01*
X408857Y341928D01*
G01X409805Y338850D02*
Y338939D01*
X412794Y341928D01*
G01X413929Y131400D02*
Y128889D01*
X413540Y128500D01*
G01X413505Y346250D02*
X412855Y346900D01*
Y349820D01*
X412815Y349860D01*
G01X415705Y346250D02*
X416355Y346900D01*
Y349670D01*
X416615Y349930D01*
G01X421805Y372500D02*
Y372287D01*
X424605Y369487D01*
G01X425305Y372500D02*
X425529D01*
X428542Y369487D01*
G01X430513Y320841D02*
X430523Y320851D01*
Y323533D01*
G01X444955Y326500D02*
X444305Y327150D01*
Y330102D01*
X444290Y330117D01*
G01X438055Y322750D02*
X437655Y323150D01*
Y327200D01*
G01D02*
Y328656D01*
X436416Y329895D01*
Y330117D01*
G01X439855Y327200D02*
X439805Y327150D01*
Y329569D01*
X440353Y330117D01*
G01X435355Y348900D02*
Y346926D01*
X436416Y345865D01*
G01X433155Y348900D02*
Y346420D01*
X432585Y345850D01*
G01X443255Y362700D02*
Y364515D01*
X444290Y365550D01*
G01X443255Y360400D02*
Y358711D01*
X444290Y357676D01*
G01X431855Y359370D02*
Y360989D01*
X432479Y361613D01*
G01X441055Y360400D02*
Y358378D01*
X440353Y357676D01*
G01X441055Y362700D02*
Y364848D01*
X440353Y365550D01*
G01X434055Y359370D02*
X434173D01*
X436416Y361613D01*
G01X431900Y372000D02*
Y370066D01*
X432479Y369487D01*
G01X434100Y372000D02*
Y371803D01*
X436416Y369487D01*
G01X444255Y392400D02*
X447516D01*
X448227Y393111D01*
G01X444255Y394600D02*
Y397013D01*
X444290Y397048D01*
G01X445435Y839000D02*
Y834860D01*
X440228Y829653D01*
G01X445435Y853000D02*
Y858343D01*
X441528Y862250D01*
G01X456305Y326500D02*
Y329915D01*
X456103Y330117D01*
G01X459805Y326500D02*
Y329882D01*
X460040Y330117D01*
G01X447155Y326500D02*
X447805Y327150D01*
Y329695D01*
X448227Y330117D01*
G01X463535Y352710D02*
X462948D01*
X460040Y349802D01*
G01X453555Y364800D02*
X455353D01*
X456103Y365550D01*
G01X453255Y357800D02*
X455979D01*
X456103Y357676D01*
G01X450455Y362600D02*
X449214D01*
X448227Y361613D01*
G01X453555Y362600D02*
X455116D01*
X456103Y361613D01*
G01X463535Y354910D02*
X462806D01*
X460040Y357676D01*
G01X450455Y364800D02*
X448977D01*
X448227Y365550D01*
G01X451055Y357800D02*
X448351D01*
X448227Y357676D01*
G01X453855Y386200D02*
X455140D01*
X456103Y385237D01*
G01X453855Y378900D02*
X454655D01*
X456103Y377452D01*
Y377363D01*
G01X453855Y381100D02*
X455903D01*
X456103Y381300D01*
G01X453455Y400300D02*
X455418D01*
X456103Y400985D01*
G01X451255Y400300D02*
X448912D01*
X448227Y400985D01*
G01X458955Y404000D02*
Y402070D01*
X460040Y400985D01*
G01X451355Y392800D02*
X448538D01*
X448227Y393111D01*
G01X451355Y395000D02*
X450275D01*
X448227Y397048D01*
G01X451255Y398100D02*
X449279D01*
X448227Y397048D01*
G01X453455Y398100D02*
X455051D01*
X456103Y397048D01*
G01X453855Y388400D02*
X455329D01*
X456103Y389174D01*
G01X461155Y404000D02*
Y403807D01*
X463977Y400985D01*
G01X455278Y839000D02*
Y834500D01*
X456278Y833500D01*
G01X457247Y839000D02*
Y834469D01*
X456278Y833500D01*
G01X455278Y853000D02*
Y857000D01*
X456278Y858000D01*
G01X457247Y853000D02*
Y857031D01*
X456278Y858000D01*
G01X464955Y326500D02*
X464305Y327150D01*
Y329789D01*
X463977Y330117D01*
G01X467155Y326500D02*
X467805Y327150D01*
Y330008D01*
X467914Y330117D01*
G01X476455Y344500D02*
Y342595D01*
X475788Y341928D01*
G01X474955Y338500D02*
Y341095D01*
X475788Y341928D01*
G01X477155Y338500D02*
Y339358D01*
X479725Y341928D01*
G01X475055Y364900D02*
Y362346D01*
X475788Y361613D01*
G01X475855Y354900D02*
Y357609D01*
X475788Y357676D01*
G01X479055Y355100D02*
Y355500D01*
X476879Y357676D01*
X475788D01*
G01X472855Y364900D02*
Y362617D01*
X471851Y361613D01*
G01X474755Y372500D02*
Y370520D01*
X475788Y369487D01*
G01X474755Y374800D02*
Y376330D01*
X475788Y377363D01*
G01X474755Y383800D02*
Y382333D01*
X475788Y381300D01*
G01X472555Y374800D02*
Y376659D01*
X471851Y377363D01*
G01X472555Y372500D02*
Y370191D01*
X471851Y369487D01*
G01X472555Y383800D02*
Y382004D01*
X471851Y381300D01*
G01X471455Y404000D02*
X470929D01*
X467914Y400985D01*
G01X472455Y410000D02*
Y412192D01*
X471851Y412796D01*
G01X469055Y418100D02*
Y419000D01*
X472055Y422000D01*
Y425000D01*
G01X480023Y428583D02*
X479764D01*
X475788Y424607D01*
G01X474555Y420100D02*
Y423374D01*
X475788Y424607D01*
G01X467089Y839000D02*
Y836189D01*
X472778Y830500D01*
X476278D01*
G01X467089Y853000D02*
Y858311D01*
X472778Y864000D01*
X475278D01*
G01X478655Y344500D02*
Y342998D01*
X479725Y341928D01*
G01X488555Y385900D02*
X490873D01*
X491536Y385237D01*
G01X482555Y380600D02*
X480425D01*
X479725Y381300D01*
G01X492655Y371500D02*
X493555D01*
X495555Y369500D01*
G01X482055Y372900D02*
Y371817D01*
X479725Y369487D01*
G01X490455Y371500D02*
Y370568D01*
X491536Y369487D01*
G01X489055Y393900D02*
X490747D01*
X491536Y393111D01*
G01X483055Y396100D02*
X480673D01*
X479725Y397048D01*
G01X481055Y408100D02*
X482903D01*
X483662Y408859D01*
G01X488555Y409900D02*
X490495D01*
X491536Y408859D01*
G01X499655Y380000D02*
X502047D01*
X503347Y381300D01*
G01X507355Y385500D02*
Y390800D01*
G01X501155Y393000D02*
X505155D01*
X507355Y390800D01*
G01Y400500D02*
Y403700D01*
X506055Y405000D01*
X503425D01*
X503347Y404922D01*
G01X497155Y405500D02*
Y407177D01*
X495473Y408859D01*
G01X1073500Y140500D02*
X1078500D01*
G01X1144768Y677534D02*
X1143501Y676567D01*
X1141968D01*
X1141954Y676581D01*
G54D68*
X1045000Y32598D03*
X1096732D03*
G54D59*
X590315Y9134D03*
Y19134D03*
X649527Y9134D03*
Y19134D03*
Y29134D03*
G54D87*
G01X407205Y372000D02*
Y370381D01*
X407057Y370233D01*
Y367350D01*
X408857Y365550D01*
G01X410705Y372000D02*
Y367639D01*
X412794Y365550D01*
G54D78*
G01X380769Y154440D02*
X380119Y155090D01*
X377821D01*
X377765Y155146D01*
G01X375040Y149600D02*
X374490D01*
X373744Y148854D01*
X371455D01*
G01X375040Y147400D02*
X375690Y146750D01*
X376677D01*
X377757Y145670D01*
G01X378189Y164630D02*
X374648D01*
X374577Y164559D01*
G01X374629Y171100D02*
X377312D01*
X377566Y170846D01*
X377750D01*
G01X378229Y158600D02*
X374903D01*
X374570Y158267D01*
G01X374629Y173300D02*
X373979Y173950D01*
X371485D01*
X371457Y173978D01*
G01X389409Y148420D02*
X388759Y147770D01*
Y147223D01*
X387206Y145670D01*
G01X391609Y148420D02*
Y146924D01*
X390355Y145670D01*
G01X396029Y148500D02*
Y146296D01*
X396655Y145670D01*
G01X387029Y152600D02*
X387639Y151990D01*
X390339D01*
G01X380769Y152240D02*
Y148918D01*
X380888Y148799D01*
G01X380429Y158600D02*
X381079Y159250D01*
Y161282D01*
X380944Y161417D01*
G01X380829Y191350D02*
X382433D01*
X384036Y189747D01*
G01X398229Y148500D02*
Y147771D01*
X399804Y146196D01*
Y145670D01*
G01X406529Y151600D02*
X406419Y151710D01*
X404818D01*
X402988Y151900D01*
X402938Y151950D01*
G01X403109Y216030D02*
Y214803D01*
X406102Y211810D01*
G01X437598Y148818D02*
X437006Y149410D01*
X433490D01*
X432600Y150300D01*
Y153800D01*
X431350Y155050D01*
X429940D01*
G01X437555Y374700D02*
Y376224D01*
X436416Y377363D01*
G01X439355Y372000D02*
Y370485D01*
X440353Y369487D01*
G01X439255Y383900D02*
Y382398D01*
X440353Y381300D01*
G01X439755Y374700D02*
Y376765D01*
X440353Y377363D01*
G01X437155Y372000D02*
Y370226D01*
X436416Y369487D01*
G01X437055Y383900D02*
Y381939D01*
X436416Y381300D01*
G01X439255Y386300D02*
Y388076D01*
X440353Y389174D01*
G01X436355Y392000D02*
X433590D01*
X432479Y393111D01*
G01X436355Y394200D02*
Y396987D01*
X436416Y397048D01*
G01X437055Y386300D02*
Y388535D01*
X436416Y389174D01*
G01X450955Y342000D02*
X448299D01*
X448227Y341928D01*
G01X453155Y342000D02*
X456031D01*
X456103Y341928D01*
G01X474755Y347300D02*
Y348769D01*
X475788Y349802D01*
G01X475855Y352700D02*
X472890D01*
X471851Y353739D01*
G01X472555Y347300D02*
Y349098D01*
X471851Y349802D01*
G01X1066118Y681554D02*
X1063056D01*
G01X1135588Y688864D02*
Y686004D01*
X1135551Y685967D01*
G01X1157000Y677250D02*
X1157022Y677228D01*
Y675978D01*
X1154470Y673426D01*
Y673363D01*
G01X1160850Y679300D02*
Y676617D01*
X1160768Y676535D01*
G01X1193450Y698520D02*
X1192470Y699500D01*
X1190000D01*
G01X1199450Y698520D02*
X1203500D01*
G54D69*
X1066929Y43267D03*
X1057086D03*
X1084646D03*
X1074803D03*
G54D88*
G01X362302Y164450D02*
G02X362904Y164201I0J-852D01*
G01X363871Y163234D01*
G03X364487Y162979I616J616D01*
G01X367242D01*
G03X367646Y163147I-1J572D01*
G01X368000Y163500D01*
G03X368325Y164285I-785J785D01*
G01Y164585D01*
G01X364311Y153517D02*
X366743D01*
X368333Y155107D01*
G01X376671Y133886D02*
G03X377256Y135300I-1414J1413D01*
G01Y136819D01*
G03X376902Y137674I-1209J0D01*
G01X376602Y137974D01*
G02X376175Y139005I1031J1031D01*
G01Y140200D01*
G03X375643Y141483I-1815J-1D01*
G01X375578Y141549D01*
X374607Y142520D01*
G01X379181Y132221D02*
Y137615D01*
X379345Y137779D01*
Y139500D01*
G03X378940Y140478I-1383J0D01*
G01X378923Y140495D01*
X378364Y141053D01*
G02X377757Y142520I1467J1466D01*
G01X378181Y137704D02*
Y138359D01*
G03X378059Y138943I-1471J-3D01*
G03X377750Y139400I-1352J-581D01*
G01X388780Y137460D02*
Y139250D01*
G03X388232Y140573I-1871J0D01*
G01X387507Y141298D01*
G02X387206Y142025I727J727D01*
G01Y142520D01*
G01X385219Y137309D02*
G03X385594Y138214I-905J905D01*
G01Y139415D01*
G03X385163Y140455I-1470J0D01*
G01X384370Y141248D01*
G02X384056Y142006I758J758D01*
G01Y142520D01*
G01X395108Y138000D02*
Y139255D01*
G03X394560Y140578I-1871J0D01*
G01X393794Y141344D01*
G02X393505Y142042I698J698D01*
G01Y142520D01*
G01X405129Y135183D02*
G02X404528Y136633I1449J1450D01*
G01Y139868D01*
G03X403765Y141709I-2604J-1D01*
G01X402954Y142520D01*
G01X407958Y137961D02*
G02X407678Y138637I676J676D01*
G01Y139373D01*
G03X407217Y140486I-1574J0D01*
G01X407216Y140487D01*
X407215D01*
X406404Y141298D01*
G02X406103Y142025I727J727D01*
G01Y142520D01*
G01X398260Y138220D02*
Y139450D01*
G03X398024Y140543I-2655J-1D01*
G03X397594Y141581I-1468J0D01*
G01X396655Y142520D01*
G01X1132434Y682860D02*
X1130915Y684379D01*
X1126843D01*
X1126841Y684377D01*
X1125393D01*
X1125340Y684430D01*
G01X1129273Y689170D02*
X1127699Y687596D01*
X1123338D01*
G01X1129290Y692303D02*
X1128320D01*
X1126769Y693854D01*
X1116364D01*
X1116220Y693710D01*
G01X1122450Y703170D02*
X1122558Y703278D01*
X1127331D01*
X1127375Y703235D01*
X1128896Y701714D01*
X1129270D01*
G01X1127358Y674014D02*
X1128269Y674925D01*
X1129925D01*
X1131445Y673405D01*
X1132402D01*
G01X1122840Y710220D02*
X1123456Y709604D01*
X1126841D01*
X1128389Y708056D01*
X1129285D01*
G01X1127610Y663660D02*
X1129450Y665500D01*
X1133024D01*
X1133973Y666449D01*
Y667683D01*
X1135595Y669305D01*
Y670225D01*
G01X1129238Y704878D02*
X1129082D01*
X1127511Y706449D01*
X1122489D01*
X1122250Y706210D01*
G01X1134079Y710360D02*
X1133995Y710444D01*
Y711839D01*
X1133064Y712770D01*
X1131792D01*
X1130835Y713727D01*
Y715003D01*
X1130702Y715136D01*
Y721260D01*
G01X1122319Y713181D02*
X1123619D01*
X1123969Y712831D01*
X1125430D01*
X1125468Y712793D01*
X1126774D01*
X1127696Y711871D01*
Y710563D01*
X1128628Y709631D01*
X1129938D01*
X1130860Y708709D01*
Y707403D01*
X1130831Y707374D01*
Y704251D01*
X1131753Y703329D01*
X1134834D01*
X1134894Y703389D01*
X1136489D01*
X1138400Y705300D01*
G01X1154900Y665011D02*
X1156071Y666182D01*
Y671876D01*
X1157613Y673418D01*
G01X1168500Y659000D02*
Y660302D01*
X1165523Y663279D01*
Y665523D01*
X1167034Y667034D01*
Y667092D01*
G01X1173391Y652608D02*
Y654992D01*
X1169650Y658733D01*
Y663608D01*
X1168609Y664649D01*
Y667745D01*
X1167687Y668667D01*
X1165525D01*
X1163917Y670275D01*
G01X1177668Y665332D02*
X1177509Y665491D01*
X1175931D01*
X1175891Y665531D01*
X1175756D01*
X1174927Y666360D01*
Y666463D01*
X1174924Y666466D01*
Y667842D01*
X1174927Y667845D01*
Y669016D01*
X1176129Y670218D01*
X1176503D01*
G01X1171767Y665500D02*
Y668267D01*
X1173403Y669903D01*
Y670237D01*
G01X1175500Y660000D02*
X1174920Y660580D01*
Y664812D01*
X1173349Y666383D01*
Y667099D01*
G01X1182599Y666901D02*
X1182564D01*
X1180806Y668659D01*
X1179000D01*
X1178078Y669581D01*
Y670871D01*
X1177156Y671793D01*
X1175207D01*
X1173594Y673406D01*
X1173309D01*
G01X1191500Y690680D02*
X1183520D01*
X1183470Y690730D01*
X1182164D01*
X1182114Y690680D01*
X1179953D01*
X1179916Y690717D01*
X1178283D01*
X1176724Y692276D01*
X1176529D01*
G01X1176496Y695415D02*
X1177085D01*
X1178629Y693871D01*
X1180627D01*
X1181968Y692530D01*
X1192470D01*
G01X1187948Y687552D02*
X1182132D01*
X1182116Y687536D01*
X1178113D01*
X1173384Y692265D01*
G01X1177500Y725000D02*
Y723838D01*
X1174924Y721262D01*
Y719956D01*
X1175000Y719880D01*
Y719080D01*
X1173400Y717480D01*
G01X1170812Y720442D02*
Y719116D01*
X1171774Y718154D01*
Y716880D01*
X1171775Y716879D01*
Y715857D01*
X1170248Y714330D01*
G54D79*
G01X706966Y133284D02*
Y129784D01*
G01X1151000Y708000D02*
X1151320Y708320D01*
Y711146D01*
X1151352Y711178D01*
G01X1170250Y685500D02*
Y683000D01*
X1169800Y682550D01*
Y682200D01*
G01X1170218Y695284D02*
X1173252D01*
X1173365Y695397D01*
G01X1170218Y689284D02*
X1173226D01*
X1173389Y689121D01*
G54D89*
G01X129919Y1009860D02*
Y984419D01*
X110484Y964984D01*
X41335D01*
X13529Y937178D01*
Y796895D01*
X27004Y783420D01*
G01X122049Y1009860D02*
Y981549D01*
X110626Y970126D01*
X42375D01*
X10629Y938380D01*
Y794509D01*
X68147Y736991D01*
Y734920D01*
G01X125984Y1009860D02*
Y982984D01*
X110034Y967034D01*
X41334D01*
X12079Y937779D01*
Y795112D01*
X71846Y735345D01*
Y726562D01*
G01X145669Y1009860D02*
Y1000508D01*
X146729Y999448D01*
Y991406D01*
X117323Y962000D01*
X42453D01*
X16429Y935976D01*
Y799426D01*
X26335Y789520D01*
X27431D01*
X49369Y767582D01*
G01X149604Y1009860D02*
Y991104D01*
X118900Y960400D01*
X42904D01*
X17879Y935375D01*
Y801123D01*
X23820Y795182D01*
G01X133859Y1009860D02*
Y1001182D01*
X131677Y999000D01*
Y984126D01*
X111051Y963500D01*
X41902D01*
X14979Y936577D01*
Y798825D01*
X73246Y740558D01*
X75656D01*
X77699Y738515D01*
G01X75432Y735059D02*
X27071Y783420D01*
X27004D01*
G01X157479Y1009860D02*
Y993928D01*
X121051Y957500D01*
X44106D01*
X20779Y934173D01*
Y805045D01*
X46304Y779520D01*
G01X87772Y735059D02*
X78377Y744454D01*
X74548D01*
X58954Y760048D01*
Y761144D01*
X30507Y789591D01*
X29411D01*
X23820Y795182D01*
G01X153544Y1009860D02*
Y992044D01*
X120450Y958950D01*
X43505D01*
X19329Y934774D01*
Y803295D01*
X60404Y762220D01*
Y760649D01*
X75049Y746004D01*
X81420D01*
X86704Y740720D01*
G01X161419Y1009860D02*
Y992242D01*
X124982Y955805D01*
X44462D01*
X22229Y933572D01*
Y806795D01*
X40204Y788820D01*
G01X173229Y1009860D02*
Y997326D01*
X126523Y950620D01*
X45430D01*
X26579Y931769D01*
Y812371D01*
X63167Y775783D01*
G01X165354Y1009860D02*
Y993554D01*
X125750Y953950D01*
X44658D01*
X23679Y932971D01*
Y808673D01*
X35747Y796605D01*
G01X169289Y1009860D02*
Y995437D01*
X126352Y952500D01*
X45259D01*
X25129Y932370D01*
Y810672D01*
X30312Y805489D01*
G01X68762Y764239D02*
Y767039D01*
X30312Y805489D01*
G01X177164Y1009860D02*
Y999210D01*
X127124Y949170D01*
X46031D01*
X28029Y931168D01*
Y814922D01*
X75496Y767455D01*
X77469D01*
X77504Y767420D01*
G01X185039Y1009860D02*
Y1001539D01*
X128949Y945449D01*
X52310D01*
X30929Y924068D01*
Y818995D01*
X36904Y813020D01*
G01X181104Y1009860D02*
Y999937D01*
X128066Y946899D01*
X51709D01*
X29479Y924669D01*
Y817297D01*
X43456Y803320D01*
G01X52804Y943220D02*
X32379Y922795D01*
Y849745D01*
X38804Y843320D01*
G01X34304Y897720D02*
Y895696D01*
X38500Y891500D01*
G01X83849Y735513D02*
X76359Y743003D01*
X73948D01*
X49369Y767582D01*
G01X46304Y779520D02*
X62104Y763720D01*
Y761672D01*
X65272Y758504D01*
G01X64683Y762056D02*
Y764341D01*
X40204Y788820D01*
G01X35747Y796605D02*
X66704Y765648D01*
Y762848D01*
X68910Y760642D01*
G01X36904Y813020D02*
Y813019D01*
X54614Y795309D01*
Y792439D01*
X75923Y771130D01*
X82894D01*
X85304Y768720D01*
G01X43456Y803320D02*
X52604Y794172D01*
Y792398D01*
X75322Y769680D01*
X79959D01*
X85037Y764602D01*
Y764139D01*
X85672Y763504D01*
G01X44804Y837220D02*
Y837320D01*
X38804Y843320D01*
G01X52720Y832220D02*
X35304D01*
G01X37211Y881115D02*
X39157Y879169D01*
Y876444D01*
X39000Y876287D01*
Y867000D01*
X54355Y851645D01*
X56102D01*
X63879Y843868D01*
Y839879D01*
G01X317758Y581297D02*
Y588829D01*
X254350Y652237D01*
Y669860D01*
X232610Y691600D01*
X201529D01*
X201479Y691650D01*
X201478D01*
X196911Y696217D01*
Y696218D01*
X154303Y738826D01*
Y743672D01*
X154304Y743673D01*
Y751762D01*
X71729Y834337D01*
Y839200D01*
X57034Y853895D01*
Y856966D01*
X50131Y863869D01*
X46705D01*
X41250Y869324D01*
Y875355D01*
X42229Y876334D01*
Y888072D01*
X40650Y889651D01*
X40349D01*
X38500Y891500D01*
G01X48750Y868500D02*
X52024D01*
X52304Y868220D01*
G01X48750Y872500D02*
X51780D01*
X52000Y872720D01*
G01X113222Y831222D02*
X78625Y865819D01*
X47931D01*
X45250Y868500D01*
G01D02*
X43200Y870550D01*
Y874200D01*
X46500Y877500D01*
Y879500D01*
G01X45250Y872500D02*
Y873408D01*
X50510Y878668D01*
X51896D01*
G01X46500Y879500D02*
X47708Y880708D01*
X49792D01*
X51304Y882220D01*
G01X48020Y910938D02*
X47804Y910722D01*
Y906720D01*
G01X43520Y910938D02*
Y908004D01*
X43804Y907720D01*
G01X48020Y914438D02*
X52770Y919188D01*
Y927420D01*
G01X43520Y914438D02*
X47880Y918798D01*
G01D02*
X50270Y921188D01*
Y929186D01*
G01X63167Y775783D02*
X73946Y765004D01*
X79861D01*
X80624Y764241D01*
G01X94804Y718720D02*
Y756720D01*
X88671Y762853D01*
Y769730D01*
X59697Y798704D01*
Y802302D01*
X57304Y804695D01*
Y815720D01*
G01X61304Y815220D02*
Y805915D01*
X91304Y775915D01*
Y762978D01*
X99804Y754478D01*
Y727120D01*
G01X313000Y582000D02*
Y584247D01*
X312680Y584567D01*
Y587543D01*
X249850Y650373D01*
Y667996D01*
X230746Y687100D01*
X199664D01*
X192411Y694353D01*
Y694354D01*
X149500Y737265D01*
Y746748D01*
X86729Y809518D01*
X85602Y810645D01*
X85474D01*
X76547Y819572D01*
Y821952D01*
X67221Y831278D01*
X62746D01*
X61804Y832220D01*
X52720D01*
G01X314930Y585500D02*
Y588475D01*
X252100Y651305D01*
Y668928D01*
X231678Y689350D01*
X200597D01*
X200547Y689400D01*
X200546D01*
X194661Y695285D01*
Y695286D01*
X152000Y737947D01*
Y750247D01*
X87952Y814295D01*
X85006D01*
X83879Y815422D01*
Y817802D01*
X67886Y833795D01*
X65006D01*
X63879Y834922D01*
Y839879D01*
G01X51896Y878668D02*
Y878604D01*
X56500Y874000D01*
G01X112500Y835000D02*
X79730Y867770D01*
X62730D01*
X56500Y874000D01*
G01X61520Y910938D02*
X60804Y910222D01*
Y907720D01*
G01X57020Y910938D02*
X56804Y910722D01*
Y907220D01*
G01X52520Y910938D02*
X52304Y910722D01*
Y906720D01*
G01X66020Y910938D02*
X64804Y909722D01*
Y907720D01*
G01X57770Y932686D02*
Y926520D01*
G01X57020Y914438D02*
X57770Y915188D01*
Y926520D01*
G01X55270Y929186D02*
Y920220D01*
G01X52520Y914438D02*
X55270Y917188D01*
Y920220D01*
G01X62770Y932686D02*
Y926400D01*
G01D02*
Y917688D01*
X66020Y914438D01*
G01X60270Y929186D02*
Y918820D01*
G01X61520Y914438D02*
X60270Y915688D01*
Y918820D01*
G01X52770Y932686D02*
Y927420D01*
G01X93604Y938795D02*
X52804D01*
G01Y943220D02*
X105804D01*
G01X68147Y734920D02*
Y722511D01*
G01X71846Y726562D02*
Y722426D01*
G01X77699Y738515D02*
X80272Y735942D01*
Y735103D01*
G01X77504Y767420D02*
X80168D01*
X83112Y764476D01*
Y760720D01*
G01X72304Y869720D02*
X74504Y871920D01*
X87104D01*
G01X76304Y869720D02*
X86157D01*
X86182Y869695D01*
X88026D01*
X88051Y869720D01*
X94904D01*
G01X94804Y718720D02*
Y708220D01*
G01X99804Y727120D02*
Y709220D01*
G01X92365Y735040D02*
Y735059D01*
X86704Y740720D01*
G01X321780Y575000D02*
Y587565D01*
X256300Y653045D01*
Y670668D01*
X233418Y693550D01*
X202337D01*
X202287Y693600D01*
X202286D01*
X198861Y697025D01*
Y697026D01*
X156253Y739634D01*
Y742864D01*
X156254Y742865D01*
Y753174D01*
X84221Y825207D01*
Y831279D01*
G01Y836078D02*
Y831279D01*
G01X87104Y871920D02*
X87129Y871945D01*
X106502D01*
X126554Y891997D01*
Y895470D01*
G01X94904Y869720D02*
X106328D01*
X129100Y892492D01*
Y892924D01*
G01X99804Y912970D02*
Y908220D01*
X103312Y904712D01*
G01X99804Y916470D02*
Y920520D01*
G01D02*
Y923470D01*
X109054Y932720D01*
G01X108804Y938795D02*
X93604D01*
G01X113222Y831222D02*
X158204Y786240D01*
Y742057D01*
X158203Y742056D01*
Y740442D01*
X200811Y697834D01*
Y697833D01*
X203094Y695550D01*
X203095D01*
X203145Y695500D01*
X234226D01*
X258250Y671476D01*
Y653853D01*
X323929Y588174D01*
Y481439D01*
X323903Y481413D01*
Y479799D01*
X323929Y479773D01*
Y478950D01*
X325873Y477006D01*
G01X146304Y804220D02*
Y805658D01*
X119853Y832109D01*
Y833723D01*
X119854Y833724D01*
Y839146D01*
X110500Y848500D01*
G01X325854Y480606D02*
X325879Y480631D01*
Y588982D01*
X260200Y654661D01*
Y672284D01*
X234984Y697500D01*
X203902D01*
X202761Y698641D01*
Y698642D01*
X160154Y741249D01*
Y787346D01*
X112500Y835000D01*
G01X146500Y808220D02*
X121804Y832916D01*
Y842196D01*
X115500Y848500D01*
G01X109054Y898620D02*
Y892720D01*
G01X114054D02*
Y900220D01*
G01X103804Y912970D02*
Y908220D01*
X109054Y902970D01*
Y898620D01*
G01X106554Y895720D02*
Y901470D01*
X103312Y904712D01*
G01X111804Y912970D02*
Y906720D01*
X114054Y904470D01*
Y900220D01*
G01X111554Y896220D02*
Y903970D01*
X107804Y907720D01*
Y908820D01*
G01D02*
Y912970D01*
G01X115804Y916470D02*
Y924924D01*
X117202Y926322D01*
G01X115804Y912970D02*
X116554Y912220D01*
Y909020D01*
G01X116600Y929924D02*
Y928868D01*
X112476Y924744D01*
G01X111804Y916470D02*
Y924072D01*
X112476Y924744D01*
G01X107804Y920720D02*
Y916470D01*
G01Y920720D02*
Y923220D01*
X113479Y928895D01*
Y931895D01*
X114054Y932470D01*
G01X103804Y916470D02*
Y924322D01*
X106803Y927321D01*
G01X111554Y929720D02*
X109202D01*
X106803Y927321D01*
G01X118109Y1009860D02*
Y999568D01*
X119925Y997752D01*
Y987925D01*
X115500Y983500D01*
G01X114174Y1009860D02*
Y998326D01*
X115625Y996875D01*
Y987625D01*
X111000Y983000D01*
Y981500D01*
G01X135804Y912970D02*
Y909720D01*
X129804Y903720D01*
Y893628D01*
X129100Y892924D01*
G01X124054Y892220D02*
Y897920D01*
G01X119054Y892720D02*
Y901520D01*
G01X131804Y912970D02*
Y910220D01*
X126554Y904970D01*
Y895470D01*
G01X127804Y912970D02*
Y908271D01*
X124054Y904521D01*
Y897920D01*
G01X121600Y895266D02*
X121554Y895312D01*
Y906470D01*
X122904Y907820D01*
G01X123804Y912970D02*
Y908720D01*
X122904Y907820D01*
G01X119804Y912970D02*
Y908720D01*
X119054Y907970D01*
Y901520D01*
G01X116554Y895720D02*
Y909020D01*
G01X119804Y920320D02*
Y916470D01*
G01X121598Y929924D02*
Y927614D01*
X119804Y925820D01*
Y920320D01*
G01X131404Y925520D02*
X129629Y927295D01*
Y932145D01*
X129054Y932720D01*
G01X131804Y916470D02*
Y925120D01*
X131404Y925520D01*
G01X127804Y916470D02*
Y920520D01*
G01D02*
Y928632D01*
X126554Y929882D01*
G01X123804Y916470D02*
Y925720D01*
G01D02*
Y932221D01*
X124098Y932515D01*
G01X117202Y926322D02*
X119099Y928219D01*
Y932516D01*
G01X135804Y920020D02*
Y925220D01*
X131554Y929470D01*
G01X135804Y916470D02*
Y920020D01*
G01X157500Y867500D02*
X158000Y867000D01*
Y815500D01*
X163000Y810500D01*
Y741161D01*
X204711Y699450D01*
X235792D01*
X262150Y673092D01*
Y655469D01*
X327829Y589790D01*
Y575171D01*
X334555Y568445D01*
Y548500D01*
G01X175993Y559938D02*
X184000Y567945D01*
Y643000D01*
X221500Y680500D01*
X230000D01*
G01X188295Y301209D02*
Y297209D01*
G01X195295Y301709D02*
X194795Y298709D01*
X193841Y297755D01*
G01X184295Y305709D02*
X185039Y304965D01*
Y295209D01*
G01X195295Y307709D02*
X191795Y304209D01*
Y295709D01*
X191295Y295209D01*
G01X183795Y311709D02*
X184295Y312209D01*
Y322209D01*
G01X195795Y313709D02*
Y315709D01*
X192795Y318709D01*
Y321709D01*
G01X188295Y315209D02*
X186614Y316890D01*
Y319028D01*
G01X189795Y308709D02*
X191295Y310209D01*
Y317709D01*
X190295Y318709D01*
G01X369555Y470800D02*
Y472555D01*
X376930Y479930D01*
Y550889D01*
X359869Y567950D01*
X351501D01*
X331229Y588222D01*
Y591199D01*
X265550Y656878D01*
Y674950D01*
X222075Y718425D01*
X200074D01*
X200000Y718500D01*
X194500Y724000D01*
G01X365940Y464200D02*
Y471459D01*
X375480Y480999D01*
Y550288D01*
X359268Y566500D01*
X350900D01*
X329779Y587621D01*
Y590598D01*
X264100Y656277D01*
Y673900D01*
X221500Y716500D01*
X212500D01*
G01X204500Y721000D02*
X205500Y720000D01*
X226081D01*
X268825Y677256D01*
Y657705D01*
X334129Y592401D01*
Y589424D01*
X352703Y570850D01*
X361071D01*
X381500Y550421D01*
Y534000D01*
G01X229000Y493500D02*
Y496945D01*
X229055Y497000D01*
G01X231200Y509800D02*
X233600D01*
X233700Y509700D01*
X234755D01*
G01X228319Y524798D02*
Y521464D01*
X227755Y520900D01*
G01X221000Y723000D02*
X225132D01*
X270375Y677757D01*
Y658216D01*
X338091Y590500D01*
X343472D01*
X384000Y549972D01*
Y536592D01*
X384046Y536546D01*
G01X220118Y729409D02*
Y725129D01*
G03X221000Y723000I3011J0D01*
G01X242003Y506327D02*
X242000Y506330D01*
Y509600D01*
G01X241200Y501800D02*
X244079Y504679D01*
X245205D01*
G01X246613Y501365D02*
X250165D01*
X250200Y501400D01*
G01X237055Y513500D02*
Y516500D01*
G01X234155Y530700D02*
Y527168D01*
X234185Y527138D01*
G01X241600Y522500D02*
X239600Y520500D01*
Y519645D01*
X239555Y519600D01*
Y519500D01*
G01X238500Y705000D02*
X267000Y676500D01*
Y657479D01*
X332679Y591800D01*
Y588823D01*
X352102Y569400D01*
X360470D01*
X379000Y550870D01*
Y531000D01*
G01X259055Y500500D02*
Y497200D01*
G01X260288Y514589D02*
Y513689D01*
X258592Y511993D01*
G01X249000Y513700D02*
X250000Y512700D01*
Y510855D01*
X250055Y510800D01*
G01X256055Y531016D02*
X255835Y530796D01*
Y527930D01*
X255829Y527924D01*
G01X263400Y527900D02*
X261000Y525500D01*
X260555D01*
G01X253679Y523137D02*
Y520037D01*
G01X260605Y519245D02*
X261330Y519970D01*
X264615D01*
G01X248855Y532300D02*
Y529780D01*
X248045Y528970D01*
G01X263555Y534500D02*
X262200D01*
X259000Y537700D01*
G01X261255Y549000D02*
X263700Y551445D01*
Y552500D01*
G01X265455Y544853D02*
X262347D01*
X262200Y545000D01*
G01X252055Y548760D02*
X248740D01*
X248700Y548800D01*
G01X255500Y552600D02*
Y551055D01*
X257555Y549000D01*
G01X264665Y487730D02*
X264655Y487720D01*
Y367240D01*
X286996Y344899D01*
Y344898D01*
X287844Y344050D01*
X324503D01*
X324953Y343600D01*
Y340300D01*
X325403Y339850D01*
X326303D01*
X326753Y340300D01*
Y343600D01*
X327203Y344050D01*
X328103D01*
X328553Y343600D01*
Y340300D01*
X329003Y339850D01*
X329903D01*
X330353Y340300D01*
Y343600D01*
X330803Y344050D01*
X331703D01*
X332153Y343600D01*
Y341443D01*
X332653Y340943D01*
X333453D01*
X333953Y341443D01*
Y343600D01*
X334403Y344050D01*
X335500D01*
X337525Y342025D01*
X346550D01*
X350000Y338575D01*
X389230D01*
X389730Y339075D01*
Y339107D01*
X390798Y340175D01*
X392312D01*
X392687Y339800D01*
X396554D01*
X397071Y339283D01*
X398555D01*
G01X271655Y528210D02*
X268380Y524935D01*
Y370475D01*
X269986Y368869D01*
Y368233D01*
X269195Y367442D01*
Y366806D01*
X269832Y366169D01*
X270468D01*
X271259Y366960D01*
X271895D01*
X272532Y366323D01*
Y365687D01*
X271741Y364896D01*
Y364260D01*
X272378Y363623D01*
X273014D01*
X273805Y364414D01*
X274441D01*
X275078Y363777D01*
Y363141D01*
X274287Y362350D01*
Y361714D01*
X274924Y361077D01*
X275560D01*
X276351Y361868D01*
X276987D01*
X277624Y361231D01*
Y360595D01*
X276833Y359804D01*
Y359164D01*
X289047Y346950D01*
X339735D01*
X341610Y345075D01*
X366425D01*
X368825Y342675D01*
X389197D01*
X389597Y343075D01*
X395130D01*
X397201Y345146D01*
X397555D01*
G01X275055Y517960D02*
Y516062D01*
X271280Y512287D01*
Y371677D01*
X272308Y370649D01*
X272944D01*
X274252Y371957D01*
X274888D01*
X275525Y371320D01*
Y370684D01*
X274217Y369376D01*
Y368740D01*
X274854Y368103D01*
X275490D01*
X276798Y369411D01*
X277434D01*
X278071Y368774D01*
Y368138D01*
X276763Y366830D01*
Y366194D01*
X277400Y365557D01*
X278036D01*
X279344Y366865D01*
X279980D01*
X280617Y366228D01*
Y365592D01*
X279309Y364284D01*
Y363648D01*
X279946Y363011D01*
X280582D01*
X281890Y364319D01*
X282526D01*
X283163Y363682D01*
Y363046D01*
X281855Y361738D01*
Y361102D01*
X282492Y360465D01*
X283128D01*
X284436Y361773D01*
X285072D01*
X285709Y361136D01*
Y360500D01*
X284401Y359192D01*
Y358556D01*
X285038Y357919D01*
X285674D01*
X286982Y359227D01*
X287618D01*
X288255Y358590D01*
Y357954D01*
X286947Y356646D01*
Y356010D01*
X289927Y353030D01*
X337756D01*
X340936Y349850D01*
X340937D01*
X342812Y347975D01*
X368100D01*
X370500Y345575D01*
X387994D01*
X389219Y346800D01*
X393061D01*
G01X408857Y345865D02*
X407951Y346771D01*
X395613D01*
X393367Y344525D01*
X388995D01*
X388595Y344125D01*
X369899D01*
X367499Y346525D01*
X342211D01*
X340336Y348400D01*
X340335D01*
X337155Y351580D01*
X289326D01*
X269830Y371076D01*
Y521385D01*
X271866Y523421D01*
X271986D01*
G01X266055Y531725D02*
X266930Y530850D01*
Y368218D01*
X266929Y368217D01*
Y367017D01*
X288446Y345500D01*
X339105D01*
X340980Y343625D01*
X365375D01*
X367775Y341225D01*
X389798D01*
X390198Y341625D01*
X392913D01*
X393017Y341521D01*
X403466D01*
X404065Y342120D01*
X404965D01*
G01X279997Y514179D02*
X275630Y509812D01*
Y386375D01*
X276759Y385246D01*
X277395D01*
X279034Y386885D01*
X279670D01*
X280307Y386248D01*
Y385612D01*
X278668Y383973D01*
Y383337D01*
X279305Y382700D01*
X279941D01*
X281580Y384339D01*
X282216D01*
X282853Y383702D01*
Y383066D01*
X281214Y381427D01*
Y380791D01*
X281851Y380154D01*
X282487D01*
X284126Y381793D01*
X284762D01*
X285399Y381156D01*
Y380520D01*
X283760Y378881D01*
Y378245D01*
X286680Y375325D01*
Y374689D01*
X284598Y372607D01*
Y371971D01*
X285235Y371334D01*
X285871D01*
X287953Y373416D01*
X288589D01*
X289226Y372779D01*
Y372143D01*
X287144Y370061D01*
Y369425D01*
X287781Y368788D01*
X288417D01*
X290499Y370870D01*
X291135D01*
X291772Y370233D01*
Y369597D01*
X289690Y367515D01*
Y366879D01*
X290327Y366242D01*
X290963D01*
X293045Y368324D01*
X293681D01*
X294318Y367687D01*
Y367051D01*
X292236Y364969D01*
Y364333D01*
X292873Y363696D01*
X293509D01*
X295591Y365778D01*
X296227D01*
X296864Y365141D01*
Y364505D01*
X294782Y362423D01*
Y361787D01*
X295419Y361150D01*
X296055D01*
X298137Y363232D01*
X298773D01*
X299410Y362595D01*
Y361959D01*
X297328Y359877D01*
Y359241D01*
X297965Y358604D01*
X298601D01*
X300683Y360686D01*
X301318D01*
X303354Y358650D01*
G01X282555Y540700D02*
X284963Y538292D01*
Y530139D01*
X279055Y524231D01*
Y515960D01*
X274180Y511085D01*
Y380335D01*
X275208Y379307D01*
X275844D01*
X277798Y381261D01*
X278434D01*
X279071Y380624D01*
Y379988D01*
X277117Y378034D01*
Y377398D01*
X277754Y376761D01*
X278390D01*
X280344Y378715D01*
X280980D01*
X281617Y378078D01*
Y377442D01*
X279663Y375488D01*
Y374852D01*
X280300Y374215D01*
X280936D01*
X282890Y376169D01*
X283526D01*
X284163Y375532D01*
Y374896D01*
X282209Y372942D01*
Y372306D01*
X298585Y355930D01*
X338958D01*
X342138Y352750D01*
X342139D01*
X343737Y351152D01*
X373513D01*
X374355Y350310D01*
X376600D01*
G01X385425Y348740D02*
X384095Y347410D01*
X374368D01*
X372353Y349425D01*
X343413D01*
X341538Y351300D01*
X341537D01*
X338357Y354480D01*
X294905D01*
X293489Y355896D01*
Y356532D01*
X294358Y357401D01*
Y358037D01*
X293721Y358674D01*
X293085D01*
X292216Y357805D01*
X291580D01*
X290943Y358442D01*
Y359078D01*
X291812Y359947D01*
Y360583D01*
X291175Y361220D01*
X290539D01*
X289670Y360351D01*
X289034D01*
X288397Y360988D01*
Y361624D01*
X289266Y362493D01*
Y363129D01*
X288629Y363766D01*
X287993D01*
X287124Y362897D01*
X286488D01*
X285851Y363534D01*
Y364170D01*
X286720Y365039D01*
Y365675D01*
X286083Y366312D01*
X285447D01*
X284578Y365443D01*
X283942D01*
X283305Y366080D01*
Y366716D01*
X284174Y367585D01*
Y368221D01*
X283537Y368858D01*
X282901D01*
X282032Y367989D01*
X281396D01*
X280759Y368626D01*
Y369262D01*
X281628Y370131D01*
Y370767D01*
X280991Y371404D01*
X280355D01*
X279486Y370535D01*
X278850D01*
X278213Y371172D01*
Y371808D01*
X279082Y372677D01*
Y373313D01*
X278445Y373950D01*
X277809D01*
X276940Y373081D01*
X276304D01*
X275667Y373718D01*
Y374354D01*
X276536Y375223D01*
Y375859D01*
X275899Y376496D01*
X275263D01*
X274394Y375627D01*
X273758D01*
X272730Y376655D01*
Y511686D01*
X276622Y515578D01*
Y515579D01*
X277605Y516562D01*
Y524832D01*
X283380Y530607D01*
Y533653D01*
X283038Y533995D01*
Y536850D01*
G01X314588Y361696D02*
X313147Y363137D01*
Y366337D01*
X312510Y366974D01*
X311874D01*
X308136Y363236D01*
X307500D01*
X306863Y363873D01*
Y364509D01*
X310601Y368247D01*
Y368883D01*
X309964Y369520D01*
X309328D01*
X305590Y365782D01*
X304954D01*
X302029Y368707D01*
Y369343D01*
X305382Y372697D01*
Y373333D01*
X304745Y373970D01*
X304109D01*
X300756Y370616D01*
X300120D01*
X284013Y386723D01*
Y387359D01*
X287517Y390862D01*
Y391498D01*
X286880Y392135D01*
X286244D01*
X282740Y388632D01*
X282104D01*
X281467Y389269D01*
Y389905D01*
X284971Y393408D01*
Y394044D01*
X284334Y394681D01*
X283698D01*
X280194Y391178D01*
X279558D01*
X278530Y392206D01*
Y507738D01*
X284098Y513306D01*
Y513307D01*
X284551Y513760D01*
Y518760D01*
X283103Y520208D01*
G01X308474Y373060D02*
X306017Y375517D01*
Y375518D01*
X304869Y376666D01*
X304113D01*
X300436Y372989D01*
X299800D01*
X299163Y373626D01*
Y374262D01*
X302840Y377939D01*
Y378575D01*
X302203Y379212D01*
X301567D01*
X297890Y375535D01*
X297254D01*
X296617Y376172D01*
Y376808D01*
X300294Y380485D01*
Y381121D01*
X299657Y381758D01*
X299021D01*
X295344Y378081D01*
X294708D01*
X294071Y378718D01*
Y379354D01*
X297748Y383031D01*
Y383667D01*
X297111Y384304D01*
X296475D01*
X292798Y380627D01*
X292162D01*
X291525Y381264D01*
Y381900D01*
X295202Y385577D01*
Y386213D01*
X294565Y386850D01*
X293929D01*
X290252Y383173D01*
X289616D01*
X288979Y383810D01*
Y384446D01*
X292656Y388123D01*
Y388759D01*
X292019Y389396D01*
X291383D01*
X287706Y385719D01*
X287070D01*
X286433Y386356D01*
Y386992D01*
X290110Y390669D01*
Y391305D01*
X279980Y401435D01*
Y507134D01*
X285548Y512702D01*
Y512706D01*
X286555Y513713D01*
Y519272D01*
X286588Y519305D01*
G01X424605Y357676D02*
X423143D01*
X421393Y355926D01*
X420556D01*
X418481Y353851D01*
Y353190D01*
X417280Y351989D01*
X411544D01*
X410719Y351164D01*
X401401D01*
X398513Y354052D01*
X344939D01*
X343341Y355650D01*
X343340D01*
X340160Y358830D01*
X306765D01*
X304810Y360785D01*
Y363875D01*
X302905Y365780D01*
X302269D01*
X300591Y364102D01*
X299955D01*
X299318Y364739D01*
Y365375D01*
X300996Y367053D01*
Y367689D01*
X300359Y368326D01*
X299723D01*
X298045Y366648D01*
X297409D01*
X296772Y367285D01*
Y367921D01*
X298450Y369599D01*
Y370235D01*
X297813Y370872D01*
X297177D01*
X295499Y369194D01*
X294863D01*
X294226Y369831D01*
Y370467D01*
X295904Y372145D01*
Y372781D01*
X295267Y373418D01*
X294631D01*
X292953Y371740D01*
X292317D01*
X291680Y372377D01*
Y373013D01*
X293358Y374691D01*
Y375327D01*
X292721Y375964D01*
X292085D01*
X290407Y374286D01*
X289771D01*
X289134Y374923D01*
Y375559D01*
X290812Y377237D01*
Y377873D01*
X290175Y378510D01*
X289539D01*
X287861Y376832D01*
X287225D01*
X286588Y377469D01*
Y378105D01*
X288266Y379783D01*
Y380419D01*
X277929Y390756D01*
X277928D01*
X277080Y391604D01*
Y508339D01*
X282576Y513835D01*
Y516589D01*
X282626Y516639D01*
G01X264655Y511100D02*
Y487740D01*
X264665Y487730D01*
G01X271655Y528210D02*
X274945Y531500D01*
X275555D01*
G01X275055Y517960D02*
Y521825D01*
G01X278676Y539500D02*
X276442Y537266D01*
Y533342D01*
X277480Y532304D01*
Y528915D01*
X271986Y523421D01*
G01X266055Y531725D02*
X266635Y532305D01*
Y537120D01*
G01X278000Y543700D02*
X275121D01*
X272571Y541150D01*
G01X278367Y535140D02*
X280707Y532800D01*
X280800D01*
G01X274200Y537200D02*
X270755D01*
X269555Y536000D01*
G01X271400Y547800D02*
Y544641D01*
X271425Y544616D01*
X271451D01*
G01X342500Y653000D02*
X325325Y670175D01*
Y820917D01*
X280067Y866175D01*
X280066D01*
X279100Y867141D01*
Y953642D01*
X278549Y954193D01*
Y958001D01*
X278050Y958500D01*
G01X346402Y653004D02*
Y653098D01*
X327275Y672225D01*
Y821725D01*
X281050Y867950D01*
Y954450D01*
X280500Y955000D01*
G01X279528Y1009860D02*
Y993178D01*
X282500Y990206D01*
Y870000D01*
X328725Y823775D01*
Y674153D01*
X350000Y652878D01*
G01X291530Y525407D02*
X289964Y523841D01*
Y513018D01*
X288449Y511503D01*
Y511501D01*
X282880Y505932D01*
Y410075D01*
X297494Y395461D01*
Y394825D01*
X294497Y391828D01*
Y391192D01*
X295134Y390555D01*
X295770D01*
X298767Y393552D01*
X299403D01*
X300040Y392915D01*
Y392279D01*
X297043Y389282D01*
Y388646D01*
X297680Y388009D01*
X298316D01*
X301313Y391006D01*
X301949D01*
X302586Y390369D01*
Y389733D01*
X299589Y386736D01*
Y386100D01*
X300226Y385463D01*
X300862D01*
X303859Y388460D01*
X304495D01*
X305132Y387823D01*
Y387187D01*
X302135Y384190D01*
Y383554D01*
X302772Y382917D01*
X303408D01*
X306405Y385914D01*
X307041D01*
X307678Y385277D01*
Y384641D01*
X304681Y381644D01*
Y381008D01*
X305318Y380371D01*
X305954D01*
X308951Y383368D01*
X309587D01*
X326680Y366275D01*
X336200D01*
G01X292555Y533043D02*
X294905Y530693D01*
Y513855D01*
X285780Y504730D01*
Y411277D01*
X286808Y410249D01*
X287444D01*
X291442Y414247D01*
X292078D01*
X292715Y413610D01*
Y412974D01*
X288717Y408976D01*
Y408340D01*
X289354Y407703D01*
X289990D01*
X293988Y411701D01*
X294624D01*
X295261Y411064D01*
Y410428D01*
X291263Y406430D01*
Y405794D01*
X291900Y405157D01*
X292536D01*
X296534Y409155D01*
X297170D01*
X297807Y408518D01*
Y407882D01*
X293809Y403884D01*
Y403248D01*
X326517Y370540D01*
X370783D01*
X371233Y370990D01*
Y371938D01*
X371683Y372388D01*
X372583D01*
X373033Y371938D01*
Y370990D01*
X373483Y370540D01*
X374383D01*
X374833Y370990D01*
Y371938D01*
X375283Y372388D01*
X376183D01*
X376633Y371938D01*
Y370990D01*
X377083Y370540D01*
X377983D01*
X378433Y370990D01*
Y371938D01*
X378883Y372388D01*
X379783D01*
X380233Y371938D01*
Y370990D01*
X380683Y370540D01*
X381583D01*
X382033Y370990D01*
Y371938D01*
X382483Y372388D01*
X383383D01*
X383833Y371938D01*
Y370990D01*
X384283Y370540D01*
X385183D01*
X385633Y370990D01*
Y371938D01*
X386083Y372388D01*
X386983D01*
X387433Y371938D01*
Y370990D01*
X387883Y370540D01*
X388783D01*
X389233Y370990D01*
Y371938D01*
X389683Y372388D01*
X390583D01*
X391033Y371938D01*
Y370990D01*
X391483Y370540D01*
X392383D01*
X392833Y370990D01*
Y371938D01*
X393283Y372388D01*
X394183D01*
X394633Y371938D01*
Y370990D01*
X395083Y370540D01*
X397060D01*
X404100Y363500D01*
X418055D01*
X419942Y361613D01*
X420668D01*
G01X291755Y529000D02*
Y528153D01*
X293455Y526453D01*
Y522882D01*
X293005Y522432D01*
X291864D01*
X291414Y521982D01*
Y521082D01*
X291864Y520632D01*
X293005D01*
X293455Y520182D01*
Y519282D01*
X293005Y518832D01*
X291864D01*
X291414Y518382D01*
Y517482D01*
X291864Y517032D01*
X293005D01*
X293455Y516582D01*
Y514457D01*
X289899Y510901D01*
Y510900D01*
X284330Y505331D01*
Y410676D01*
X326506Y368500D01*
X343815D01*
X344000Y368315D01*
G01X325100Y364000D02*
X319635D01*
X319134Y364501D01*
Y365137D01*
X322131Y368134D01*
Y368770D01*
X321494Y369407D01*
X320858D01*
X317861Y366410D01*
X317225D01*
X316588Y367047D01*
Y367683D01*
X319585Y370680D01*
Y371316D01*
X318948Y371953D01*
X318312D01*
X315315Y368956D01*
X314679D01*
X314042Y369593D01*
Y370229D01*
X317039Y373226D01*
Y373862D01*
X316402Y374499D01*
Y374501D01*
X312833Y378070D01*
X305565D01*
X289459Y394176D01*
Y394812D01*
X292423Y397776D01*
Y398412D01*
X291786Y399049D01*
X291150D01*
X288186Y396085D01*
X287550D01*
X286913Y396722D01*
Y397358D01*
X289877Y400322D01*
Y400958D01*
X289240Y401595D01*
X288604D01*
X285640Y398631D01*
X285004D01*
X284367Y399268D01*
Y399904D01*
X287331Y402868D01*
Y403504D01*
X286694Y404141D01*
X286058D01*
X283094Y401177D01*
X282458D01*
X281430Y402205D01*
Y506533D01*
X286998Y512101D01*
Y512104D01*
X288513Y513619D01*
Y522566D01*
X286555Y524524D01*
G01X293273Y509500D02*
X287230Y503457D01*
Y421585D01*
X303402Y405413D01*
Y404777D01*
X299186Y400561D01*
Y399925D01*
X299823Y399288D01*
X300459D01*
X304675Y403504D01*
X305311D01*
X305948Y402867D01*
Y402231D01*
X301732Y398015D01*
Y397379D01*
X302369Y396742D01*
X303005D01*
X307221Y400958D01*
X307857D01*
X308494Y400321D01*
Y399685D01*
X304278Y395469D01*
Y394833D01*
X304915Y394196D01*
X305551D01*
X309767Y398412D01*
X310403D01*
X316132Y392683D01*
Y392047D01*
X311916Y387831D01*
Y387195D01*
X312553Y386558D01*
X313189D01*
X317405Y390774D01*
X318041D01*
X318678Y390137D01*
Y389501D01*
X314462Y385285D01*
Y384649D01*
X315099Y384012D01*
X315735D01*
X319951Y388228D01*
X320587D01*
X326316Y382499D01*
Y381863D01*
X322100Y377647D01*
Y377011D01*
X322737Y376374D01*
X323373D01*
X327589Y380590D01*
X328225D01*
X328862Y379953D01*
Y379317D01*
X324646Y375101D01*
Y374465D01*
X325283Y373828D01*
X325919D01*
X330135Y378044D01*
X330771D01*
X334977Y373838D01*
X363662D01*
G01X293495Y494300D02*
Y497810D01*
X292525Y498780D01*
G01X292045Y504897D02*
X293279D01*
X294692Y503484D01*
G01X281500Y523500D02*
X281000Y523000D01*
Y518265D01*
X282626Y516639D01*
G01X292555Y533043D02*
Y536510D01*
X292605Y536560D01*
G01X303354Y358650D02*
X304624Y357380D01*
X339559D01*
X342739Y354200D01*
X342740D01*
X344338Y352602D01*
X395749D01*
X398055Y350296D01*
G01X308474Y373060D02*
X310016Y371518D01*
X310017D01*
X319805Y361730D01*
X341362D01*
X344542Y358550D01*
X344543D01*
X346066Y357027D01*
X392385D01*
X392553Y357195D01*
X401580D01*
X404935Y353840D01*
G01X323060Y285250D02*
X325250D01*
X326500Y284000D01*
X327500D01*
X328000Y284500D01*
Y285000D01*
G01X320500Y291750D02*
Y290000D01*
X322000Y288500D01*
X327250D01*
X329500Y290750D01*
G01D02*
X330500Y289750D01*
Y287000D01*
G01X412794Y353739D02*
X411754D01*
X410129Y352114D01*
X404362D01*
X402635Y353841D01*
Y354669D01*
X401559Y355745D01*
X393155D01*
X392987Y355577D01*
X362490D01*
X362489Y355576D01*
X345466D01*
X343942Y357100D01*
X343941D01*
X340761Y360280D01*
X316004D01*
X314588Y361696D01*
G01X408857Y353739D02*
X403671Y358925D01*
X398297D01*
X395672Y361550D01*
X391744D01*
X389520Y359326D01*
Y359325D01*
X388672Y358477D01*
X346667D01*
X345144Y360000D01*
X345143D01*
X341963Y363180D01*
X334500D01*
X333680Y364000D01*
X325100D01*
G01X330000Y84250D02*
X334000D01*
G01D02*
X337500D01*
G01X341000Y116290D02*
Y119040D01*
X340000Y120040D01*
G01X342900D02*
X347000D01*
G01X340000D02*
X342900D01*
G01X346000Y116290D02*
Y119040D01*
X347000Y120040D01*
G01X340679Y189000D02*
X344954Y184725D01*
X346644D01*
X346869Y184500D01*
X350040D01*
G01X351320Y194520D02*
X349520D01*
X345929Y198111D01*
Y201611D01*
X345540Y202000D01*
G01X344040Y207250D02*
Y203500D01*
X345540Y202000D01*
G01X340790Y197500D02*
X342540D01*
X347040Y193000D01*
G01X340790D02*
X345590Y188200D01*
X346129D01*
G01D02*
X349657D01*
X351731Y190274D01*
G01X336200Y366275D02*
X340919D01*
X345744Y361450D01*
X345745D01*
X347268Y359927D01*
X348718D01*
X349168Y360377D01*
Y364280D01*
X349618Y364730D01*
X350518D01*
X350968Y364280D01*
Y360377D01*
X351418Y359927D01*
X388070D01*
X391533Y363390D01*
X395566D01*
X399081Y359875D01*
X404359D01*
X408359Y355875D01*
X418735D01*
X420536Y357676D01*
X420668D01*
G01X344000Y368315D02*
X348865D01*
X351000Y366180D01*
X353139D01*
X353589Y365730D01*
Y361827D01*
X354039Y361377D01*
X354939D01*
X355389Y361827D01*
Y365730D01*
X355839Y366180D01*
X356739D01*
X357189Y365730D01*
Y361827D01*
X357639Y361377D01*
X358539D01*
X358989Y361827D01*
Y365730D01*
X359439Y366180D01*
X360339D01*
X360789Y365730D01*
Y361827D01*
X361239Y361377D01*
X362139D01*
X362589Y361827D01*
Y365730D01*
X363039Y366180D01*
X374457D01*
X374907Y365730D01*
Y361827D01*
X375357Y361377D01*
X376257D01*
X376707Y361827D01*
Y365730D01*
X377157Y366180D01*
X378057D01*
X378507Y365730D01*
Y361827D01*
X378957Y361377D01*
X379857D01*
X380307Y361827D01*
Y365730D01*
X380757Y366180D01*
X381657D01*
X382107Y365730D01*
Y361827D01*
X382557Y361377D01*
X383457D01*
X383907Y361827D01*
Y365792D01*
X387085Y368970D01*
X396885D01*
X405800Y360055D01*
X406356Y359500D01*
X414555D01*
X416555Y357500D01*
G01X387669Y387355D02*
X386542Y388482D01*
X382938D01*
X341065Y430355D01*
Y522990D01*
X340055Y524000D01*
G01X386455Y392000D02*
X386447Y392008D01*
X381463D01*
X345020Y428451D01*
Y471469D01*
X343300Y473189D01*
Y482105D01*
X345613Y484418D01*
Y523108D01*
X342971Y525750D01*
G01X416731Y385237D02*
X415093D01*
X413468Y383612D01*
X410875D01*
X409925Y382662D01*
X407789D01*
X406451Y384000D01*
X399755D01*
X397380Y381625D01*
X395174D01*
X395149Y381600D01*
X387453D01*
X385440Y383613D01*
Y385151D01*
X383560Y387032D01*
X382337D01*
X338300Y431069D01*
Y457455D01*
X336855Y458900D01*
G01X387519Y379375D02*
X386054D01*
X333048Y432381D01*
Y522933D01*
X330491Y525490D01*
G01X334055Y526000D02*
X334498Y525557D01*
Y461257D01*
X336855Y458900D01*
G01X344055Y529000D02*
X347063Y525992D01*
Y483816D01*
X344750Y481503D01*
Y473790D01*
X346470Y472070D01*
Y429052D01*
X374522Y401000D01*
X383000D01*
G01X341055Y534500D02*
X341136D01*
X348513Y527123D01*
Y483215D01*
X346200Y480902D01*
Y474391D01*
X349065Y471526D01*
Y439665D01*
X364430Y424300D01*
G01X352917Y443700D02*
X352900Y443717D01*
Y443755D01*
X351740Y444915D01*
Y476348D01*
X350613Y477475D01*
X348880D01*
X347650Y478705D01*
Y480301D01*
X349963Y482614D01*
Y529192D01*
X344655Y534500D01*
G01X349830Y179800D02*
X351729D01*
X356229Y184300D01*
X358080D01*
G01D02*
X360538Y181842D01*
X363668D01*
X368308Y177202D01*
G01X362260Y179910D02*
Y177379D01*
X362036Y177155D01*
G01D02*
X362274D01*
X365429Y174000D01*
X366729D01*
G01X358858Y177128D02*
Y177071D01*
X361929Y174000D01*
G01X358760Y179910D02*
X358858Y179812D01*
Y177128D01*
G01X354410Y176460D02*
X355370Y175500D01*
X357358D01*
X358848Y174010D01*
G01X371485Y177175D02*
X371254D01*
X361929Y186500D01*
X355429D01*
X353429Y184500D01*
X350040D01*
G01X358879Y192929D02*
X355000D01*
X353465Y194464D01*
Y195075D01*
X350040Y198500D01*
G01X348540Y207250D02*
Y200000D01*
X350040Y198500D01*
G01X361987Y189747D02*
X361540Y189300D01*
X358440D01*
G01X361679Y199389D02*
X361029Y198739D01*
Y192500D01*
X358440Y189911D01*
Y189300D01*
G01X358850Y196050D02*
X357540Y197360D01*
Y199500D01*
G01D02*
Y206750D01*
X357040Y207250D01*
G01X353040D02*
Y202500D01*
G01D02*
X352915Y202375D01*
Y197835D01*
X355090Y195660D01*
G01X355139Y190099D02*
X352738Y192500D01*
X347540D01*
X347040Y193000D01*
G01X379500Y377000D02*
X372500D01*
X371000Y378500D01*
X355000D01*
X347750Y385750D01*
Y392750D01*
X351000Y396000D01*
Y396250D01*
G01X346750Y396000D02*
X347000Y396250D01*
X351000D01*
G01X404920Y393111D02*
X403658Y394373D01*
X400015D01*
X398308Y396080D01*
Y396260D01*
X395380Y399188D01*
Y401237D01*
X352917Y443700D01*
G01X356555Y513000D02*
X355230Y511675D01*
Y505407D01*
X357880Y502757D01*
Y498458D01*
X357780Y498358D01*
Y454275D01*
X375100Y436955D01*
G01X352095Y524040D02*
Y478044D01*
X353190Y476949D01*
Y447065D01*
X359855Y440400D01*
G01D02*
X364161Y436094D01*
Y434507D01*
X395458Y403210D01*
Y402631D01*
X396674Y401415D01*
Y399238D01*
X399258Y396654D01*
Y396474D01*
X400309Y395423D01*
X402478D01*
X404103Y397048D01*
X404920D01*
G01X356055Y502000D02*
X356330Y501725D01*
Y451425D01*
X359455Y448300D01*
G01D02*
X374255Y433500D01*
Y428515D01*
X397358Y405412D01*
Y403419D01*
X398574Y402203D01*
Y401095D01*
X400896Y398773D01*
X406781D01*
X408508Y397048D01*
X408857D01*
G01X367500Y436355D02*
X354640Y449215D01*
Y477550D01*
X353780Y478410D01*
Y512276D01*
X354020Y512516D01*
Y528735D01*
X348255Y534500D01*
G01X357055Y507000D02*
X359330Y504725D01*
Y457502D01*
X369900Y446932D01*
G01X366255Y456700D02*
X361055Y461900D01*
Y496103D01*
X361155Y496203D01*
G01X361000Y925490D02*
X361500Y924990D01*
Y905000D01*
X362000Y904500D01*
G01X359000Y931500D02*
X361000Y929500D01*
Y925490D01*
G01X359000Y931500D02*
X360500Y933000D01*
Y938500D01*
X376000Y954000D01*
Y960000D01*
G01X362203Y1009860D02*
Y991341D01*
X361646Y990784D01*
G01X380829Y187850D02*
X379779Y186800D01*
X376140D01*
G01D02*
X374606Y188334D01*
Y189763D01*
G01X377929Y174000D02*
X377770D01*
X374560Y177210D01*
G01X373200Y179790D02*
Y178570D01*
X374560Y177210D01*
G01X371429Y203750D02*
X372179D01*
X374929Y201000D01*
Y197611D01*
X375040Y197500D01*
G01D02*
Y193346D01*
X374606Y192912D01*
G01X377855Y300110D02*
Y297922D01*
X380702Y295075D01*
X383374D01*
X390949Y287500D01*
X408249D01*
X418234Y277515D01*
X428985D01*
X436500Y270000D01*
Y261799D01*
X427701Y253000D01*
X417500D01*
G01X428100Y266500D02*
Y268624D01*
X421724Y275000D01*
X418500D01*
X407800Y285700D01*
X388523D01*
X380723Y293500D01*
X374000D01*
G01X376600Y350310D02*
X382065D01*
X382907Y351152D01*
X393103D01*
X393755Y350500D01*
G01X363662Y373838D02*
X414679D01*
X418555Y369962D01*
Y367663D01*
X420668Y365550D01*
G01X364430Y424300D02*
Y424200D01*
X365830Y422800D01*
X371056D01*
X393930Y399926D01*
Y399294D01*
X396674Y396550D01*
Y396370D01*
X399621Y393423D01*
X402168D01*
X404205Y391386D01*
X413343D01*
X415555Y389174D01*
X416731D01*
G01X374600Y413540D02*
X370275D01*
G01X374900Y404300D02*
X372700Y406500D01*
X371745D01*
X371710Y406535D01*
G01X367800Y420300D02*
X369555Y418545D01*
Y417500D01*
G01X367000Y412000D02*
X368527D01*
X370575Y409952D01*
G01X375100Y436955D02*
X376205Y435850D01*
Y428616D01*
X398308Y406513D01*
Y403813D01*
X400983Y401138D01*
Y400985D01*
G01X369900Y446932D02*
X377655Y439177D01*
Y429217D01*
X399258Y407614D01*
Y404348D01*
X400434Y403172D01*
X402733D01*
X404920Y400985D01*
G01X400983Y397048D02*
X397624Y400407D01*
Y401809D01*
X396408Y403025D01*
Y404311D01*
X371187Y429532D01*
Y432668D01*
X367500Y436355D01*
G01X366255Y456700D02*
X379289Y443666D01*
Y429634D01*
X400983Y407940D01*
Y404922D01*
G01X404920D02*
Y406791D01*
X395330Y416381D01*
X394623D01*
X381305Y429699D01*
Y446735D01*
X365940Y462100D01*
Y464200D01*
G01X408857Y404922D02*
X408133D01*
X382755Y430300D01*
Y448600D01*
X369555Y461800D01*
Y470800D01*
G01X371000Y866500D02*
X384500Y853000D01*
Y723742D01*
X393742Y714500D01*
X396000D01*
G01X392500Y718500D02*
X386621Y724379D01*
Y855461D01*
X376041Y866041D01*
G01X363000Y931500D02*
X364500Y930000D01*
Y926000D01*
X363000Y924500D01*
Y909162D01*
X363480Y908682D01*
Y907783D01*
G01X375500Y906000D02*
X379750D01*
G01X375600Y909600D02*
Y906100D01*
X375500Y906000D01*
G01Y901500D02*
X379750D01*
G01X371900Y901400D02*
X375400D01*
X375500Y901500D01*
G01X369500Y936500D02*
Y936223D01*
X366000Y932723D01*
Y916500D01*
X365500Y916000D01*
G01X369341Y916117D02*
X368000Y917458D01*
Y932000D01*
G01X383250Y910750D02*
Y913850D01*
X371100Y926000D01*
G01X381000Y919500D02*
X376000Y924500D01*
X375500D01*
X371000Y929000D01*
Y930000D01*
G01X369500Y936500D02*
Y940500D01*
X370500Y941500D01*
G01D02*
X383050Y954050D01*
Y967051D01*
X387500Y971501D01*
Y985622D01*
X387061Y986061D01*
G01X377000Y942000D02*
Y945500D01*
X385475Y953975D01*
Y967425D01*
X389500Y971450D01*
Y992000D01*
G01X377000Y942000D02*
Y941000D01*
X368000Y932000D01*
G01X363000Y931500D02*
Y936000D01*
G01D02*
Y938500D01*
X379500Y955000D01*
Y963500D01*
G01X392575Y924575D02*
X382325D01*
X379400Y927500D01*
X377000D01*
G01X370078Y1009860D02*
Y987900D01*
X364378Y982200D01*
Y980231D01*
X364396Y980213D01*
Y980109D01*
G01X374018Y1009860D02*
Y988840D01*
X366878Y981700D01*
Y977500D01*
G01X366143Y1009860D02*
Y991035D01*
X366678Y990500D01*
G01X396329Y227800D02*
Y228200D01*
X395029Y229500D01*
X393429D01*
G01X393929Y224750D02*
X396329Y227150D01*
Y227800D01*
G01X400000Y237500D02*
X401500Y239000D01*
Y243500D01*
X390500Y254500D01*
Y257500D01*
G01X399500Y240500D02*
X399000Y241000D01*
X397050D01*
X392500Y245550D01*
Y248000D01*
X390500Y250000D01*
G01X387500Y261000D02*
Y253000D01*
X390500Y250000D01*
G01X390100Y263600D02*
Y263400D01*
X390500Y263000D01*
Y257500D01*
G01X413429Y240250D02*
X414679Y241500D01*
X418252D01*
X438000Y261248D01*
Y271500D01*
X430535Y278965D01*
X418835D01*
X408800Y289000D01*
X391500D01*
X383500Y297000D01*
X381500D01*
G01X391555Y338350D02*
X393406D01*
X395381Y336375D01*
X396680D01*
X397276Y335779D01*
X405635D01*
X407360Y334054D01*
X408857D01*
G01X390230Y349327D02*
X386012D01*
X385425Y348740D01*
G01X386500Y362100D02*
X388100D01*
X391797Y365797D01*
X392991D01*
G01X387669Y387355D02*
X387865D01*
X389390Y385829D01*
Y384143D01*
X390458Y383075D01*
X395442D01*
X398016Y385649D01*
X406146D01*
X408183Y383612D01*
X409531D01*
X410482Y384563D01*
Y385224D01*
X412120Y386862D01*
X421342D01*
X422293Y385911D01*
Y385250D01*
X423931Y383612D01*
X424592D01*
X426904Y381300D01*
X428542D01*
G01X387519Y379375D02*
X398180D01*
X400580Y376975D01*
X402318D01*
X403555Y375738D01*
X413468D01*
X414419Y376689D01*
Y377350D01*
X416744Y379675D01*
X417405D01*
X418615Y380885D01*
Y382615D01*
X419500Y383500D01*
X422000D01*
X423000Y382500D01*
X423405D01*
X424605Y381300D01*
G01X379500Y377000D02*
X397000D01*
X399212Y374788D01*
X416455D01*
X418943Y377276D01*
Y377937D01*
X419503Y378497D01*
Y380135D01*
X420668Y381300D01*
G01X383000Y401000D02*
X383549D01*
X389449Y395100D01*
X394708D01*
X402259Y387549D01*
X405735D01*
X407360Y389174D01*
X408857D01*
G01X380555Y407000D02*
X385105Y402450D01*
X389206D01*
X392480Y399176D01*
Y398693D01*
X394623Y396550D01*
X395150D01*
X399227Y392473D01*
X401621D01*
X404920Y389174D01*
G01X392900Y388000D02*
X395893D01*
X396490Y388597D01*
G01X412794Y389174D02*
X411297D01*
X409572Y387449D01*
X407080D01*
X406230Y386599D01*
X400928D01*
X397402Y390125D01*
X397261D01*
X397164Y390222D01*
X395816D01*
X395719Y390125D01*
X388330D01*
X386455Y392000D01*
G01X400983Y416733D02*
X394555Y423161D01*
Y426000D01*
G01D02*
Y431250D01*
G01X400200Y893925D02*
X396802D01*
X395675Y892798D01*
Y889326D01*
X396500Y888500D01*
G01X383250Y906000D02*
Y910750D01*
G01Y901500D02*
X386000Y904250D01*
Y914500D01*
X381000Y919500D01*
G01X422098Y948630D02*
Y944098D01*
X421000Y943000D01*
Y937942D01*
X407633Y924575D01*
X392575D01*
G01X384000Y926500D02*
X385000Y927500D01*
X402500D01*
G01X393000Y944250D02*
Y949000D01*
G01D02*
Y949750D01*
X398250Y955000D01*
G01X393703Y1009860D02*
Y990297D01*
X396500Y987500D01*
X410500D01*
G01X406099Y214950D02*
Y219830D01*
X401929Y224000D01*
Y225300D01*
G01X413429Y236750D02*
X414429Y235750D01*
Y232000D01*
X413429Y231000D01*
X411429D01*
X409429Y229000D01*
Y220700D01*
X408429Y219700D01*
G01D02*
Y215785D01*
X409249Y214965D01*
G01X406929Y230250D02*
X407179D01*
X410091Y233162D01*
X412767D01*
G01X402929Y230250D02*
X401929Y229250D01*
Y225300D01*
G01X402929Y233750D02*
X404500Y235321D01*
Y242694D01*
X409306Y247500D01*
X412000D01*
X417500Y253000D01*
G01X622500Y696500D02*
Y640500D01*
X553500Y571500D01*
Y383000D01*
X540196Y369696D01*
Y344795D01*
X510500Y315099D01*
Y307700D01*
X495900Y293100D01*
X475400D01*
X473425Y295075D01*
X467571D01*
X464646Y298000D01*
X455925D01*
X446500Y288575D01*
X442452D01*
X436925Y294102D01*
Y294798D01*
X434998Y296725D01*
X405080D01*
X401855Y293500D01*
G01X408857Y330117D02*
X406555Y327815D01*
Y326750D01*
G01D02*
X406805Y326500D01*
X410330D01*
G01X406555Y320500D02*
X408908D01*
X412555Y324147D01*
Y327579D01*
X414419Y329443D01*
Y331864D01*
X416609Y334054D01*
X416731D01*
G01X401055Y381500D02*
X401255Y381300D01*
X412794D01*
G01X405555Y379000D02*
X406130Y379575D01*
X413498D01*
X415211Y381288D01*
X415234Y381300D01*
X416731D01*
G01X404555Y412000D02*
X407132Y409423D01*
Y408285D01*
X408283Y407134D01*
X408944D01*
X410582Y405496D01*
Y399260D01*
X412794Y397048D01*
G01X406055Y423700D02*
X407055Y422700D01*
X409126D01*
X410582Y421244D01*
Y408772D01*
X412707Y406647D01*
X413368D01*
X415006Y405009D01*
Y400411D01*
X416157Y399260D01*
X416818D01*
X418943Y397135D01*
Y396474D01*
X420581Y394836D01*
X425320D01*
X427156Y393000D01*
X428555D01*
G01X404920Y416733D02*
X399555Y422098D01*
Y426000D01*
G01X406055Y423700D02*
Y423725D01*
X404980Y424800D01*
Y426665D01*
X404855Y426790D01*
Y430200D01*
X404555Y430500D01*
G01X406555Y428300D02*
X407355D01*
X408880Y429825D01*
X413397D01*
X415006Y428216D01*
Y408949D01*
X415755Y408200D01*
G01X399555Y426000D02*
Y431250D01*
G01X407250Y893500D02*
X408000D01*
X428500Y914000D01*
Y938000D01*
X429823Y939323D01*
Y951832D01*
X420655Y961000D01*
X420277D01*
X417277Y964000D01*
X416000D01*
G01X407250Y889500D02*
X410000D01*
X430000Y909500D01*
Y937000D01*
X431273Y938273D01*
Y952727D01*
X420000Y964000D01*
G01X403750Y893500D02*
X403325Y893925D01*
X400200D01*
G01X397600Y892000D02*
Y890900D01*
X400000Y888500D01*
G01X403750Y889500D02*
X402750Y888500D01*
X400000D01*
G01X407250Y897500D02*
X408000D01*
X427000Y916500D01*
Y939000D01*
X428373Y940373D01*
Y951231D01*
X420104Y959500D01*
X416092D01*
X416046Y959546D01*
G01X407250Y909500D02*
X408296D01*
X422500Y923704D01*
Y942000D01*
X424023Y943523D01*
Y949428D01*
X421362Y952089D01*
X414215D01*
G01X407250Y905500D02*
X410500Y908750D01*
Y909653D01*
X424000Y923153D01*
Y941000D01*
X425473Y942473D01*
Y950029D01*
X421002Y954500D01*
X410500D01*
G01X407250Y901500D02*
X414500Y908750D01*
Y911602D01*
X425500Y922602D01*
Y940000D01*
X426923Y941423D01*
Y950630D01*
X420553Y957000D01*
X413500D01*
G01X403750Y897500D02*
X398245D01*
X396600Y895855D01*
G01X403750Y901500D02*
Y900500D01*
X402955Y899705D01*
X400428D01*
X400298Y899575D01*
X398702D01*
X398572Y899705D01*
X396330D01*
G01X403750Y905500D02*
X403500D01*
X399500Y901500D01*
G01X403750Y909500D02*
X400500D01*
X399500Y908500D01*
G01D02*
X396500Y905500D01*
Y904000D01*
G01X402500Y927500D02*
X408507D01*
X419407Y938400D01*
Y947593D01*
X418500Y948500D01*
G01X401000Y944250D02*
Y946750D01*
X403250Y949000D01*
G01X414000Y977500D02*
X408575Y972075D01*
Y953702D01*
X410277Y952000D01*
X414126D01*
G01X409000Y944250D02*
Y948750D01*
X408250Y949500D01*
G01X410500Y954500D02*
Y970852D01*
X411574Y971926D01*
G01X405000Y944250D02*
X405704Y944954D01*
Y952046D01*
G01X397000Y944250D02*
Y948500D01*
X398000Y949500D01*
G01X400750Y952000D02*
X400500D01*
X398000Y949500D01*
G01X409448Y1009860D02*
Y999552D01*
X418425Y990575D01*
Y978777D01*
X411574Y971926D01*
G01X409000Y992000D02*
X411500D01*
X415525Y987975D01*
Y982702D01*
X414398Y981575D01*
X411925D01*
X410000Y983500D01*
G01X401573Y1009860D02*
Y999427D01*
X409000Y992000D01*
G01X403900Y990500D02*
X404900Y989500D01*
X411500D01*
X413600Y987400D01*
Y983500D01*
G01X403900Y990500D02*
X402000D01*
X397638Y994862D01*
Y1009860D01*
G01X405513D02*
Y1000987D01*
X416975Y989525D01*
Y980475D01*
X414000Y977500D01*
G01X437679Y113500D02*
X426786D01*
G01D02*
X418929D01*
X418192Y114237D01*
G01D02*
X415552Y116877D01*
Y136221D01*
G01X421540Y118500D02*
X423686Y120646D01*
Y126215D01*
G01X421540Y123500D02*
Y128450D01*
X421590Y128500D01*
G01X418040Y132500D02*
X418702Y133162D01*
Y136221D01*
G01X425229Y128700D02*
Y135991D01*
X425000Y136220D01*
G01X428040Y133000D02*
Y136110D01*
X428116Y136186D01*
Y136218D01*
G01X422940Y133000D02*
Y135132D01*
X421851Y136221D01*
G01X428040Y123500D02*
X428840D01*
X431251Y125911D01*
X431348D01*
G01X417729Y145500D02*
Y147847D01*
X418700Y148818D01*
G01X428149D02*
Y147810D01*
X429939Y146020D01*
G01X412929Y145500D02*
Y146196D01*
X415551Y148818D01*
G01X424999D02*
X425040Y148859D01*
X425940Y151550D01*
G01X423329Y145620D02*
X424999Y148030D01*
Y148818D01*
G01X425940Y151550D02*
X429940D01*
G01X420219Y151810D02*
X421280Y150749D01*
X421850Y148818D01*
G01X542500Y215500D02*
X541150Y216850D01*
X539500D01*
X539050Y216400D01*
Y213950D01*
X538600Y213500D01*
X537700D01*
X537250Y213950D01*
Y216400D01*
X536800Y216850D01*
X518184D01*
X514183Y212849D01*
X512817D01*
X512816Y212850D01*
X469185D01*
X466368Y210033D01*
X466367D01*
X466285Y209951D01*
X465451D01*
X465444Y209944D01*
X457230D01*
X455897Y208611D01*
X451719D01*
X445924Y214406D01*
X431094D01*
X429447Y216053D01*
X427053D01*
X424979Y218127D01*
G01X425126Y221124D02*
Y220970D01*
X428047Y218049D01*
G01X510500Y237300D02*
X510300D01*
X508542Y235542D01*
X448573D01*
X448123Y235092D01*
Y231500D01*
X447623Y231000D01*
X446823D01*
X446323Y231500D01*
Y235092D01*
X445873Y235542D01*
X444973D01*
X444523Y235092D01*
Y231000D01*
X444023Y230500D01*
X443223D01*
X442723Y231000D01*
Y235092D01*
X442273Y235542D01*
X441373D01*
X440923Y235092D01*
Y234294D01*
X440473Y233844D01*
X439573D01*
X439123Y234294D01*
Y235092D01*
X438673Y235542D01*
X437152D01*
X427527Y225917D01*
X423740D01*
X420856Y223033D01*
X418195D01*
X417104Y221942D01*
Y219662D01*
X415551Y218109D01*
G01X540500Y211000D02*
X537500D01*
X533500Y215000D01*
X523350D01*
X522900Y214550D01*
Y211950D01*
X522450Y211500D01*
X521550D01*
X521100Y211950D01*
Y214550D01*
X520650Y215000D01*
X519000D01*
X515000Y211000D01*
X469669D01*
X466963Y208294D01*
X458534D01*
X458403Y208425D01*
X457055D01*
X456291Y207661D01*
X450346D01*
X444552Y213455D01*
X430500D01*
X428968Y214987D01*
X426486D01*
X424998Y216475D01*
X420354D01*
X418729Y218100D01*
G01X445000Y223000D02*
X444000D01*
X442239Y221239D01*
X432232D01*
X430222Y223249D01*
X424245D01*
X421850Y220854D01*
Y218109D01*
G01X555000Y219500D02*
X553284Y221216D01*
X544687D01*
X541971Y218500D01*
X517500D01*
X513500Y214500D01*
X468501D01*
X465684Y211683D01*
X465683D01*
X465601Y211601D01*
X460169D01*
X459462Y210894D01*
X454034D01*
X449572Y215356D01*
X431792D01*
X429711Y217437D01*
Y219781D01*
X428172Y221320D01*
G01X425532Y228137D02*
X423437D01*
X422630Y227330D01*
Y227232D01*
G01X506000Y239500D02*
X503692Y237192D01*
X432357D01*
X426147Y230982D01*
G01X420714Y225190D02*
X420524Y225000D01*
X416750D01*
G01D02*
X416500Y225250D01*
Y229500D01*
G01X524000Y243500D02*
X504378D01*
X499520Y238642D01*
X431381D01*
X420144Y227405D01*
X419000D01*
G01X418729Y221268D02*
X420435D01*
X424134Y224967D01*
X428189D01*
X431636Y228414D01*
X435316D01*
X435855Y227875D01*
X438180D01*
X438380Y228075D01*
X446575D01*
X452392Y233892D01*
X538508D01*
X544294Y239678D01*
X566822D01*
X567500Y239000D01*
X568000D01*
G01X425250Y314500D02*
X422398Y317352D01*
Y319657D01*
X421055Y321000D01*
G01X422952Y325500D02*
X424990D01*
X426523Y327033D01*
G01D02*
Y334772D01*
X427555Y335804D01*
X428654D01*
X430555Y337705D01*
Y340070D01*
X432365Y341880D01*
G01X421055Y321000D02*
X420727Y321328D01*
Y327672D01*
X422980Y329925D01*
Y332429D01*
X424605Y334054D01*
G01X416731Y330117D02*
X416390D01*
X415273Y329000D01*
Y326783D01*
X414773Y326283D01*
G01D02*
X414555Y326065D01*
Y323000D01*
X413555Y322000D01*
G01X424000Y377000D02*
X428500D01*
G01X415755Y408200D02*
X418456Y405499D01*
Y404835D01*
X420094Y403197D01*
X420755D01*
X422880Y401072D01*
Y400270D01*
X424605Y398545D01*
Y397048D01*
G01X427028Y833000D02*
X430988D01*
X431278Y832710D01*
X431298D01*
G01X427028Y842000D02*
X430078D01*
X430878Y842800D01*
G01X427028Y828500D02*
X428428Y829900D01*
X435878D01*
X436978Y831000D01*
G01X427028Y837500D02*
X430978D01*
G01X427028Y846500D02*
X429278D01*
X431126Y848348D01*
G01X427028Y855500D02*
X430091Y858563D01*
X431466D01*
G01X427028Y851000D02*
X429878D01*
X430978Y852100D01*
Y853103D01*
G01X427028Y860000D02*
X428028Y861000D01*
X432178D01*
X434178Y859000D01*
X437978D01*
G01X416046Y959546D02*
Y961231D01*
X414075Y963202D01*
Y966075D01*
X417000Y969000D01*
G01Y944250D02*
Y946000D01*
X414500Y948500D01*
G01X414126Y952000D02*
X414215Y952089D01*
G01X413000Y944250D02*
Y947000D01*
X412575Y947425D01*
Y950449D01*
X414126Y952000D01*
G01X418071Y974956D02*
X412625Y969510D01*
Y957875D01*
X413500Y957000D01*
G01X417323Y1009860D02*
Y997677D01*
X421325Y993675D01*
Y973325D01*
X417000Y969000D01*
G01X413388Y1009860D02*
Y998612D01*
X419875Y992125D01*
Y977500D01*
X418115Y975740D01*
Y975000D01*
X418071Y974956D01*
G01X421258Y1009860D02*
Y996242D01*
X422775Y994725D01*
Y970775D01*
X416000Y964000D01*
G01X425198Y1009860D02*
Y997802D01*
X426825Y996175D01*
Y970825D01*
X420000Y964000D01*
G01X433929Y100000D02*
X439029D01*
G01X441179Y113500D02*
X446179D01*
G01X433040Y119000D02*
Y122500D01*
X432540Y123000D01*
G01X443290Y118000D02*
Y118250D01*
X436040Y125500D01*
X434094D01*
X432542Y127052D01*
Y128500D01*
X433040Y128998D01*
Y132500D01*
G01X438540Y119000D02*
Y120100D01*
X435640Y123000D01*
G01X438540Y132500D02*
Y135280D01*
X437599Y136221D01*
G01X434450D02*
X433040Y134811D01*
Y132500D01*
G01X430040Y128500D02*
Y132100D01*
X430329Y132389D01*
Y135250D01*
X431329Y136250D01*
X431372D01*
X431407Y136285D01*
G01X443429Y132400D02*
X443540Y131670D01*
X440931Y129061D01*
G01X444540Y122500D02*
Y123783D01*
X442323Y126000D01*
G01X435040Y128000D02*
X437104D01*
X437945Y127159D01*
G01X443042Y139065D02*
X440836Y142771D01*
X440765Y144000D01*
Y145670D01*
G01X447349Y149920D02*
X445037D01*
X443928Y148811D01*
G01X454479Y150150D02*
X451419D01*
X449269Y152300D01*
X444192D01*
X443891Y151999D01*
G01X450255Y140258D02*
X446240D01*
X443933Y142565D01*
X443890D01*
G01X465429Y127000D02*
Y133688D01*
X459642Y139475D01*
X459626D01*
X458226Y140875D01*
X456048D01*
X453923Y143000D01*
X447435D01*
X444785Y145650D01*
X443909D01*
G01X433633Y145701D02*
X430059Y145900D01*
X429939Y146020D01*
G01X450989Y153950D02*
X445104D01*
X443936Y155118D01*
G01X448179Y171500D02*
X442429D01*
G01X458129Y167900D02*
X456642Y169387D01*
X443233D01*
X442257Y168411D01*
Y163072D01*
X443899Y161430D01*
G01X443882Y167737D02*
X452958D01*
X460338Y160357D01*
Y160227D01*
X461272Y159293D01*
G01X447489Y162190D02*
X445149Y164530D01*
X443899D01*
G01X447129Y157000D02*
X445139Y157010D01*
X443871Y158278D01*
G01X448179Y180000D02*
X447859Y180320D01*
X443879D01*
G01X448179Y175500D02*
X446541Y177138D01*
X443887D01*
G01X442099Y187600D02*
Y184810D01*
X440769Y183480D01*
G01X443919D02*
X444939Y184500D01*
X448179D01*
G01X443897Y192914D02*
X445325Y191486D01*
X453600D01*
X454043Y191043D01*
X458910D01*
X465807Y197940D01*
G01X564500Y217000D02*
X562485D01*
X556129Y210644D01*
X555493D01*
X553672Y212466D01*
X552966D01*
X552399Y211899D01*
Y211193D01*
X554220Y209371D01*
Y207905D01*
X552943Y206628D01*
X538650D01*
X537928Y207350D01*
X471184D01*
X468828Y204994D01*
X461000D01*
X460031Y204025D01*
X455805D01*
X454055Y202275D01*
X452255D01*
X452030Y202500D01*
X447186D01*
X443898Y199212D01*
G01X443897Y196063D02*
X447444Y192516D01*
X453016D01*
X454964Y194464D01*
X458964D01*
X460500Y196000D01*
G01X544500Y224500D02*
X543334D01*
X539160Y220326D01*
X514049D01*
X513599Y219876D01*
Y216950D01*
X513149Y216500D01*
X512249D01*
X511799Y216950D01*
Y219876D01*
X511349Y220326D01*
X510449D01*
X509999Y219876D01*
Y216950D01*
X509549Y216500D01*
X508649D01*
X508199Y216950D01*
Y219876D01*
X507749Y220326D01*
X506849D01*
X506399Y219876D01*
Y216950D01*
X505949Y216500D01*
X493305D01*
X492855Y216950D01*
Y219876D01*
X492405Y220326D01*
X491505D01*
X491055Y219876D01*
Y216950D01*
X490605Y216500D01*
X489705D01*
X489255Y216950D01*
Y219876D01*
X488805Y220326D01*
X487905D01*
X487455Y219876D01*
Y216950D01*
X487005Y216500D01*
X468167D01*
X465000Y213333D01*
X460192D01*
X458703Y211844D01*
X454428D01*
X449788Y216484D01*
X432963D01*
X431336Y218111D01*
G01X449500Y220925D02*
X446072D01*
X445922Y220775D01*
X443119D01*
X442633Y220289D01*
X442364D01*
X441809Y219734D01*
X436463D01*
X434838Y218109D01*
X434448D01*
G01X462500Y221500D02*
X462459D01*
X460500Y219541D01*
X456269D01*
X454403Y217675D01*
X453055D01*
X452621Y218109D01*
X437598D01*
G01X440009Y225589D02*
X438699Y226899D01*
X434444D01*
X434334Y226789D01*
G01X431321Y232880D02*
Y232069D01*
X429444Y230192D01*
G01X435659Y223364D02*
X434166Y224857D01*
X432307D01*
G01X444055Y295250D02*
X439950D01*
X439250Y294550D01*
X439200D01*
G01X429500Y307500D02*
Y311000D01*
G01X436555Y337000D02*
X437407D01*
X440353Y334054D01*
G01X432523Y330283D02*
X432338D01*
X430523Y328468D01*
Y327033D01*
G01D02*
X430556Y327000D01*
X434155D01*
G01X432555Y333500D02*
X432605Y333539D01*
Y337880D01*
G01X442555Y324000D02*
Y330500D01*
X441055Y332000D01*
X439500D01*
X437446Y334054D01*
X436416D01*
G01X448555Y338000D02*
X444299D01*
X444290Y337991D01*
G01X436055Y342000D02*
X436555D01*
X440555Y338000D01*
G01X432000Y366000D02*
X428992D01*
X428542Y365550D01*
G01X441498Y839000D02*
Y836220D01*
X438503Y833225D01*
X431813D01*
X431298Y832710D01*
G01X437478Y845016D02*
X433094D01*
X430878Y842800D01*
G01X443467Y839000D02*
Y835689D01*
X438778Y831000D01*
X436978D01*
G01X439530Y839000D02*
X432778D01*
X431278Y837500D01*
X430978D01*
G01X437478Y848953D02*
X431731D01*
X431126Y848348D01*
G01X441498Y853000D02*
Y855000D01*
X440718Y855780D01*
X434898D01*
X432115Y858563D01*
X431466D01*
G01X430936Y853145D02*
X430978Y853103D01*
G01X439530Y853000D02*
X431081D01*
X430978Y853103D01*
G01X443467Y853000D02*
Y856811D01*
X441278Y859000D01*
X437978D01*
G01X432000Y933500D02*
Y936500D01*
X432723Y937223D01*
Y970223D01*
G01X429133Y1009860D02*
Y986867D01*
X432723Y983277D01*
Y970223D01*
G01X446179Y113500D02*
Y112250D01*
X447654Y110775D01*
X454959D01*
X456084Y111900D01*
X465329D01*
G01X452159Y125370D02*
X449809D01*
X448669Y126510D01*
G01X448229Y133000D02*
X450209Y131220D01*
Y129230D01*
G01X445059Y127830D02*
X445639D01*
X447389Y129580D01*
G01X452929Y134500D02*
Y135748D01*
X454676Y137495D01*
G01X454929Y130000D02*
Y133500D01*
X456429Y135000D01*
G01X459929Y128500D02*
Y130500D01*
X457929Y132500D01*
G01X458349Y137762D02*
X456708D01*
X454136Y140334D01*
X453929D01*
G01X449429Y145500D02*
Y146000D01*
X451679Y148250D01*
G01X456309Y157740D02*
Y155830D01*
X455731Y155252D01*
Y154302D01*
G01X463429Y139000D02*
X462929D01*
X460829Y141100D01*
X460300D01*
G01X456929Y143000D02*
Y144500D01*
X454929Y146500D01*
G01X458839Y147900D02*
Y151750D01*
X459069Y151980D01*
G01X448179Y175500D02*
Y171500D01*
G01X455229Y162460D02*
X452119Y165570D01*
X451329D01*
G01X451669Y159120D02*
Y158623D01*
X453599Y156693D01*
G01X470679Y153500D02*
X469777D01*
X463497Y159780D01*
Y160215D01*
X462194Y161518D01*
X461835D01*
X458129Y165224D01*
Y167900D01*
G01X470679Y149000D02*
Y149366D01*
X461272Y158773D01*
Y159293D01*
G01X448179Y184500D02*
Y185250D01*
X449929Y187000D01*
X453929D01*
X455429Y185500D01*
G01X560468Y203788D02*
X560231D01*
X553443Y197000D01*
X543850D01*
X543400Y197450D01*
Y197900D01*
X542950Y198350D01*
X542050D01*
X541600Y197900D01*
Y197450D01*
X541150Y197000D01*
X539500D01*
X538000Y195500D01*
X536500D01*
X534000Y198000D01*
X469437D01*
X466103Y194666D01*
X465000D01*
X459609Y189275D01*
X450685D01*
X450196Y189764D01*
G01X550075Y212500D02*
Y209000D01*
X549575Y208500D01*
X547925D01*
X547475Y208950D01*
Y210500D01*
X546975Y211000D01*
X546175D01*
X545675Y210500D01*
Y208950D01*
X545225Y208500D01*
X539500D01*
X539000Y209000D01*
X531090D01*
X530640Y209450D01*
Y212900D01*
X530190Y213350D01*
X529290D01*
X528840Y212900D01*
Y209450D01*
X528390Y209000D01*
X527490D01*
X527040Y209450D01*
Y212900D01*
X526590Y213350D01*
X525690D01*
X525240Y212900D01*
Y209450D01*
X524790Y209000D01*
X470500D01*
X468144Y206644D01*
X459854D01*
X459354Y206144D01*
Y206126D01*
X458403Y205175D01*
X457055D01*
X456104Y206126D01*
Y206144D01*
X455604Y206644D01*
X446500D01*
X446000Y206144D01*
Y204400D01*
X446500Y203900D01*
X452929D01*
G01X564000Y212000D02*
X559819D01*
X558036Y210217D01*
Y209387D01*
X550724Y202075D01*
X548925D01*
X546500Y204500D01*
X538000D01*
X537000Y205500D01*
X483665D01*
X483215Y205050D01*
Y203750D01*
X482765Y203300D01*
X481865D01*
X481415Y203750D01*
Y205050D01*
X480965Y205500D01*
X480065D01*
X479615Y205050D01*
Y203750D01*
X479165Y203300D01*
X478265D01*
X477815Y203750D01*
Y205050D01*
X477365Y205500D01*
X476465D01*
X476015Y205050D01*
Y203750D01*
X475565Y203300D01*
X474665D01*
X474215Y203750D01*
Y205050D01*
X473765Y205500D01*
X472000D01*
X469500Y203000D01*
X461500D01*
X459950Y201450D01*
X458450D01*
X453104Y196104D01*
Y195075D01*
X452329Y194300D01*
G01X450237Y200375D02*
X448204D01*
X447063Y199234D01*
G01X562441Y199072D02*
X559344Y195975D01*
X554752D01*
X551777Y193000D01*
X536500D01*
X533500Y196000D01*
X472000D01*
X464139Y188139D01*
X448672D01*
X447047Y189764D01*
G01X448876Y195275D02*
X448930D01*
X451292Y197637D01*
G01X559961Y209419D02*
Y208800D01*
X555661Y204500D01*
X555483D01*
X551408Y200425D01*
X548241D01*
X545816Y202850D01*
X537316D01*
X536316Y203850D01*
X495443D01*
X494993Y203400D01*
Y202100D01*
X494543Y201650D01*
X493643D01*
X493193Y202100D01*
Y203400D01*
X492743Y203850D01*
X491843D01*
X491393Y203400D01*
Y202100D01*
X490943Y201650D01*
X490043D01*
X489593Y202100D01*
Y203400D01*
X489143Y203850D01*
X486850D01*
X484650Y201650D01*
X472816D01*
X472516Y201350D01*
X462184D01*
X460500Y199666D01*
Y196000D01*
G01X548000Y231000D02*
X547500D01*
X538476Y221976D01*
X504492D01*
X504042Y221526D01*
Y218600D01*
X503592Y218150D01*
X502692D01*
X502242Y218600D01*
Y221526D01*
X501792Y221976D01*
X500892D01*
X500442Y221526D01*
Y218600D01*
X499992Y218150D01*
X499092D01*
X498642Y218600D01*
Y221526D01*
X498192Y221976D01*
X497292D01*
X496842Y221526D01*
Y218600D01*
X496392Y218150D01*
X495492D01*
X495042Y218600D01*
Y221526D01*
X494592Y221976D01*
X485112D01*
X484662Y221526D01*
Y218950D01*
X484212Y218500D01*
X483312D01*
X482862Y218950D01*
Y221526D01*
X482412Y221976D01*
X481512D01*
X481062Y221526D01*
Y218950D01*
X480612Y218500D01*
X479712D01*
X479262Y218950D01*
Y221526D01*
X478812Y221976D01*
X477912D01*
X477462Y221526D01*
Y218950D01*
X477012Y218500D01*
X476112D01*
X475662Y218950D01*
Y221526D01*
X475212Y221976D01*
X474312D01*
X473862Y221526D01*
Y218950D01*
X473412Y218500D01*
X472512D01*
X472062Y218950D01*
Y221526D01*
X471612Y221976D01*
X470712D01*
X470262Y221526D01*
Y218950D01*
X469812Y218500D01*
X468912D01*
X468462Y218950D01*
Y221526D01*
X468012Y221976D01*
X466123D01*
X461000Y216853D01*
Y216500D01*
G01X458029Y213469D02*
Y213529D01*
X461000Y216500D01*
G01X564631Y234356D02*
X564453Y234178D01*
X557796D01*
X557399Y234575D01*
X546193D01*
X540118Y228500D01*
X512558D01*
X512108Y228050D01*
Y225726D01*
X511658Y225276D01*
X510758D01*
X510308Y225726D01*
Y228050D01*
X509858Y228500D01*
X508958D01*
X508508Y228050D01*
Y225726D01*
X508058Y225276D01*
X507158D01*
X506708Y225726D01*
Y228050D01*
X506258Y228500D01*
X505358D01*
X504908Y228050D01*
Y225726D01*
X504458Y225276D01*
X503558D01*
X503108Y225726D01*
Y228050D01*
X502658Y228500D01*
X501758D01*
X501308Y228050D01*
Y225726D01*
X500858Y225276D01*
X499958D01*
X499508Y225726D01*
Y228050D01*
X499058Y228500D01*
X498158D01*
X497708Y228050D01*
Y225726D01*
X497258Y225276D01*
X496358D01*
X495908Y225726D01*
Y228050D01*
X495458Y228500D01*
X493500D01*
X490486Y225486D01*
X463330D01*
X458769Y220925D01*
X449500D01*
G01X445892Y225995D02*
X447297Y227400D01*
X449514D01*
X449956Y226958D01*
X452509D01*
G01X559971Y237753D02*
X559581D01*
X559459Y237875D01*
X544825D01*
X539192Y232242D01*
X488942D01*
X488492Y231792D01*
Y229236D01*
X488042Y228786D01*
X487142D01*
X486692Y229236D01*
Y231792D01*
X486242Y232242D01*
X485342D01*
X484892Y231792D01*
Y229236D01*
X484442Y228786D01*
X483542D01*
X483092Y229236D01*
Y231792D01*
X482642Y232242D01*
X481742D01*
X481292Y231792D01*
Y229236D01*
X480842Y228786D01*
X479942D01*
X479492Y229236D01*
Y231792D01*
X479042Y232242D01*
X473493D01*
X473043Y231792D01*
Y229259D01*
X472593Y228809D01*
X471693D01*
X471243Y229259D01*
Y231792D01*
X470793Y232242D01*
X469893D01*
X469443Y231792D01*
Y229259D01*
X468993Y228809D01*
X468093D01*
X467643Y229259D01*
Y231792D01*
X467193Y232242D01*
X466293D01*
X465843Y231792D01*
Y229259D01*
X465393Y228809D01*
X464493D01*
X464043Y229259D01*
Y231792D01*
X463593Y232242D01*
X462693D01*
X462243Y231792D01*
Y229259D01*
X461793Y228809D01*
X460893D01*
X460443Y229259D01*
Y231792D01*
X459993Y232242D01*
X459093D01*
X458643Y231792D01*
Y229259D01*
X458193Y228809D01*
X457293D01*
X456843Y229259D01*
Y231792D01*
X456393Y232242D01*
X455242D01*
X453554Y230554D01*
Y229126D01*
X452509Y228081D01*
Y226958D01*
G01X573179Y233535D02*
X570433Y236281D01*
X561222D01*
X560769Y235828D01*
X558672D01*
X558275Y236225D01*
X545509D01*
X539784Y230500D01*
X493000D01*
X489636Y227136D01*
X477668D01*
X477218Y227586D01*
Y228000D01*
X476718Y228500D01*
X475918D01*
X475418Y228000D01*
Y227586D01*
X474968Y227136D01*
X462646D01*
X458392Y222882D01*
X454993D01*
X454725Y223150D01*
X446650D01*
X446500Y223000D01*
X445000D01*
G01X448055Y311500D02*
X449555Y313000D01*
Y317000D01*
X452223Y319668D01*
Y333983D01*
G01X452555Y316500D02*
X453173Y317118D01*
Y332462D01*
X453948Y333237D01*
Y334339D01*
X455388Y335779D01*
X456818D01*
X458543Y334054D01*
X460040D01*
G01X447055Y321500D02*
X449852Y324297D01*
Y330791D01*
X448227Y332416D01*
Y334054D01*
G01X456055Y321500D02*
X454378Y323177D01*
Y331861D01*
X456103Y333586D01*
Y334054D01*
G01X467255Y342600D02*
X464858Y340203D01*
X462252D01*
X460040Y337991D01*
G01X452555Y352900D02*
X452655D01*
X455715Y349840D01*
X455825D01*
G01X510179Y125500D02*
X506679Y122000D01*
X478783D01*
X472283Y115500D01*
X467500D01*
X465329Y113329D01*
Y111900D01*
G01X467679Y122000D02*
X465429Y124250D01*
Y127000D01*
G01X468600Y136700D02*
X468429Y140303D01*
X466500Y142232D01*
Y144500D01*
G01X462539Y144270D02*
X461685Y145124D01*
Y150386D01*
G01X470750Y144500D02*
X469500D01*
X466464Y147536D01*
Y151000D01*
G01X474250Y140000D02*
X472000D01*
X471000Y141000D01*
G01X462500Y154000D02*
Y153969D01*
X463969Y152500D01*
Y147610D01*
G01X466250Y169000D02*
X462500D01*
G01X471250Y157500D02*
X468700D01*
X467800Y158400D01*
X467600D01*
G01X465600Y162000D02*
X464500D01*
X462500Y164000D01*
G01X470750Y162000D02*
X465600D01*
G01X472000Y184500D02*
X473583Y182917D01*
X475216D01*
G01X476250Y186231D02*
X475216Y185197D01*
Y182917D01*
G01X467010Y186000D02*
X467510D01*
X470000Y188490D01*
Y188500D01*
G01X466250Y176000D02*
X463579D01*
X462679Y176900D01*
G01X465807Y197940D02*
X467567Y199700D01*
X473200D01*
X473500Y200000D01*
X546032D01*
X546532Y199500D01*
Y199275D01*
X547032Y198775D01*
X552092D01*
X556167Y202850D01*
X556345D01*
X563098Y209603D01*
X569745D01*
X571461Y207887D01*
G01X476281Y190291D02*
X475978Y189988D01*
X471488D01*
X470000Y188500D01*
G01X552435Y232150D02*
X549573D01*
X548798Y232925D01*
X546877D01*
X540452Y226500D01*
X535500D01*
X535050Y226050D01*
Y224076D01*
X534600Y223626D01*
X533700D01*
X533250Y224076D01*
Y226050D01*
X532800Y226500D01*
X531150D01*
X530700Y226050D01*
Y224076D01*
X530250Y223626D01*
X529350D01*
X528900Y224076D01*
Y226050D01*
X528450Y226500D01*
X527550D01*
X527100Y226050D01*
Y224076D01*
X526650Y223626D01*
X525750D01*
X525300Y224076D01*
Y226050D01*
X524850Y226500D01*
X523950D01*
X523500Y226050D01*
Y224076D01*
X523050Y223626D01*
X522150D01*
X521700Y224076D01*
Y226050D01*
X521250Y226500D01*
X520350D01*
X519900Y226050D01*
Y224076D01*
X519450Y223626D01*
X518550D01*
X518100Y224076D01*
Y226050D01*
X517650Y226500D01*
X516000D01*
X513126Y223626D01*
X464626D01*
X462500Y221500D01*
G01X619876Y195000D02*
X619000Y195876D01*
Y243500D01*
X613000Y249500D01*
X589000D01*
X580500Y258000D01*
X558000D01*
X534500Y281500D01*
X491000D01*
X486000Y286500D01*
X465750D01*
G01X463371Y290371D02*
X462250Y289250D01*
Y286500D01*
G01X476273Y334283D02*
X472055Y334000D01*
G01D02*
X471851Y335405D01*
Y337991D01*
G01X467300Y320100D02*
X467700Y320500D01*
X472548D01*
X473576Y321528D01*
Y328823D01*
X470630Y331769D01*
X469639Y332761D01*
Y334769D01*
X467914Y336494D01*
Y337991D01*
G01X463055Y322500D02*
Y324000D01*
X461765Y325290D01*
Y331842D01*
X463977Y334054D01*
G01X468555Y323000D02*
Y324150D01*
X469680Y325275D01*
Y331375D01*
X467914Y333141D01*
Y334054D01*
G01X462555Y346000D02*
Y348310D01*
X463945Y349700D01*
G01X472055Y341500D02*
X471955D01*
X470830Y340375D01*
X467030D01*
X464646Y337991D01*
X463977D01*
G01X471026Y839000D02*
X473778D01*
X476778Y836000D01*
X479078D01*
G01X473078Y843047D02*
X474731D01*
X478478Y839300D01*
X483878D01*
G01X473078Y845016D02*
X477762D01*
X479578Y843200D01*
G01X473078Y848953D02*
X478231D01*
X479278Y850000D01*
G01X483178Y861500D02*
X472278D01*
X469058Y858280D01*
Y853000D01*
G01X473078Y846984D02*
X484178D01*
G01X471026Y853000D02*
X477578D01*
X480578Y856000D01*
G01X480429Y144100D02*
Y149000D01*
X481429Y150000D01*
G01X485529Y145500D02*
X484129Y144100D01*
X480429D01*
G01X488028Y844000D02*
X485378D01*
X484578Y843200D01*
X479578D01*
G01X488028Y836000D02*
X479078D01*
G01X488028Y840000D02*
X486478D01*
X485778Y839300D01*
X483878D01*
G01X488028Y852500D02*
X481778D01*
X479278Y850000D01*
G01X488028Y848500D02*
X486512Y846984D01*
X484178D01*
G01X488028Y857000D02*
X481578D01*
X480578Y856000D01*
G01X491528Y857000D02*
X498000D01*
X505500Y864500D01*
Y894500D01*
X495500Y904500D01*
X488000D01*
G01X491528Y852500D02*
X496500D01*
X508500Y864500D01*
Y894500D01*
X495500Y907500D01*
X483500D01*
G01X488028Y861500D02*
X483178D01*
G01X506000Y239500D02*
X506500Y240000D01*
X535000D01*
X536500Y241500D01*
X569988D01*
X576955Y234533D01*
Y233303D01*
X577119Y233139D01*
G01X509555Y416750D02*
X507301D01*
X505922Y415371D01*
G01X509555Y420250D02*
X506440D01*
X506163Y419973D01*
G01X508100Y605500D02*
X548571Y645971D01*
Y950607D01*
X544178Y955000D01*
Y956000D01*
G01X531125Y142250D02*
X528750D01*
X526500Y144500D01*
Y145000D01*
G01X531250Y148500D02*
X528500D01*
X526500Y146500D01*
Y145000D01*
G01X510500Y237300D02*
X512954D01*
X513404Y236850D01*
Y235992D01*
X513854Y235542D01*
X514754D01*
X515204Y235992D01*
Y236850D01*
X515654Y237300D01*
X516554D01*
X517004Y236850D01*
Y235992D01*
X517454Y235542D01*
X518354D01*
X518804Y235992D01*
Y236850D01*
X519254Y237300D01*
X520154D01*
X520604Y236850D01*
Y235992D01*
X521054Y235542D01*
X521954D01*
X522404Y235992D01*
Y236850D01*
X522854Y237300D01*
X523754D01*
X524204Y236850D01*
Y235992D01*
X524654Y235542D01*
X525554D01*
X526004Y235992D01*
Y236850D01*
X526454Y237300D01*
X527354D01*
X527804Y236850D01*
Y235992D01*
X528254Y235542D01*
X529154D01*
X529604Y235992D01*
Y236850D01*
X530054Y237300D01*
X530954D01*
X531404Y236850D01*
Y235992D01*
X531854Y235542D01*
X532754D01*
X533204Y235992D01*
Y236850D01*
X533654Y237300D01*
X539073D01*
G01X524000Y243500D02*
X575552D01*
X581046Y238006D01*
Y236493D01*
X580709Y236156D01*
Y232091D01*
G01X548000Y369500D02*
X541400Y362900D01*
Y348521D01*
X541146Y348267D01*
Y330146D01*
X531300Y320300D01*
Y317099D01*
X526575Y312374D01*
Y302635D01*
X531590Y297620D01*
G01X543500Y179000D02*
X539864D01*
X539714Y179150D01*
G01X538500Y188500D02*
X542500D01*
G01Y215500D02*
X544991Y217991D01*
Y218439D01*
X546118Y219566D01*
X550022D01*
X553675Y215913D01*
G01X546916Y217641D02*
Y214916D01*
X543000Y211000D01*
X540500D01*
G01X569555Y364000D02*
Y363261D01*
X562294Y356000D01*
X555615D01*
X544996Y345381D01*
Y319996D01*
X542300Y317300D01*
Y317233D01*
X542204Y317137D01*
Y312446D01*
X538983Y309225D01*
X535477D01*
X531919Y305667D01*
Y300633D01*
X533600Y298952D01*
Y296400D01*
X534500Y295500D01*
G01X564215Y369339D02*
X564480Y369074D01*
Y363702D01*
X560778Y360000D01*
X554223D01*
X542096Y347873D01*
Y321696D01*
X539625Y319225D01*
X538626D01*
X538601Y319200D01*
X537999D01*
X528799Y310000D01*
X528500D01*
G01X566430Y366500D02*
Y362894D01*
X561586Y358050D01*
X554907D01*
X543046Y346189D01*
Y321046D01*
X540925Y318925D01*
Y316926D01*
X540254Y316255D01*
Y314554D01*
X536875Y311175D01*
X534669D01*
X534665Y311171D01*
X534629D01*
G01X550500Y184500D02*
Y188000D01*
G01X556500Y184500D02*
X558000Y186000D01*
X560500D01*
G01X555500Y190500D02*
Y194000D01*
G01X557275Y214918D02*
Y217225D01*
X555000Y219500D01*
G01X550075Y215913D02*
Y212500D01*
G01X544500Y224500D02*
X545303Y225303D01*
X547746D01*
G01X569322Y234220D02*
X567252Y232150D01*
X552435D01*
G01X549014Y308070D02*
X551115D01*
X561429Y297756D01*
Y295071D01*
X563704Y292796D01*
Y272000D01*
G01X556455Y337700D02*
X557061Y337094D01*
Y334194D01*
G01X553155Y334300D02*
X550755Y336700D01*
Y337500D01*
G01X556555Y341750D02*
X560253Y338052D01*
Y329500D01*
G01X552555Y341750D02*
X554555Y339600D01*
X556455Y337700D01*
G01X548555Y341750D02*
X550555Y337700D01*
X550755Y337500D01*
G01X558955Y368150D02*
Y368100D01*
X562555Y364500D01*
G01X554955Y368150D02*
Y363980D01*
X555935Y363000D01*
G01X558955Y371650D02*
X561904D01*
X564215Y369339D01*
G01X554955Y371650D02*
X557305Y374000D01*
X562430D01*
X566430Y370000D01*
Y366500D01*
G01X544178Y964750D02*
Y956000D01*
G01X568500Y180500D02*
X571398Y183398D01*
Y183602D01*
G01X568158Y206455D02*
X568114Y206499D01*
Y207453D01*
X567614Y207953D01*
X563785D01*
X563264Y207432D01*
X563261D01*
X562310Y206481D01*
Y205630D01*
X560468Y203788D01*
G01X564583Y206028D02*
Y201214D01*
X562441Y199072D01*
G01X566900Y195900D02*
X565000Y194000D01*
X563100D01*
G01X569000Y217000D02*
X564500D01*
G01X564000Y212000D02*
X568027D01*
X569127Y213100D01*
G01X568000Y239000D02*
X570437D01*
X575104Y234333D01*
Y228826D01*
X575425Y228505D01*
G01X584500Y240500D02*
Y238101D01*
X583204Y236805D01*
G01X625000Y706000D02*
X626000Y705000D01*
Y676000D01*
G01X641000Y475750D02*
Y650000D01*
X626000Y665000D01*
Y676000D01*
G01X641000Y472250D02*
X645500D01*
G01Y466250D02*
X649100Y469850D01*
Y471700D01*
G01X645500Y472250D02*
X648550D01*
X649100Y471700D01*
G01X666750Y961550D02*
Y653250D01*
X680000Y640000D01*
G01X670474Y808700D02*
X669900D01*
X669000Y809600D01*
Y887385D01*
G01X671500Y899000D02*
Y861000D01*
G01X673500Y864000D02*
Y888400D01*
X674000Y888900D01*
G01D02*
Y965250D01*
X676500Y967750D01*
G01X669000Y887385D02*
Y967700D01*
X667000Y969700D01*
G01X672000Y967750D02*
X671500Y967250D01*
Y899000D01*
G01X688500Y606000D02*
X731343Y648843D01*
Y758782D01*
X732718Y760157D01*
Y768218D01*
X735500Y771000D01*
Y771984D01*
G01X683000Y603950D02*
X683925Y604875D01*
Y747059D01*
X678575Y752409D01*
Y772425D01*
X677500Y773500D01*
G01X698624Y308070D02*
Y316076D01*
X704048Y321500D01*
X817500D01*
X820000Y324000D01*
Y347380D01*
X821100Y348480D01*
G01X694684Y315945D02*
X695445D01*
X703000Y323500D01*
X814000D01*
X817500Y327000D01*
Y348880D01*
X821100Y352480D01*
G01X733784Y861131D02*
Y812716D01*
X736000Y810500D01*
G01X733000Y969700D02*
X733800D01*
X735365Y968135D01*
Y904365D01*
X735000Y904000D01*
Y880000D01*
X731500Y876500D01*
Y874500D01*
X733784Y872216D01*
Y861131D01*
G01X740000Y886000D02*
X740500D01*
X748500Y878000D01*
Y858700D01*
G01X766000Y635000D02*
X747775Y653225D01*
Y710275D01*
G01D02*
Y803225D01*
X741050Y809950D01*
Y869500D01*
G01X748500Y858700D02*
Y808500D01*
X755000Y802000D01*
Y732000D01*
X757000Y730000D01*
Y650500D01*
X817500Y590000D01*
Y566000D01*
X819500Y564000D01*
G01X762900Y767800D02*
X763500Y767200D01*
Y648500D01*
X763000Y648000D01*
G01X767000Y648500D02*
X765425Y650075D01*
Y840298D01*
X763593Y842130D01*
Y858444D01*
G01X768000Y760600D02*
Y728000D01*
G01X757000Y896400D02*
Y896000D01*
X757500Y895500D01*
Y743500D01*
G01X768000Y833000D02*
Y760600D01*
G01X763500Y839500D02*
X762900Y838900D01*
Y767800D01*
G01X763593Y858444D02*
Y889083D01*
X765010Y890500D01*
X774500D01*
G01X780250Y973000D02*
Y968500D01*
G01D02*
X784300D01*
X785500Y969700D01*
G01X794488Y1009860D02*
Y999988D01*
X792000Y997500D01*
Y976200D01*
X785500Y969700D01*
G01X818000Y240900D02*
X818975Y241875D01*
X832625D01*
X853000Y221500D01*
X1044818D01*
X1053643Y212675D01*
X1056675D01*
X1067500Y223500D01*
X1084500D01*
G01X1157700Y368500D02*
Y368200D01*
X1156000Y366500D01*
X868717D01*
X865745Y363528D01*
Y363082D01*
X864618Y361955D01*
X861455D01*
X845860Y346360D01*
X844410D01*
G01X1155400Y371500D02*
Y370400D01*
X1153500Y368500D01*
X863940D01*
X847500Y352060D01*
Y352000D01*
G01X869544Y226000D02*
X871269Y227725D01*
X1041775D01*
X1055000Y214500D01*
G01X876000Y631700D02*
Y646700D01*
X867500Y655200D01*
G01X1306000Y338500D02*
X1301000Y333500D01*
Y329514D01*
X1297192Y325706D01*
X1255794D01*
X1253112Y328388D01*
X1207611D01*
X1207298Y328075D01*
X1205702D01*
X1204777Y329000D01*
X1036000D01*
X1009075Y355925D01*
X947925D01*
X944000Y352000D01*
X939500D01*
G01X970382Y455872D02*
X970010Y456244D01*
Y467450D01*
X976035Y473475D01*
X1069769D01*
X1075294Y479000D01*
X1163222D01*
X1164247Y477975D01*
X1199753D01*
X1223325Y501547D01*
Y505976D01*
X1225771Y508422D01*
X1225828D01*
X1239881Y522475D01*
X1253330D01*
X1262425Y531570D01*
Y548352D01*
X1261250Y549527D01*
Y619250D01*
X1267500Y625500D01*
G01X973015Y453416D02*
X972925Y453506D01*
Y466335D01*
X977815Y471225D01*
X1070701D01*
X1076226Y476750D01*
X1162290D01*
X1163315Y475725D01*
X1200685D01*
X1225575Y500615D01*
Y505044D01*
X1226702Y506171D01*
X1226759D01*
X1240813Y520225D01*
X1254262D01*
X1265425Y531388D01*
Y555575D01*
X1263500Y557500D01*
Y598075D01*
X1264000Y598575D01*
Y613500D01*
G01X992690Y466750D02*
X994915Y468975D01*
X1071633D01*
X1077158Y474500D01*
X1161358D01*
X1162383Y473475D01*
X1203198D01*
X1247698Y517975D01*
X1255194D01*
X1267675Y530456D01*
Y556507D01*
X1265750Y558432D01*
Y597143D01*
X1266500Y597893D01*
Y617500D01*
G01X1271000D02*
X1269925Y616425D01*
Y598136D01*
X1268000Y596211D01*
Y559364D01*
X1269925Y557439D01*
Y529523D01*
X1268608Y528206D01*
X1268607D01*
X1256126Y515725D01*
X1248630D01*
X1204130Y471225D01*
X1199292D01*
X1199291Y471224D01*
X1193701D01*
X1193700Y471225D01*
X1161451D01*
X1160426Y472250D01*
X1079650D01*
X1074125Y466725D01*
X997075D01*
X996910Y466560D01*
G01X1003422Y490578D02*
X1003344Y490500D01*
X995000D01*
X994500Y491000D01*
G01X1002500Y653000D02*
X1029500D01*
G01X1010250Y66500D02*
X1011000Y65750D01*
Y55500D01*
X1008260Y52760D01*
Y50500D01*
G01X1010250Y66500D02*
Y70500D01*
G01D02*
X1010500Y70750D01*
Y74750D01*
G01X1008260Y59500D02*
X1003000D01*
G01X1010500Y74750D02*
X1011250D01*
X1016500Y80000D01*
Y87500D01*
G01X1022000Y492500D02*
Y494000D01*
X1020500Y495500D01*
Y573500D01*
X1016057Y577943D01*
Y586280D01*
X1041277Y611500D01*
X1052277D01*
X1070777Y630000D01*
X1071977D01*
G01X1017982Y585018D02*
X1058518D01*
X1079000Y605500D01*
X1106000D01*
G01X1027426Y346500D02*
X1171500D01*
X1182000Y357000D01*
G01X1023000Y347000D02*
X1025450Y344550D01*
X1177050D01*
X1184000Y351500D01*
G01X1031000Y348500D02*
X1170000D01*
X1178000Y356500D01*
G01X1174400D02*
X1032000D01*
X1031450Y355950D01*
X1031000D01*
G01X1021000Y588500D02*
X1057964D01*
X1078964Y609500D01*
X1088000D01*
G01X1118200Y657400D02*
X1093875Y633075D01*
X1026925D01*
X1022500Y637500D01*
G01X1087750Y655000D02*
X1080329Y647579D01*
X1046397D01*
X1045068Y646250D01*
X1039250D01*
X1032500Y653000D01*
X1029500D01*
G01X1045000Y266600D02*
X1046400Y268000D01*
X1097500D01*
X1124150Y294650D01*
X1136450D01*
G01X1068000Y645329D02*
X1047329D01*
X1046000Y644000D01*
G01X1042450Y648500D02*
X1042500D01*
X1046650Y652650D01*
X1082218D01*
X1105692Y676124D01*
X1107524D01*
G01X1112400Y678500D02*
X1105310D01*
X1081862Y655052D01*
X1050092D01*
G01X1050500Y680500D02*
X1053950D01*
X1054080Y680630D01*
G01X1059000Y558190D02*
X1079206D01*
X1085896Y551500D01*
G01X1129272Y673350D02*
X1128584D01*
X1128188Y672954D01*
X1118894D01*
X1091215Y645275D01*
X1086754D01*
X1086700Y645329D01*
X1068000D01*
G01X1058500Y660900D02*
X1060600Y658800D01*
X1066300D01*
G01D02*
X1066425Y658675D01*
X1075812D01*
X1077750Y660613D01*
Y667500D01*
G01X1055000Y664500D02*
Y661000D01*
X1054900Y660900D01*
G01X1058000Y677500D02*
Y681100D01*
X1058350Y681450D01*
G01X1065000Y677000D02*
X1068500D01*
G01X1077750Y679500D02*
X1072000D01*
X1069500Y677000D01*
X1068500D01*
G01Y687000D02*
X1069618Y685882D01*
Y681554D01*
G01X1293960Y528740D02*
X1289700Y533000D01*
X1278500D01*
X1258500Y513000D01*
X1249087D01*
X1205062Y468975D01*
X1200224D01*
X1200223Y468974D01*
X1192769D01*
X1192768Y468975D01*
X1160519D01*
X1159494Y470000D01*
X1084500D01*
X1078500Y464000D01*
G01X1071977Y630000D02*
X1086250D01*
G01X1081250Y640000D02*
X1085250D01*
G01X1093000Y670000D02*
X1085000Y662000D01*
Y661000D01*
G01X1081250Y679500D02*
X1081500D01*
X1084000Y677000D01*
X1088000D01*
G01X1129278Y682804D02*
X1122624D01*
X1119939Y685489D01*
X1118591D01*
X1115952Y682850D01*
X1103872D01*
X1096072Y675050D01*
X1092550D01*
X1085000Y667500D01*
G01D02*
X1081250D01*
G01Y671500D02*
Y671145D01*
X1077750Y667645D01*
Y667500D01*
G01X1081250Y675500D02*
X1077750Y679000D01*
Y679500D01*
G01X1095500Y681706D02*
X1093146D01*
X1092940Y681500D01*
X1083500D01*
X1081500Y683500D01*
X1081250D01*
G01Y687500D02*
X1081500D01*
X1083000Y686000D01*
X1087400D01*
G01X1081250Y691500D02*
X1082700Y690050D01*
X1094250D01*
G01X1081250Y695500D02*
X1081750Y695000D01*
X1087100D01*
G01X1069618Y681554D02*
X1072990Y684925D01*
X1074798D01*
X1076223Y683500D01*
X1077750D01*
G01X1094000Y699500D02*
X1081250D01*
G01Y711500D02*
X1083000D01*
X1084500Y713000D01*
X1086500D01*
G01X1092812Y708500D02*
X1082250D01*
X1081250Y707500D01*
G01Y703500D02*
X1081750Y704000D01*
X1086600D01*
G01X1081250Y719500D02*
X1085700D01*
X1086300Y720100D01*
G01X1081250Y727500D02*
X1083250Y729500D01*
X1096200D01*
X1112600Y713100D01*
G01X1081250Y715500D02*
X1085000D01*
X1087000Y717500D01*
X1092200D01*
X1093600Y716100D01*
G01X1081250Y723500D02*
X1084071D01*
X1087600Y727029D01*
G01X1087000Y739200D02*
X1086974D01*
X1084300Y741874D01*
G01X1082250Y736500D02*
X1083250Y735500D01*
X1099557D01*
X1116500Y718557D01*
Y718300D01*
G01X1093975Y742500D02*
X1089399D01*
X1084000Y747899D01*
Y748099D01*
G01X1085896Y551500D02*
X1105496Y531900D01*
X1189798D01*
X1192948Y535050D01*
X1201450D01*
X1201500Y535000D01*
G01X1088000Y609500D02*
X1106000D01*
G01X1115000Y650000D02*
X1095000Y630000D01*
X1089750D01*
G01X1085250Y640000D02*
Y641250D01*
X1087000Y643000D01*
X1093424D01*
X1110500Y660076D01*
G01X1091238Y650584D02*
X1093267D01*
X1110700Y668017D01*
Y669200D01*
G01X1091250Y655000D02*
Y658500D01*
X1094250Y661500D01*
X1097200D01*
X1102500Y666800D01*
G01X1094500Y657500D02*
X1096276D01*
X1097776Y659000D01*
X1098000D01*
G01X1125340Y684430D02*
X1122342D01*
X1120333Y686439D01*
X1118197D01*
X1116558Y684800D01*
X1103064D01*
X1095264Y677000D01*
X1088000D01*
G01X1132421Y679648D02*
X1128494D01*
X1126795Y681347D01*
X1117377D01*
X1116930Y680900D01*
X1104680D01*
X1096880Y673100D01*
X1096100D01*
X1093000Y670000D01*
G01X1126117Y685952D02*
X1122164D01*
X1120727Y687389D01*
X1117803D01*
X1117164Y686750D01*
X1102256D01*
X1097212Y681706D01*
X1095500D01*
G01X1123338Y687596D02*
X1121864D01*
X1121060Y688400D01*
X1101572D01*
X1099172Y686000D01*
X1087400D01*
G01X1126122Y689171D02*
X1121633D01*
X1120754Y690050D01*
X1094250D01*
G01X1116220Y693710D02*
X1100902D01*
X1095112Y699500D01*
X1094000D01*
G01X1087100Y695000D02*
X1094982D01*
X1097922Y692060D01*
X1116195D01*
X1116414Y692279D01*
X1126116D01*
G01X1086600Y704000D02*
X1093282D01*
X1100712Y696570D01*
X1116690D01*
X1117180Y697060D01*
X1127151D01*
X1131946Y692265D01*
X1132440D01*
G01X1086300Y720100D02*
X1092926D01*
X1109856Y703170D01*
X1122450D01*
G01X1093600Y716100D02*
X1093692Y716008D01*
Y716000D01*
X1108172Y701520D01*
X1115652D01*
X1115835Y701703D01*
X1126114D01*
G01X1086500Y713000D02*
X1092442D01*
X1105572Y699870D01*
X1127250D01*
X1128556Y698564D01*
X1129290D01*
G01X1132423Y695469D02*
X1130086D01*
X1127335Y698220D01*
X1103092D01*
X1092812Y708500D01*
G01X1119400Y706210D02*
X1109150D01*
X1091107Y724253D01*
X1090257D01*
G01X1106400Y714400D02*
X1104359Y716441D01*
X1102541D01*
X1091953Y727029D01*
X1087600D01*
G01X1126121Y714368D02*
X1124744Y715745D01*
Y715756D01*
X1122700Y717800D01*
X1122689D01*
X1097989Y742500D01*
X1093975D01*
G01X1110500Y660076D02*
X1122311Y671887D01*
X1123659D01*
X1125271Y670275D01*
X1129271D01*
G01X1132423Y663902D02*
X1132002D01*
X1119080Y650980D01*
X1115980D01*
X1115000Y650000D01*
G01X1126102Y676518D02*
X1125259D01*
X1123612Y678165D01*
X1118052D01*
X1116011Y676124D01*
X1107524D01*
G01X1110700Y669200D02*
X1112978Y671478D01*
X1115575D01*
X1118001Y673904D01*
X1127248D01*
X1127358Y674014D01*
G01X1102500Y666800D02*
X1109574Y673874D01*
X1115721D01*
X1116726Y674879D01*
X1126862D01*
X1128538Y676555D01*
X1129290D01*
G01X1112400Y678500D02*
X1115827D01*
X1117049Y679722D01*
X1126121D01*
G01X1112600Y713100D02*
X1115480Y710220D01*
X1122840D01*
G01X1106400Y714400D02*
X1112230Y708570D01*
X1125614D01*
X1126155Y708029D01*
G01X1116500Y718300D02*
Y714651D01*
X1119933Y711218D01*
X1126121D01*
G01X1126885Y736721D02*
X1123149D01*
X1115300Y744570D01*
Y765900D01*
X1115800Y766400D01*
G01X1128959Y729952D02*
X1126048D01*
X1125000Y731000D01*
X1121868D01*
X1110350Y742518D01*
Y764764D01*
X1110400Y764814D01*
Y769500D01*
G01X1124497Y734140D02*
X1123396D01*
X1113650Y743886D01*
Y764764D01*
X1113700Y764814D01*
Y765353D01*
X1113575Y765478D01*
Y780975D01*
X1114825Y782225D01*
Y784315D01*
X1115835Y785325D01*
X1115925D01*
X1117600Y787000D01*
G01X1117630Y779565D02*
X1116900Y778835D01*
Y768447D01*
X1118025Y767322D01*
Y765478D01*
X1117000Y764453D01*
Y745204D01*
X1122689Y739515D01*
X1123771D01*
X1124326Y738960D01*
G01X1123254Y792663D02*
X1119891Y789300D01*
X1116753D01*
X1112600Y785147D01*
Y770612D01*
X1112625Y770587D01*
Y768213D01*
X1112050Y767638D01*
Y764130D01*
X1112000Y764080D01*
Y743202D01*
X1122887Y732315D01*
X1126549D01*
X1126955Y731909D01*
G01X1115800Y766400D02*
Y770962D01*
X1115350Y771412D01*
X1115256D01*
X1114806Y771862D01*
Y772762D01*
X1115256Y773212D01*
X1115350D01*
X1115800Y773662D01*
Y774562D01*
X1115350Y775012D01*
X1115256D01*
X1114806Y775462D01*
Y776362D01*
X1115256Y776812D01*
X1115350D01*
X1115800Y777262D01*
Y778162D01*
X1115350Y778612D01*
X1115256D01*
X1114806Y779062D01*
Y779962D01*
X1115256Y780412D01*
X1115350D01*
X1115800Y780862D01*
Y782850D01*
X1116550Y783600D01*
G01X1110400Y769500D02*
Y782453D01*
X1110375Y782478D01*
Y784322D01*
X1117136Y791083D01*
X1119060D01*
G01X1110300Y790000D02*
Y807400D01*
X1108641Y809059D01*
Y813864D01*
X1120577Y825800D01*
X1135300D01*
X1141100Y831600D01*
G01X1117600Y787000D02*
X1117675Y787075D01*
Y787316D01*
X1118685Y788326D01*
X1120115D01*
X1120241Y788200D01*
X1124170D01*
X1124360Y788390D01*
G01X1120529Y786350D02*
Y785139D01*
X1117765Y782375D01*
Y779700D01*
X1117630Y779565D01*
G01X1296000Y329500D02*
X1291500Y334000D01*
X1133500D01*
X1132500Y333000D01*
G01X1136200Y574100D02*
X1124447Y585853D01*
Y601983D01*
X1125000Y602536D01*
Y603050D01*
G01X1147500Y660471D02*
Y650828D01*
X1147265Y650593D01*
Y622181D01*
X1144300Y619216D01*
Y616284D01*
X1128347Y600331D01*
Y591637D01*
X1140574Y579410D01*
Y572960D01*
X1167534Y546000D01*
X1209500D01*
G01X1231000Y543775D02*
X1167001D01*
X1138624Y572152D01*
Y578602D01*
X1126397Y590829D01*
Y601174D01*
X1142350Y617127D01*
Y620024D01*
X1145315Y622989D01*
Y650593D01*
X1146525Y651803D01*
Y666263D01*
X1146588Y666326D01*
G01X1132222Y593278D02*
X1132500Y593556D01*
Y597500D01*
X1152505Y617505D01*
Y619339D01*
X1152600Y619434D01*
Y634600D01*
G01X1240173Y550327D02*
X1219402D01*
X1219225Y550150D01*
X1166142D01*
X1142524Y573768D01*
Y580218D01*
X1130297Y592445D01*
Y599522D01*
X1149215Y618440D01*
Y655138D01*
X1148775Y655578D01*
Y661009D01*
X1150675Y662909D01*
Y663257D01*
X1151354Y663936D01*
G01X1132398Y667102D02*
X1127902D01*
X1118200Y657400D01*
G01X1127800Y656204D02*
X1135553Y663957D01*
G01X1129289Y686005D02*
X1129298Y686014D01*
Y686074D01*
X1132088Y688864D01*
G01D02*
X1135224Y692000D01*
X1135260D01*
X1135724Y692464D01*
G01X1122250Y706210D02*
X1119400D01*
G01X1148169Y711219D02*
X1147318D01*
X1145504Y709405D01*
X1139958D01*
X1138994Y708441D01*
X1137646D01*
X1136512Y709575D01*
X1134865D01*
X1134467Y709972D01*
X1134079Y710360D01*
G01X1130702Y721260D02*
Y735489D01*
X1129998Y736193D01*
Y740863D01*
X1128727Y742134D01*
Y749343D01*
X1128430Y749640D01*
G01X1141765Y711030D02*
X1141010Y711785D01*
X1137661D01*
X1136000Y713446D01*
Y715223D01*
X1134210Y717013D01*
Y721111D01*
X1132336Y722985D01*
Y735930D01*
X1131950Y736316D01*
Y737054D01*
X1131949Y737055D01*
Y739789D01*
X1131948Y739790D01*
Y741672D01*
X1130677Y742945D01*
Y750151D01*
X1128135Y752693D01*
Y753608D01*
X1127000Y754743D01*
Y762560D01*
X1127800Y763360D01*
Y767385D01*
X1129670Y769255D01*
Y772930D01*
X1128454Y774146D01*
X1128378D01*
G01X1132902Y746400D02*
Y743772D01*
X1133600Y743074D01*
Y741842D01*
X1133598Y741840D01*
Y740474D01*
X1133599Y740473D01*
Y737739D01*
X1133600Y737738D01*
Y736316D01*
X1133986Y735930D01*
Y725108D01*
X1135160Y723934D01*
Y717407D01*
X1137104Y715463D01*
Y713686D01*
X1138055Y712735D01*
X1139403D01*
X1141007Y714339D01*
X1141840D01*
G01X1127554Y724482D02*
X1127518Y724518D01*
Y727432D01*
X1126969Y727981D01*
G01X1119295Y774903D02*
X1119300Y774898D01*
Y771146D01*
X1118850Y770696D01*
X1118695D01*
X1118245Y770246D01*
Y769346D01*
X1118695Y768896D01*
X1118850D01*
X1119300Y768446D01*
Y764125D01*
X1118650Y763475D01*
Y762325D01*
X1119300Y761675D01*
Y760525D01*
X1118650Y759875D01*
Y758725D01*
X1119300Y758075D01*
Y756925D01*
X1118650Y756275D01*
Y755125D01*
X1119300Y754475D01*
Y753325D01*
X1118650Y752675D01*
Y751525D01*
X1119300Y750875D01*
Y749725D01*
X1118650Y749075D01*
Y747925D01*
X1119300Y747275D01*
Y745238D01*
X1123373Y741165D01*
X1126225D01*
X1126585Y740805D01*
X1127183D01*
G01X1126671Y744629D02*
X1125346D01*
X1122635Y747340D01*
Y763875D01*
X1126185Y767425D01*
Y772815D01*
X1123852Y775148D01*
Y776918D01*
G01X1123393Y743726D02*
Y744091D01*
X1120985Y746499D01*
Y767105D01*
X1123233Y769353D01*
Y772157D01*
G01X1134000Y757350D02*
X1133169Y758181D01*
Y766871D01*
X1132520Y767520D01*
Y772192D01*
X1131600Y773112D01*
Y777376D01*
X1128495Y780481D01*
Y782699D01*
X1129417Y783621D01*
Y786656D01*
X1128885Y787188D01*
Y790115D01*
X1126360Y792640D01*
G01X1138729Y714360D02*
Y715182D01*
X1136110Y717801D01*
Y724990D01*
X1135061Y726039D01*
Y736122D01*
X1135252Y736313D01*
X1135250Y736316D01*
Y738422D01*
X1135249Y738423D01*
Y741157D01*
X1135250Y741158D01*
Y744498D01*
X1135127Y744621D01*
Y756223D01*
X1134000Y757350D01*
G01X1124978Y747578D02*
Y748852D01*
X1124285Y749545D01*
Y757935D01*
X1124735Y758385D01*
X1124900D01*
X1125350Y758835D01*
Y759735D01*
X1124900Y760185D01*
X1124735D01*
X1124285Y760635D01*
Y762285D01*
X1125900Y763900D01*
Y764200D01*
G01X1132902Y746400D02*
Y750260D01*
X1131035Y752127D01*
Y755626D01*
X1130585Y756076D01*
X1129150D01*
X1128700Y756526D01*
Y757426D01*
X1129150Y757876D01*
X1130585D01*
X1131035Y758326D01*
Y759226D01*
X1130585Y759676D01*
X1129150D01*
X1128700Y760126D01*
Y761026D01*
X1129150Y761476D01*
X1130585D01*
X1131035Y761926D01*
Y763165D01*
X1129175Y765025D01*
Y767416D01*
X1130800Y769041D01*
Y772568D01*
X1130650Y772718D01*
Y775780D01*
X1129501Y776929D01*
G01X1120400Y781600D02*
Y778800D01*
X1119300Y777700D01*
Y774908D01*
X1119295Y774903D01*
G01X1123852Y776918D02*
Y778496D01*
X1125500Y780144D01*
Y784363D01*
X1126642Y785505D01*
G01X1123233Y772157D02*
Y774120D01*
X1121575Y775778D01*
Y777788D01*
X1123200Y779413D01*
Y783900D01*
G01X1128378Y774146D02*
Y774222D01*
X1126500Y776100D01*
Y782781D01*
X1128467Y784748D01*
Y786262D01*
X1127935Y786794D01*
Y788062D01*
X1127160Y788837D01*
G01X1130610Y788820D02*
Y783470D01*
X1129445Y782305D01*
Y780875D01*
X1132550Y777770D01*
Y773506D01*
X1136000Y770056D01*
Y766398D01*
X1134820Y765218D01*
Y761580D01*
X1134819Y761579D01*
Y760200D01*
X1137030Y757989D01*
Y745300D01*
G01X1132600Y784822D02*
Y779300D01*
X1133500Y778400D01*
Y773900D01*
X1137000Y770400D01*
Y767666D01*
X1136999Y767665D01*
Y765293D01*
X1136470Y764764D01*
Y760883D01*
X1138855Y758498D01*
Y744543D01*
X1136900Y742588D01*
Y740474D01*
X1136899Y740473D01*
Y739107D01*
X1136900Y739106D01*
Y736316D01*
X1137286Y735930D01*
Y731000D01*
G01X1129497Y792673D02*
X1132420Y789750D01*
Y787480D01*
X1133705Y786195D01*
Y786157D01*
X1134325Y785537D01*
Y784107D01*
X1133561Y783343D01*
Y779720D01*
X1134450Y778831D01*
Y774294D01*
X1138200Y770544D01*
Y765696D01*
X1138120Y765616D01*
Y762380D01*
X1138900Y761600D01*
G01X1134145Y788450D02*
Y787099D01*
X1134655Y786589D01*
Y786551D01*
X1135275Y785931D01*
Y783713D01*
X1134511Y782949D01*
Y780114D01*
X1135400Y779225D01*
Y774688D01*
X1139400Y770688D01*
Y765134D01*
X1140250Y764284D01*
Y763397D01*
X1140919Y762728D01*
Y762713D01*
X1141590Y762042D01*
Y762029D01*
X1142155Y761464D01*
Y744543D01*
X1142156Y744542D01*
Y743176D01*
X1140200Y741220D01*
Y736315D01*
X1140586Y735929D01*
Y725300D01*
G01X1132684Y792636D02*
X1132557Y792509D01*
Y790957D01*
X1133154Y790360D01*
X1134960D01*
X1135870Y789450D01*
Y786718D01*
X1137961Y784627D01*
Y780465D01*
X1143820Y774606D01*
Y771200D01*
X1143862Y771158D01*
Y770957D01*
G01X1123500Y796000D02*
Y792909D01*
X1123254Y792663D01*
G01X1206400Y536800D02*
X1206200Y537000D01*
X1148500D01*
X1146500Y539000D01*
G01D02*
X1143500Y542000D01*
G01X1154100Y539600D02*
X1151700Y542000D01*
X1147500D01*
G01X1240000Y542900D02*
X1238650Y541550D01*
X1166468D01*
X1136200Y571818D01*
Y574100D01*
G01X1145800Y576200D02*
Y579700D01*
X1145900Y579800D01*
G01X1135000Y597000D02*
X1154155Y616155D01*
Y618655D01*
X1159500Y624000D01*
G01X1136500Y592500D02*
Y595477D01*
X1156144Y615121D01*
X1156179D01*
G01X1171775Y630000D02*
Y613052D01*
X1163922Y605199D01*
X1160899D01*
X1141100Y585400D01*
G01X1137386Y660414D02*
Y661386D01*
X1138757Y662757D01*
Y663937D01*
G01X1137500Y656250D02*
Y659328D01*
X1137386Y659442D01*
Y660414D01*
G01X1145400Y673100D02*
X1142090D01*
X1141600Y673590D01*
G01X1139000Y678600D02*
Y675351D01*
X1139245Y675106D01*
G01X1145000Y711200D02*
Y711901D01*
X1146678Y713579D01*
Y716707D01*
X1146510Y716875D01*
Y721308D01*
X1150075Y724873D01*
Y731009D01*
X1147845Y733239D01*
Y737945D01*
X1149600Y739700D01*
Y763355D01*
X1148095Y764860D01*
Y770025D01*
X1145500Y772620D01*
Y774270D01*
X1138911Y780859D01*
Y785146D01*
X1136820Y787237D01*
Y791580D01*
X1135900Y792500D01*
G01X1148135Y720634D02*
X1148334D01*
X1157200Y729500D01*
X1158167D01*
X1162225Y733558D01*
Y735402D01*
X1161600Y736027D01*
Y749274D01*
X1161324Y749550D01*
G01X1138900Y761600D02*
X1140505Y759995D01*
Y743859D01*
X1138550Y741904D01*
Y736316D01*
X1139511Y735355D01*
Y729507D01*
X1138361Y728357D01*
Y724378D01*
X1138685Y724054D01*
Y720633D01*
G01X1140586Y725300D02*
Y722186D01*
X1140304Y721904D01*
G01X1148167Y717517D02*
X1149800Y719150D01*
Y720349D01*
X1157751Y728300D01*
X1158311D01*
X1163350Y733339D01*
Y739250D01*
X1164100Y740000D01*
G01X1143862Y770957D02*
Y766198D01*
X1145485Y764575D01*
X1146046D01*
X1147950Y762671D01*
Y740384D01*
X1146195Y738629D01*
Y736316D01*
X1146368Y736143D01*
Y733372D01*
X1149125Y730615D01*
Y725267D01*
X1145560Y721702D01*
Y714834D01*
X1145053Y714327D01*
G01X1137286Y731000D02*
Y729616D01*
X1137060Y729390D01*
Y719959D01*
X1138730Y718289D01*
Y717480D01*
G01X1141904Y720633D02*
X1142811Y721540D01*
Y723277D01*
X1143261Y723727D01*
X1145225D01*
X1145675Y724177D01*
Y725077D01*
X1145225Y725527D01*
X1143261D01*
X1142811Y725977D01*
Y726877D01*
X1143261Y727327D01*
X1145225D01*
X1145675Y727777D01*
Y728677D01*
X1145225Y729127D01*
X1143261D01*
X1142811Y729577D01*
Y731100D01*
G01D02*
Y732689D01*
X1142425Y733075D01*
Y736003D01*
X1141850Y736578D01*
Y740536D01*
X1143806Y742492D01*
Y762147D01*
X1143240Y762713D01*
Y762726D01*
X1142569Y763397D01*
Y763765D01*
X1140500Y765834D01*
Y770932D01*
X1136600Y774832D01*
Y781778D01*
X1136236Y782142D01*
G01X1144075Y739375D02*
Y740427D01*
X1145500Y741852D01*
Y744137D01*
X1146300Y744937D01*
Y745937D01*
X1145500Y746737D01*
Y747737D01*
X1146300Y748537D01*
Y749537D01*
X1145500Y750337D01*
Y751337D01*
X1146300Y752137D01*
Y753137D01*
X1145500Y753937D01*
Y754937D01*
X1146300Y755737D01*
Y756737D01*
X1145500Y757537D01*
Y758537D01*
X1146300Y759337D01*
Y760337D01*
X1145500Y761137D01*
Y762787D01*
X1144890Y763397D01*
Y763410D01*
X1141600Y766700D01*
Y771200D01*
X1137800Y775000D01*
Y776140D01*
X1138600Y776940D01*
X1138961D01*
G01X1147400Y729900D02*
X1144075Y733225D01*
Y734278D01*
X1143875Y734478D01*
Y736322D01*
X1144075Y736522D01*
Y739375D01*
G01X1161324Y749550D02*
Y749886D01*
X1158408Y752802D01*
Y754398D01*
X1158625Y754615D01*
Y760875D01*
X1156183Y763317D01*
Y763698D01*
X1152000Y767881D01*
Y770899D01*
X1149839Y773061D01*
Y778838D01*
X1147058Y781620D01*
X1145425Y783253D01*
Y783828D01*
X1142415Y786838D01*
X1139659D01*
X1138545Y787952D01*
G01X1135900Y792500D02*
X1138970Y795570D01*
Y795830D01*
G01X1148061Y793765D02*
X1146966Y792670D01*
X1145270D01*
G01X1164100Y740000D02*
X1167301Y743201D01*
Y745885D01*
X1167305Y745889D01*
Y749600D01*
X1167301Y749604D01*
Y759201D01*
X1158902Y767600D01*
X1157760D01*
X1156300Y769060D01*
Y770532D01*
X1156284Y770608D01*
X1156128Y770765D01*
X1156127Y770779D01*
Y783292D01*
X1155616Y783803D01*
Y784655D01*
X1154256Y786015D01*
X1148614D01*
X1146535Y788094D01*
Y788345D01*
X1145740Y789140D01*
G01X1138931Y792658D02*
Y790228D01*
X1141371Y787788D01*
X1142809D01*
X1146376Y784221D01*
Y783990D01*
X1149201Y781165D01*
X1149377D01*
X1151914Y778628D01*
X1152300D01*
X1153600Y777328D01*
Y768311D01*
X1157833Y764078D01*
Y764001D01*
X1160450Y761384D01*
Y760352D01*
X1161128Y759674D01*
G01X1142086Y789513D02*
X1142774Y788825D01*
X1143116D01*
X1147327Y784614D01*
Y784383D01*
X1149595Y782115D01*
X1149771D01*
X1152307Y779579D01*
X1152693D01*
X1155040Y777232D01*
Y768976D01*
X1158286Y765730D01*
X1158438D01*
X1163353Y760815D01*
X1164178Y759988D01*
Y755967D01*
G01X1148760Y789016D02*
X1151590Y791846D01*
Y792660D01*
G01X1185500Y362500D02*
X1162116D01*
X1160058Y364558D01*
G01X1210000Y536800D02*
X1207800Y539000D01*
X1154700D01*
X1154100Y539600D01*
G01X1158000Y644750D02*
X1156952Y643702D01*
Y642506D01*
X1156775Y642329D01*
Y639271D01*
X1161000Y635046D01*
Y626190D01*
X1159500Y624690D01*
Y624000D01*
G01X1156179Y615121D02*
Y615179D01*
X1165000Y624000D01*
X1165023D01*
X1166750Y625727D01*
Y643000D01*
X1166000Y644750D01*
G01X1156377Y627623D02*
X1156772Y628018D01*
Y634228D01*
X1154825Y636175D01*
Y643250D01*
X1155002Y643545D01*
Y647115D01*
X1155250Y647394D01*
Y650403D01*
X1155197Y651303D01*
X1154000Y652500D01*
G01X1152600Y634600D02*
Y644350D01*
X1153000Y644750D01*
G01X1159000Y652176D02*
X1158677D01*
X1154275Y656578D01*
Y658587D01*
X1154900Y659212D01*
Y665011D01*
G01X1158000Y648250D02*
X1162000D01*
G01D02*
Y650493D01*
X1160317Y652176D01*
X1159000D01*
G01X1157599Y663956D02*
X1156500Y662857D01*
Y657500D01*
G01X1166000Y648250D02*
Y648692D01*
X1157192Y657500D01*
X1156500D01*
G01X1151000Y656500D02*
Y658000D01*
X1153000Y660000D01*
Y664589D01*
X1151825Y665764D01*
Y666545D01*
X1151282Y667088D01*
G01X1153000Y648250D02*
X1151000Y650250D01*
Y656500D01*
G01X1171775Y630000D02*
Y655335D01*
X1168500Y658610D01*
Y659000D01*
G01X1169075Y617500D02*
Y654869D01*
X1166500Y657444D01*
Y661000D01*
X1163946Y663554D01*
Y663946D01*
G01X1154000Y652500D02*
X1153325Y653175D01*
Y658981D01*
X1153950Y659606D01*
Y664983D01*
X1153118Y665815D01*
G01X1181884Y614211D02*
X1174250Y621845D01*
Y636135D01*
X1173750Y636635D01*
Y652249D01*
X1173391Y652608D01*
G01X1154434Y714335D02*
Y711516D01*
X1154610Y711340D01*
G01X1152709Y720064D02*
X1151318Y718673D01*
Y717518D01*
G01X1156080Y723482D02*
X1156018Y723420D01*
Y719882D01*
X1157637Y718263D01*
Y717463D01*
G01X1164178Y755967D02*
X1165651Y754494D01*
Y748920D01*
X1165655Y748916D01*
Y746573D01*
X1165651Y746569D01*
Y745951D01*
X1164200Y744500D01*
G01X1161128Y759674D02*
X1161953Y758849D01*
Y754703D01*
X1163830Y752826D01*
Y747899D01*
G01X1167002Y767508D02*
X1167548D01*
X1170500Y768000D01*
G01X1158801Y778038D02*
X1159274Y778511D01*
Y781974D01*
X1161022Y783722D01*
Y785693D01*
G01X1167326Y776936D02*
X1166500Y776110D01*
Y773900D01*
G01X1161545Y788844D02*
X1160656D01*
X1158600Y790900D01*
G01X1158092Y787715D02*
Y784976D01*
X1157841Y784725D01*
G01X1165063Y787500D02*
Y790400D01*
G01X1154700Y795790D02*
X1152810D01*
X1151800Y796800D01*
G01X1322500Y337000D02*
X1321000Y338500D01*
X1312999D01*
X1306499Y345000D01*
X1217999D01*
X1194732Y368267D01*
X1177233D01*
X1175500Y370000D01*
X1175125D01*
G01X1317000Y336000D02*
X1313000D01*
X1306000Y343000D01*
X1217500D01*
X1194500Y366000D01*
X1174500D01*
G01X1178500Y644250D02*
Y639000D01*
X1196425Y621075D01*
X1213243D01*
X1235750Y598568D01*
Y554070D01*
X1234257Y552577D01*
X1174923D01*
X1173500Y554000D01*
G01X1181400Y592100D02*
Y595400D01*
X1181350Y595450D01*
G01X1181884Y614211D02*
X1185595Y610500D01*
X1220636D01*
X1233500Y597636D01*
Y555002D01*
X1233000Y554502D01*
G01X1169075Y613500D02*
Y617500D01*
G01X1182500Y623500D02*
X1176500Y629500D01*
Y637067D01*
X1176000Y637567D01*
Y653656D01*
X1170550Y659106D01*
Y666742D01*
X1170192Y667100D01*
G01X1184956Y619272D02*
Y621044D01*
X1182500Y623500D01*
G01X1191000Y651500D02*
Y652000D01*
X1177668Y665332D01*
G01X1196500Y640000D02*
X1195700D01*
X1178300Y657400D01*
X1175025D01*
X1173332Y659093D01*
Y663938D01*
G01X1213000Y634250D02*
X1202750Y644500D01*
X1194500D01*
X1183000Y656000D01*
G01D02*
X1176506Y662494D01*
Y663916D01*
G01X1193804Y657175D02*
X1193749Y657230D01*
X1189770D01*
X1182500Y664500D01*
G01X1178500Y647750D02*
Y653100D01*
G01D02*
Y654600D01*
X1176650Y656450D01*
X1174631D01*
X1172382Y658699D01*
Y660718D01*
X1171707Y661393D01*
Y665440D01*
X1171767Y665500D01*
G01X1171950Y679300D02*
Y681450D01*
X1173500Y683000D01*
G01D02*
X1176437Y680063D01*
Y679764D01*
X1176525Y679676D01*
G01X1171080Y675530D02*
X1170546Y674996D01*
X1167692D01*
G01X1167280Y672050D02*
X1168371D01*
X1170181Y670240D01*
G01X1226500Y668500D02*
X1225325Y669675D01*
X1183362D01*
X1182803Y670234D01*
G01X1239500Y671000D02*
X1229700D01*
X1229075Y671625D01*
X1183757D01*
X1180336Y675046D01*
X1178212D01*
X1176534Y673368D01*
G01X1222000Y666500D02*
X1221075Y667425D01*
X1195334D01*
X1194034Y668725D01*
X1190285D01*
X1190169Y668609D01*
X1182129D01*
X1180504Y670234D01*
X1179653D01*
G01X1241500Y654000D02*
X1234000D01*
X1228175Y659825D01*
X1214770D01*
X1213170Y661425D01*
X1201664D01*
X1199914Y659675D01*
X1191399D01*
X1184173Y666901D01*
X1182599D01*
G01X1246700Y675500D02*
X1243000D01*
X1241075Y673575D01*
X1195475D01*
X1194482Y672582D01*
X1184507D01*
X1180534Y676555D01*
X1176534D01*
G01X1179667Y679655D02*
X1180521D01*
X1182157Y681291D01*
X1183505D01*
X1185003Y679793D01*
X1224177D01*
X1231884Y687500D01*
X1235000D01*
G01X1245500Y683500D02*
X1239500D01*
X1235425Y679425D01*
X1226567D01*
X1224985Y677843D01*
X1186994D01*
X1186639Y678198D01*
X1184299D01*
X1182831Y679666D01*
G01X1182500Y664500D02*
X1179908Y667092D01*
X1176526D01*
G01X1176482Y682840D02*
X1184660D01*
X1185457Y682043D01*
X1221043D01*
X1230500Y691500D01*
X1243000D01*
G01X1243500Y699500D02*
X1230500D01*
X1219100Y688100D01*
X1194080D01*
X1191500Y690680D01*
G01X1179685Y692292D02*
X1180347Y691630D01*
X1192000D01*
X1193580Y690050D01*
X1217550D01*
X1231000Y703500D01*
X1235000D01*
G01X1192470Y692530D02*
X1192824D01*
X1193159Y692195D01*
X1215453D01*
X1216758Y693500D01*
X1217000D01*
X1231000Y707500D01*
X1243000D01*
G01X1179664Y695466D02*
X1180359Y694771D01*
X1181141D01*
X1182122Y693790D01*
X1186619D01*
X1186974Y694145D01*
X1214645D01*
X1232000Y711500D01*
X1235500D01*
G01X1243000Y715500D02*
X1233000D01*
X1213595Y696095D01*
X1190000D01*
X1189055Y697040D01*
X1184421D01*
X1182796Y695415D01*
G01X1234500Y695500D02*
X1231019D01*
X1221669Y686150D01*
X1189350D01*
X1187948Y687552D01*
G01X1206000Y731000D02*
X1191000D01*
X1188000Y728000D01*
X1180500D01*
X1177500Y725000D01*
G01X1216500Y735000D02*
X1214000D01*
X1212500Y736500D01*
X1207000D01*
X1203500Y733000D01*
X1182000D01*
X1181175Y732175D01*
Y731805D01*
X1170812Y721442D01*
Y720442D01*
G01X1194573Y727580D02*
X1193493Y726500D01*
X1180600D01*
X1178500Y724400D01*
Y722610D01*
X1176499Y720609D01*
G01X1184500Y730500D02*
X1181500D01*
X1173348Y722348D01*
Y720613D01*
G01X1209000Y722500D02*
X1180500D01*
X1178124Y720124D01*
Y719935D01*
X1176489Y718300D01*
Y717469D01*
G01X1171108Y777368D02*
X1171632D01*
X1174100Y774900D01*
G01X1173902Y784414D02*
X1173771Y784545D01*
Y784552D01*
X1173410Y784912D01*
X1170911D01*
G01X1170718Y782118D02*
X1172841Y779995D01*
X1172924D01*
X1173263Y779656D01*
G01X1170300Y787985D02*
X1169865D01*
X1167410Y785530D01*
G01X1280500Y338000D02*
X1279475Y336975D01*
X1214248D01*
X1188723Y362500D01*
X1185500D01*
G01X1217000Y634250D02*
X1204250Y647000D01*
X1195500D01*
X1191000Y651500D01*
G01X1209000Y634250D02*
X1203250Y640000D01*
X1196500D01*
G01X1191000Y667000D02*
X1194425Y663575D01*
X1198298D01*
X1200048Y665325D01*
X1215175D01*
X1216000Y664500D01*
G01X1191000Y663000D02*
X1193656D01*
X1195031Y661625D01*
X1199106D01*
X1200856Y663375D01*
X1213978D01*
X1215578Y661775D01*
X1234725D01*
X1236000Y660500D01*
G01X1240500Y679500D02*
X1239500D01*
X1237425Y677425D01*
X1236000D01*
X1234100Y675525D01*
X1194916D01*
X1193598Y674207D01*
X1190500D01*
G01X1222250Y727000D02*
X1221670Y727580D01*
X1194573D01*
G01X1243000Y743000D02*
X1240456Y745544D01*
X1226956D01*
X1225500Y747000D01*
X1205456D01*
X1204000Y745544D01*
X1196544D01*
X1196500Y745500D01*
G01Y736687D02*
X1196287Y736900D01*
X1193100D01*
G01X1279000Y746575D02*
X1278425Y746000D01*
X1245000D01*
X1241150Y749850D01*
X1227459D01*
X1226934Y749325D01*
X1202023D01*
X1200989Y748291D01*
X1200966D01*
X1200875Y748200D01*
X1195200D01*
X1192500Y745500D01*
G01X1202200Y741600D02*
X1201400D01*
X1199500Y743500D01*
G01X1184975Y767500D02*
Y758528D01*
X1192944Y750559D01*
X1200075D01*
X1201091Y751575D01*
X1226002D01*
X1226527Y752100D01*
X1242400D01*
X1246000Y748500D01*
X1285500D01*
X1286500Y747500D01*
G01X1209500Y514000D02*
X1217000Y521500D01*
X1222500D01*
X1242098Y541098D01*
Y595402D01*
X1213000Y624500D01*
G01X1222500Y620500D02*
X1244048Y598952D01*
Y540290D01*
X1222758Y519000D01*
X1218100D01*
X1213100Y514000D01*
G01X1260500Y641250D02*
X1261750D01*
X1263225Y639775D01*
Y637225D01*
X1245998Y619998D01*
Y539482D01*
X1223566Y517050D01*
X1221827D01*
X1214450Y509673D01*
Y509000D01*
G01X1235482Y546982D02*
X1234500Y546000D01*
X1209500D01*
G01X1207700Y601800D02*
Y605500D01*
G01X1209000Y630750D02*
Y628500D01*
X1213000Y624500D01*
G01Y630750D02*
Y630000D01*
X1222500Y620500D01*
G01X1204500Y659500D02*
X1206853Y657147D01*
X1221353D01*
X1225500Y653000D01*
G01X1216000Y664500D02*
X1216500Y664000D01*
X1240008D01*
X1247008Y657000D01*
X1250250D01*
G01X1209000Y722500D02*
X1222250D01*
G01Y731000D02*
X1221630Y731620D01*
X1211343D01*
X1211298Y731575D01*
X1209702D01*
X1209657Y731620D01*
X1206620D01*
X1206000Y731000D01*
G01X1220500Y513000D02*
X1221000D01*
X1222500Y514500D01*
X1223774D01*
X1247948Y538674D01*
Y619190D01*
X1265175Y636417D01*
Y640583D01*
X1262258Y643500D01*
X1260000D01*
X1257750Y645750D01*
Y647000D01*
G01X1240000Y546500D02*
X1237275Y543775D01*
X1231000D01*
G01X1219300Y567800D02*
Y564700D01*
X1219200Y564600D01*
G01X1250250Y641000D02*
X1240375Y650875D01*
X1227625D01*
X1225500Y653000D01*
G01X1250250Y667000D02*
X1249250Y668000D01*
X1227000D01*
X1226500Y668500D01*
G01X1250250Y661000D02*
X1246500D01*
X1241500Y666000D01*
X1222500D01*
X1222000Y666500D01*
G01X1218040Y719850D02*
Y716000D01*
G01X1222250Y722500D02*
Y718500D01*
G01X1225750Y731000D02*
X1226500D01*
X1228000Y732500D01*
X1233500D01*
X1234700Y733700D01*
G01X1225750Y735500D02*
X1229300D01*
X1229500Y735700D01*
G01X1232000Y738000D02*
X1231800D01*
X1229500Y735700D01*
G01X1222250Y735500D02*
X1217000D01*
X1216500Y735000D01*
G01X1250250Y647000D02*
X1243250Y654000D01*
X1241500D01*
G01X1236000Y660500D02*
X1238375Y658125D01*
X1243125D01*
X1250250Y651000D01*
G01Y671000D02*
X1239500D01*
G01X1250250Y679500D02*
X1241000Y680000D01*
X1240500Y679500D01*
G01X1250250Y675500D02*
X1246700D01*
G01X1243000Y691500D02*
X1250250D01*
G01X1235000Y687500D02*
X1250250D01*
G01Y683500D02*
X1245500D01*
G01X1234500Y695500D02*
X1250250D01*
G01Y699500D02*
X1243500D01*
G01X1250250Y703500D02*
X1235000D01*
G01X1250250Y707500D02*
X1243000D01*
G01X1235500Y711500D02*
X1250250D01*
G01X1248250Y715500D02*
X1243000D01*
G01X1236500Y737925D02*
Y735500D01*
X1234700Y733700D01*
G01X1300500Y739750D02*
X1295250D01*
X1293775Y738275D01*
X1257557D01*
X1254782Y735500D01*
X1242000D01*
X1241000Y734500D01*
G01X1249251Y528688D02*
X1251411D01*
X1255000Y532277D01*
Y609300D01*
G01X1251500Y531500D02*
Y536000D01*
G01X1257750Y651000D02*
X1258000D01*
X1259825Y652825D01*
X1262403D01*
X1265136Y650100D01*
X1266499D01*
X1267673Y648926D01*
Y636157D01*
X1252825Y621309D01*
Y543325D01*
X1251500Y542000D01*
Y536000D01*
G01X1264000Y613500D02*
Y618818D01*
X1274750Y629568D01*
Y637966D01*
X1274753Y637969D01*
Y639831D01*
X1274750Y639834D01*
Y640201D01*
X1272451Y642500D01*
G01X1255000Y609300D02*
Y618000D01*
X1257500Y620500D01*
G01X1257750Y657000D02*
Y656750D01*
X1259725Y654775D01*
X1265948D01*
X1269645Y651078D01*
Y632645D01*
X1257500Y620500D01*
G01X1253750Y641000D02*
X1254000Y641250D01*
X1260500D01*
G01X1253750Y647000D02*
X1257750D01*
G01X1253750Y657000D02*
X1257750D01*
G01X1253750Y651000D02*
X1257750D01*
G01X1253750Y661000D02*
X1257750D01*
G01D02*
X1258677Y661927D01*
Y661967D01*
X1259535Y662825D01*
X1263189D01*
X1263863Y663499D01*
X1269539D01*
X1273702Y667662D01*
G01X1312115Y672000D02*
X1311365Y672750D01*
X1306750D01*
X1302588Y676912D01*
X1286412D01*
X1285575Y676075D01*
X1279925D01*
X1278000Y678000D01*
X1263742D01*
X1263121Y678621D01*
G01X1253750Y675500D02*
X1254750Y674500D01*
X1259082D01*
X1260582Y673000D01*
X1263855D01*
X1265730Y671125D01*
X1269109D01*
X1270459Y672475D01*
X1276694D01*
X1277658Y671511D01*
X1297489D01*
X1300000Y669000D01*
G01X1253750Y679500D02*
X1256800Y676450D01*
X1260426D01*
X1261924Y674950D01*
X1264663D01*
X1266538Y673075D01*
X1268301D01*
X1269651Y674425D01*
X1277502D01*
X1278102Y673825D01*
X1287138D01*
X1288000Y674687D01*
G01X1253750Y667000D02*
X1257750Y667500D01*
G01D02*
Y667146D01*
X1260121Y664775D01*
X1262379D01*
X1266404Y668800D01*
X1269542D01*
X1271267Y670525D01*
X1275885D01*
G01X1253750Y691500D02*
X1260500D01*
X1267122Y684878D01*
X1267500D01*
G01X1253750Y683500D02*
X1261378D01*
X1264200Y680678D01*
X1279550D01*
X1279672Y680800D01*
X1283922D01*
X1284697Y681575D01*
X1284802D01*
X1285027Y681800D01*
X1288942D01*
X1290192Y680550D01*
X1291803D01*
X1292078Y680275D01*
X1293922D01*
X1294197Y680550D01*
X1304950D01*
X1310141Y675359D01*
X1311938D01*
X1315000Y672297D01*
Y663726D01*
X1318091Y660635D01*
Y641091D01*
X1293500Y616500D01*
Y607500D01*
G01X1253750Y687500D02*
X1260136D01*
X1265008Y682628D01*
X1278742D01*
X1278864Y682750D01*
X1283114D01*
X1283889Y683525D01*
X1283994D01*
X1284219Y683750D01*
X1289750D01*
X1291000Y682500D01*
X1293000D01*
G01X1273236Y687128D02*
X1269872D01*
X1261500Y695500D01*
X1253750D01*
G01X1273000Y701750D02*
X1256000D01*
X1253750Y699500D01*
G01X1273000Y705750D02*
X1270750Y703500D01*
X1253750D01*
G01X1273000Y719750D02*
X1272250D01*
X1271412Y718913D01*
X1271407D01*
X1269000Y716506D01*
Y712000D01*
X1264500Y707500D01*
X1253750D01*
G01X1273000Y724250D02*
X1267550Y718800D01*
Y716550D01*
X1263500Y712500D01*
X1254750D01*
X1253750Y711500D01*
G01X1255750Y715500D02*
Y719500D01*
G01X1251750D02*
Y715500D01*
G01X1255750D02*
X1251750D01*
G01X1255750Y719500D02*
Y724104D01*
X1265471Y733825D01*
X1295175D01*
X1296000Y733000D01*
G01X1279500Y150500D02*
X1292268D01*
X1355725Y87043D01*
Y67957D01*
X1342268Y54500D01*
X1339500D01*
X1339000Y54000D01*
G01X1275500Y647000D02*
X1277500Y645000D01*
Y625329D01*
X1274500Y622329D01*
Y606000D01*
G01X1278000Y657000D02*
X1279500Y655500D01*
Y624500D01*
X1277415Y622415D01*
Y604585D01*
X1278500Y603500D01*
G01X1272502Y638900D02*
X1272500Y638898D01*
Y630500D01*
X1267500Y625500D01*
G01X1273702Y667662D02*
Y648798D01*
X1275500Y647000D01*
G01X1275885Y670525D02*
Y659115D01*
X1278000Y657000D01*
G01X1267500Y684878D02*
X1277810D01*
X1277932Y685000D01*
X1282182D01*
X1282957Y685775D01*
X1283062D01*
X1283287Y686000D01*
X1307200D01*
X1311700Y681500D01*
G01X1277000Y687250D02*
X1281000D01*
G01D02*
X1281250D01*
X1282025Y688025D01*
X1282130D01*
X1283725Y689620D01*
Y689725D01*
X1285350Y691350D01*
X1297750D01*
G01X1277000Y687250D02*
X1276878Y687128D01*
X1273236D01*
G01X1273000Y701750D02*
X1277000D01*
G01X1281000D02*
X1312750D01*
X1315000Y704000D01*
G01X1277000Y701750D02*
X1281000D01*
G01X1273000Y705750D02*
X1277000D01*
G01X1281000D02*
X1281775Y706525D01*
X1289025D01*
X1294000Y711500D01*
Y712000D01*
G01X1277000Y705750D02*
X1281000D01*
G01X1277000Y719750D02*
X1273000D01*
G01X1281000D02*
X1281250Y720000D01*
X1294500D01*
G01X1277000Y719750D02*
X1281000D01*
G01X1277000Y724250D02*
X1273000D01*
G01X1281000D02*
X1277000D01*
G01X1301800Y727199D02*
X1294699D01*
X1291750Y724250D01*
X1281000D01*
G01X1324145Y668376D02*
Y633164D01*
X1306981Y616000D01*
X1305000D01*
X1301175Y612175D01*
Y594675D01*
X1294000Y587500D01*
G01X1288335Y594048D02*
X1288911D01*
X1293500Y598637D01*
Y607500D01*
G01X1293000Y682500D02*
X1307500D01*
X1310500Y679500D01*
X1313000D01*
X1313233Y679733D01*
X1314767D01*
X1318000Y676500D01*
Y663484D01*
X1320041Y661443D01*
Y639541D01*
X1296950Y616450D01*
Y599329D01*
X1288121Y590500D01*
X1287482D01*
G01X1320500Y671500D02*
Y668421D01*
X1321991Y666930D01*
Y633768D01*
X1310723Y622500D01*
X1307377D01*
X1299225Y614348D01*
Y598725D01*
X1293500Y593000D01*
G01X1285557Y585000D02*
Y615057D01*
X1314191Y643691D01*
Y659019D01*
X1304210Y669000D01*
X1300000D01*
G01X1288000Y674687D02*
X1289226Y673461D01*
X1302507D01*
X1316141Y659827D01*
Y642141D01*
X1289570Y615570D01*
Y597430D01*
G01X1294000Y628000D02*
X1302000Y636000D01*
Y650500D01*
X1304400Y652900D01*
Y661400D01*
G01X1297500Y665000D02*
X1296409Y663909D01*
Y651409D01*
X1294000Y649000D01*
Y639000D01*
X1290500Y635500D01*
G01X1282500Y669561D02*
Y669250D01*
X1286000Y665750D01*
Y653000D01*
X1286500Y652500D01*
G01X1297750Y691350D02*
X1307000D01*
X1307150Y691500D01*
G01X1310500Y737500D02*
Y728500D01*
X1294000Y712000D01*
G01X1307000Y729100D02*
Y729099D01*
X1297901Y720000D01*
X1294500D01*
G01X1296000Y733000D02*
X1300482D01*
X1300491Y732991D01*
G01X1308100Y748200D02*
X1307300Y749000D01*
X1288000D01*
X1286500Y747500D01*
G01X1336500Y270874D02*
X1322126D01*
X1299525Y293475D01*
Y322025D01*
X1303500Y326000D01*
Y326500D01*
X1306000Y329000D01*
G01X1339000Y274000D02*
X1338124Y274876D01*
X1322124D01*
X1301775Y295225D01*
Y319775D01*
X1307925Y325925D01*
Y332575D01*
X1306000Y334500D01*
G01X1304050Y296500D02*
X1305000D01*
X1321000Y280500D01*
X1338000D01*
X1342000Y276500D01*
X1350000D01*
G01X1307000Y732500D02*
Y731681D01*
X1302518Y727199D01*
X1301800D01*
G01X1305000Y739750D02*
X1300500D01*
G01X1324145Y668376D02*
X1324000Y668521D01*
Y675000D01*
X1323500Y675500D01*
Y702000D01*
G01X1320500Y671500D02*
Y672418D01*
X1321550Y673468D01*
Y703050D01*
X1322000Y703500D01*
Y705500D01*
G01X1319000Y708000D02*
X1315000Y704000D01*
G01X1350000Y276500D02*
X1350084Y276584D01*
Y280918D01*
G01X1358584D02*
X1354082D01*
X1354000Y281000D01*
G01X1350084Y280918D02*
X1353918D01*
X1354000Y281000D01*
G01X1380300Y284450D02*
Y287300D01*
X1381500Y288500D01*
G01X1376300Y289000D02*
Y284450D01*
G01X1380300Y280950D02*
X1384300D01*
G01X1372300D02*
X1376300D01*
G01X1379500Y274500D02*
X1377000Y277000D01*
G01X1376300Y280950D02*
Y277700D01*
X1377000Y277000D01*
G01X1376000Y292000D02*
X1376300Y291700D01*
Y289000D01*
G01X1384500Y271000D02*
Y274500D01*
G01X1384300Y280950D02*
X1384500Y280750D01*
Y274500D01*
G01X1381500Y288500D02*
Y292000D01*
G01X1384500Y331500D02*
Y327500D01*
G01D02*
Y322750D01*
M02*
